# Altium SchDoc records: 03-POWER.SchDoc
|HEADER=Protel for Windows - Schematic Capture Binary File Version 5.0|Weight=4062|MinorVersion=9
|RECORD=31|FontIdCount=9|Size1=10|FontName1=Times New Roman|Size2=10|Rotation2=90|FontName2=Times New Roman|Size3=10|Underline3=T|FontName3=Times New Roman|Size4=8|FontName4=Arial|Size5=10|FontName5=Arial|Size6=12|Underline6=T|FontName6=Arial|Size7=11|FontName7=Arial|Size8=24|FontName8=Times New Roman|Size9=12|FontName9=Arial|UseMBCS=T|IsBOC=T|HotSpotGridOn=T|HotSpotGridSize=2|SheetStyle=12|SystemFont=5|BorderOn=T|SheetNumberSpaceSize=12|AreaColor=16317695|SnapGridOn=T|SnapGridSize=5|VisibleGridOn=T|VisibleGridSize=10|CustomX=2338|CustomX_Frac=58268|CustomY=1653|CustomY_Frac=54331|CustomXZones=8|CustomYZones=6|CustomMarginWidth=19|CustomMarginWidth_Frac=80000|ShowTemplateGraphics=T|TemplateFileName=C:\Users\<user>\Documents\Altium\AD20\Templates\Timecard.SchDot|Display_Unit=0
|RECORD=39|IsNotAccesible=T|OwnerPartId=-1|FileName=C:\Users\<user>\Documents\Altium\AD20\Templates\Timecard.SchDot
|RECORD=4|OwnerIndex=1|OwnerPartId=-1|Location.X=1594|Location.Y=39|Color=8388608|FontID=6|Text=timingcard.com|URL=http://timingcard.com
|RECORD=6|OwnerIndex=1|IndexInSheet=1|OwnerPartId=-1|LocationCount=2|X1=1680|Y1=35|X2=1576|Y2=35
|RECORD=4|OwnerIndex=1|IndexInSheet=2|OwnerPartId=-1|Location.X=1615|Location.Y=27|Justification=4|Color=16711680|FontID=7|Text==SheetNumber
|RECORD=4|OwnerIndex=1|IndexInSheet=3|OwnerPartId=-1|Location.X=1581|Location.X_Frac=42446|Location.Y=29|Location.Y_Frac=96838|Justification=3|FontID=4|Text=SHEET
|RECORD=4|OwnerIndex=1|IndexInSheet=4|OwnerPartId=-1|Location.X=1639|Location.X_Frac=42446|Location.Y=29|Location.Y_Frac=96838|Justification=3|FontID=4|Text=OF
|RECORD=6|OwnerIndex=1|IndexInSheet=5|OwnerPartId=-1|LineWidth=1|LocationCount=2|X1=1679|X1_Frac=42446|Y1=117|Y1_Frac=96838|X2=1576|Y2=118
|RECORD=4|OwnerIndex=1|IndexInSheet=6|OwnerPartId=-1|Location.X=1659|Location.Y=27|Justification=4|Color=16711680|FontID=7|Text==SheetTotal
|RECORD=30|OwnerIndex=1|IndexInSheet=7|OwnerPartId=-1|Location.X=1578|Location.Y=65|Corner.X=1673|Corner.X_Frac=88801|Corner.Y=115|KeepAspect=T|FileName=C:\Users\<user>\Desktop\Timecard Logo\TIMECARD.jpg
|RECORD=6|OwnerIndex=1|IndexInSheet=8|OwnerPartId=-1|LineWidth=1|LocationCount=2|X1=1576|X1_Frac=3162|Y1=117|Y1_Frac=42446|X2=1576|Y2=21
|RECORD=6|OwnerIndex=1|IndexInSheet=9|OwnerPartId=-1|LocationCount=2|X1=1680|Y1=51|X2=1576|Y2=51
|RECORD=4|OwnerIndex=1|IndexInSheet=10|OwnerPartId=-1|Location.X=1581|Location.X_Frac=42446|Location.Y=56|Location.Y_Frac=96838|Justification=3|FontID=4|Text=REV
|RECORD=4|OwnerIndex=1|IndexInSheet=11|OwnerPartId=-1|Location.X=1619|Location.Y=57|Justification=3|FontID=4|Text=DATE
|RECORD=6|OwnerIndex=1|IndexInSheet=12|OwnerPartId=-1|LocationCount=2|X1=1680|Y1=65|X2=1576|Y2=65
|RECORD=4|OwnerIndex=1|IndexInSheet=13|OwnerPartId=-1|Location.X=1605|Location.Y=58|Justification=4|Color=16711680|FontID=7|Text==ProjectRevision
|RECORD=4|OwnerIndex=1|IndexInSheet=14|OwnerPartId=-1|Location.X=1659|Location.Y=58|Justification=4|Color=16711680|FontID=7|Text==ProjectDate
|RECORD=41|IndexInSheet=1|OwnerPartId=-1|Location.X=21474|Location.X_Frac=83647|Location.Y=21464|Location.Y_Frac=83647|Color=8388608|FontID=1|IsHidden=T|Text=01910|Name=Customer
|RECORD=41|IndexInSheet=2|OwnerPartId=-1|Location.X=1000|Location.Y=10|Color=8388608|FontID=1|IsHidden=T|Text=*|Name=DocStatus
|RECORD=17|IndexInSheet=3|OwnerPartId=-1|ShowNetName=T|Location.X=602|Location.Y=937|Orientation=1|Color=128|FontID=1|Text=+12V
|RECORD=17|IndexInSheet=4|OwnerPartId=-1|Style=4|ShowNetName=T|Location.X=600|Location.Y=805|Orientation=3|Color=128|FontID=1|Text=GND
|RECORD=17|IndexInSheet=5|OwnerPartId=-1|ShowNetName=T|Location.X=85|Location.Y=630|Orientation=1|Color=128|FontID=1|Text=+3.3V
|RECORD=17|IndexInSheet=6|OwnerPartId=-1|Style=4|ShowNetName=T|Location.X=85|Location.Y=450|Orientation=3|Color=128|FontID=1|Text=GND
|RECORD=1|LibReference=CAP_0805_10UF_25V|ComponentDescription=CAP, CER, 10.UF, 25V, 10%, X5R, 0805|PartCount=2|DisplayModeCount=1|IndexInSheet=7|OwnerPartId=-1|Location.X=532|Location.Y=827|CurrentPartId=1|LibraryPath=*|SourceLibraryName=Capacitors.IntLib|TargetFileName=*|AreaColor=11599871|Color=128|PartIDLocked=F|DesignItemId=CAP_0805_10UF_25V|AllPinCount=2
|RECORD=41|OwnerIndex=23|OwnerPartId=-1|Location.X=532|Location.Y=827|Color=8388608|FontID=9|IsHidden=T|Text=TAIYO YUDEN|Name=MFG NAME
|RECORD=41|OwnerIndex=23|IndexInSheet=1|OwnerPartId=-1|Location.X=532|Location.Y=827|Color=8388608|FontID=9|IsHidden=T|Text=TMK212BBJ106KG-T|Name=MFG PART NUM
|RECORD=41|OwnerIndex=23|IndexInSheet=2|OwnerPartId=-1|Location.X=532|Location.Y=827|Color=8388608|FontID=9|IsHidden=T|Text=10/23/2013|Name=MODIFY DATE
|RECORD=41|OwnerIndex=23|IndexInSheet=3|OwnerPartId=-1|Location.X=532|Location.Y=827|Color=8388608|FontID=9|IsHidden=T|Text=CAP, CER|Name=CATEGORY
|RECORD=41|OwnerIndex=23|IndexInSheet=4|OwnerPartId=-1|Location.X=530|Location.Y=839|Location.Y_Frac=50000|Color=8388608|FontID=9|IsHidden=T|Text=4/11/2006 3:37:28 PM|Name=Date
|RECORD=41|OwnerIndex=23|IndexInSheet=5|OwnerPartId=-1|Location.X=538|Location.Y=901|Location.Y_Frac=48252|Color=8388608|FontID=9|IsHidden=T|Text=*|Name=SHEETPART
|RECORD=41|OwnerIndex=23|IndexInSheet=6|OwnerPartId=-1|Location.X=538|Location.Y=901|Location.Y_Frac=48252|Color=8388608|FontID=9|IsHidden=T|Text=10%|Name=P1
|RECORD=41|OwnerIndex=23|IndexInSheet=7|OwnerPartId=-1|Location.X=538|Location.Y=901|Location.Y_Frac=48252|Color=8388608|FontID=9|IsHidden=T|Text=85C|Name=MAXTEMP
|RECORD=41|OwnerIndex=23|IndexInSheet=8|OwnerPartId=-1|Location.X=538|Location.Y=901|Location.Y_Frac=48252|Color=8388608|FontID=9|IsHidden=T|Text=-55C|Name=MINTEMP
|RECORD=41|OwnerIndex=23|IndexInSheet=9|OwnerPartId=-1|Location.X=538|Location.Y=901|Location.Y_Frac=48252|Color=8388608|FontID=9|IsHidden=T|Name=OTHER
|RECORD=41|OwnerIndex=23|IndexInSheet=10|OwnerPartId=-1|Location.X=538|Location.Y=901|Location.Y_Frac=48252|Color=8388608|FontID=9|IsHidden=T|Text=25V|Name=P2
|RECORD=41|OwnerIndex=23|IndexInSheet=11|OwnerPartId=-1|Location.X=538|Location.Y=901|Location.Y_Frac=48252|Color=8388608|FontID=9|IsHidden=T|Text=X5R|Name=P3
|RECORD=41|OwnerIndex=23|IndexInSheet=12|OwnerPartId=-1|Location.X=538|Location.Y=901|Location.Y_Frac=48252|Color=8388608|FontID=9|IsHidden=T|Text=0805|Name=Size
|RECORD=41|OwnerIndex=23|IndexInSheet=13|OwnerPartId=-1|Location.X=538|Location.Y=901|Location.Y_Frac=48252|Color=8388608|FontID=9|IsHidden=T|Name=SUB
|RECORD=41|OwnerIndex=23|IndexInSheet=14|OwnerPartId=-1|Location.X=538|Location.Y=901|Location.Y_Frac=48252|Color=8388608|FontID=1|IsHidden=T|Text=CAP, CER, 10.UF, 10V, 10%, X5R, 0805|Name=DESC
|RECORD=41|OwnerIndex=23|IndexInSheet=15|OwnerPartId=-1|Location.X=538|Location.Y=900|Location.Y_Frac=98252|Color=8388608|FontID=1|IsHidden=T|Text=MOUSER|Name=Supplier 1|ReadOnlyState=1
|RECORD=41|OwnerIndex=23|IndexInSheet=16|OwnerPartId=-1|Location.X=538|Location.Y=900|Location.Y_Frac=98252|Color=8388608|FontID=1|IsHidden=T|Text=963-TMK212BBJ106KG-T|Name=Supplier Part Number 1|ReadOnlyState=1
|RECORD=41|OwnerIndex=23|IndexInSheet=17|OwnerPartId=-1|Location.X=562|Location.Y=857|Color=8388608|FontID=9|Text=10uF|Name=VALUE
|RECORD=2|OwnerIndex=23|OwnerPartId=1|FormalType=1|Electrical=4|PinConglomerate=35|PinLength=10|Location.X=552|Location.Y=857|Name=2|Designator=2|SwapIdPin=2|SwapIDPart=1|PinPropagationDelay=0.000000E+000
|RECORD=2|OwnerIndex=23|OwnerPartId=1|FormalType=1|Electrical=4|PinConglomerate=33|PinLength=10|Location.X=552|Location.Y=867|Name=1|Designator=1|SwapIdPin=1|SwapIDPart=1|PinPropagationDelay=0.000000E+000
|RECORD=13|OwnerIndex=23|IsNotAccesible=T|IndexInSheet=20|OwnerPartId=1|Location.X=552|Location.Y=859|Location.Y_Frac=50000|Corner.X=552|Corner.Y=857|LineWidth=1|Color=16711680
|RECORD=13|OwnerIndex=23|IsNotAccesible=T|IndexInSheet=21|OwnerPartId=1|Location.X=552|Location.Y=867|Corner.X=552|Corner.Y=864|Corner.Y_Frac=50000|LineWidth=1|Color=16711680
|RECORD=13|OwnerIndex=23|IsNotAccesible=T|IndexInSheet=22|OwnerPartId=1|Location.X=557|Location.Y=859|Location.Y_Frac=50000|Corner.X=547|Corner.Y=859|Corner.Y_Frac=50000|LineWidth=1|Color=16711680
|RECORD=13|OwnerIndex=23|IsNotAccesible=T|IndexInSheet=23|OwnerPartId=1|Location.X=557|Location.Y=864|Location.Y_Frac=50000|Corner.X=547|Corner.Y=864|Corner.Y_Frac=50000|LineWidth=1|Color=16711680
|RECORD=41|OwnerIndex=23|IndexInSheet=24|OwnerPartId=-1|Location.X=538|Location.Y=900|Location.Y_Frac=98951|Color=8388608|FontID=1|IsHidden=T|Text=<VALENTIUM>|Name=VALENTIUM PART NUM
|RECORD=34|OwnerIndex=23|IndexInSheet=-1|OwnerPartId=-1|Location.X=562|Location.Y=867|Color=8388608|FontID=1|Text=C1|Name=Designator|ReadOnlyState=1
|RECORD=41|OwnerIndex=23|IndexInSheet=-1|OwnerPartId=-1|Location.X=559|Location.X_Frac=50000|Location.Y=822|Color=8388608|FontID=1|IsHidden=T|Text=CAP_0805_10UF_25V|Name=Comment
|RECORD=44|OwnerIndex=23
|RECORD=45|OwnerIndex=53|IndexInSheet=-1|Description=Chip Capacitor, 0805, 2-Leads, Body 2.00x1.25mm, IPC Medium Density|UseComponentLibrary=T|ModelName=CAPC2012X14N|ModelType=PCBLIB|DatafileCount=1|ModelDatafileEntity0=CAPC2012X14N|ModelDatafileKind0=PCBLib|IsCurrent=T|DatalinksLocked=T|DatabaseDatalinksLocked=T|IntegratedModel=T|DatabaseModel=T
|RECORD=46|OwnerIndex=54
|RECORD=48|OwnerIndex=54
|RECORD=1|LibReference=FUSE_0603_2.00A|ComponentDescription=FUSE SLOW 5.00A 32V M 0603|PartCount=2|DisplayModeCount=1|IndexInSheet=8|OwnerPartId=-1|Location.X=320|Location.Y=915|CurrentPartId=1|LibraryPath=*|SourceLibraryName=Passives.IntLib|TargetFileName=*|AreaColor=11599871|Color=128|PartIDLocked=F|DesignItemId=FUSE_0603_2.00A|AllPinCount=2
|RECORD=41|OwnerIndex=57|OwnerPartId=-1|Location.X=320|Location.Y=880|Color=8388608|FontID=9|Text=SF-0603S500-2|Name=MFG PART NUM
|RECORD=41|OwnerIndex=57|IndexInSheet=1|OwnerPartId=-1|Location.X=320|Location.Y=915|Color=8388608|FontID=9|IsHidden=T|Text=9/4/2013|Name=MODIFY DATE
|RECORD=41|OwnerIndex=57|IndexInSheet=2|OwnerPartId=-1|Location.X=320|Location.Y=915|Color=8388608|FontID=9|IsHidden=T|Text=BOURNS|Name=MFG NAME
|RECORD=41|OwnerIndex=57|IndexInSheet=3|OwnerPartId=-1|Location.X=320|Location.Y=915|Color=8388608|FontID=9|IsHidden=T|Text=FUSE|Name=CATEGORY
|RECORD=41|OwnerIndex=57|IndexInSheet=4|OwnerPartId=-1|Location.X=318|Location.Y=932|Color=8388608|FontID=9|IsHidden=T|Text=20 OCT 15|Name=DATE
|RECORD=41|OwnerIndex=57|IndexInSheet=5|OwnerPartId=-1|Location.X=318|Location.Y=932|Color=8388608|FontID=9|IsHidden=T|Text=105C|Name=MAXTEMP
|RECORD=41|OwnerIndex=57|IndexInSheet=6|OwnerPartId=-1|Location.X=318|Location.Y=932|Color=8388608|FontID=9|IsHidden=T|Text=-40C|Name=MINTEMP
|RECORD=41|OwnerIndex=57|IndexInSheet=7|OwnerPartId=-1|Location.X=318|Location.Y=932|Color=8388608|FontID=9|IsHidden=T|Text=UL E141069|Name=OTHER
|RECORD=41|OwnerIndex=57|IndexInSheet=8|OwnerPartId=-1|Location.X=318|Location.Y=932|Color=8388608|FontID=9|IsHidden=T|Text=SLOW BLO|Name=P1
|RECORD=41|OwnerIndex=57|IndexInSheet=9|OwnerPartId=-1|Location.X=318|Location.Y=932|Color=8388608|FontID=9|IsHidden=T|Text=32V|Name=P2
|RECORD=41|OwnerIndex=57|IndexInSheet=10|OwnerPartId=-1|Location.X=318|Location.Y=932|Color=8388608|FontID=9|IsHidden=T|Text=M|Name=P3
|RECORD=41|OwnerIndex=57|IndexInSheet=11|OwnerPartId=-1|Location.X=318|Location.Y=932|Color=8388608|FontID=9|IsHidden=T|Text=0603|Name=SIZE
|RECORD=41|OwnerIndex=57|IndexInSheet=12|OwnerPartId=-1|Location.X=318|Location.Y=932|Color=8388608|FontID=9|IsHidden=T|Name=SUB
|RECORD=41|OwnerIndex=57|IndexInSheet=13|OwnerPartId=-1|Location.X=318|Location.Y=888|Color=8388608|FontID=1|IsHidden=T|Text=*|Name=SHEETPART
|RECORD=41|OwnerIndex=57|IndexInSheet=14|OwnerPartId=-1|Location.X=318|Location.Y=936|Color=8388608|FontID=1|IsHidden=T|Text=FUSE SLOW 1.25A 32V M 0603|Name=DESC
|RECORD=41|OwnerIndex=57|IndexInSheet=15|OwnerPartId=-1|Location.X=318|Location.Y=936|Color=8388608|FontID=1|IsHidden=T|Text=<VALENTIUM>|Name=VALENTIUM PART NUM
|RECORD=2|OwnerIndex=57|OwnerPartId=1|FormalType=1|Electrical=4|PinConglomerate=34|PinLength=20|Location.X=340|Location.Y=915|Name=1|Designator=1|SwapIdPin=1|SwapIDPart=1|PinPropagationDelay=0.000000E+000
|RECORD=2|OwnerIndex=57|OwnerPartId=1|FormalType=1|Electrical=4|PinConglomerate=32|PinLength=20|Location.X=360|Location.Y=915|Name=2|Designator=2|SwapIdPin=2|SwapIDPart=1|PinPropagationDelay=0.000000E+000
|RECORD=12|OwnerIndex=57|IsNotAccesible=T|IndexInSheet=18|OwnerPartId=1|Location.X=355|Location.Y=915|Radius=5|LineWidth=1|StartAngle=180.000|Color=16711680
|RECORD=12|OwnerIndex=57|IsNotAccesible=T|IndexInSheet=19|OwnerPartId=1|Location.X=345|Location.Y=915|Radius=5|LineWidth=1|EndAngle=180.000|Color=16711680
|RECORD=41|OwnerIndex=57|IndexInSheet=20|OwnerPartId=-1|Location.X=338|Location.Y=893|Color=8388608|FontID=9|Text=5.00A|Name=VALUE
|RECORD=8|OwnerIndex=57|IsNotAccesible=T|IndexInSheet=21|OwnerPartId=1|Location.X=340|Location.Y=915|Radius=2|SecondaryRadius=2|LineWidth=1|Color=16711680|AreaColor=16777215|IsSolid=T
|RECORD=8|OwnerIndex=57|IsNotAccesible=T|IndexInSheet=22|OwnerPartId=1|Location.X=360|Location.Y=915|Radius=2|SecondaryRadius=2|LineWidth=1|Color=16711680|AreaColor=16777215|IsSolid=T
|RECORD=41|OwnerIndex=57|IndexInSheet=23|OwnerPartId=-1|Location.X=318|Location.Y=930|Color=8388608|FontID=1|IsHidden=T|Text=Digi-Key|Name=Supplier 1|ReadOnlyState=3
|RECORD=41|OwnerIndex=57|IndexInSheet=24|OwnerPartId=-1|Location.X=318|Location.Y=930|Color=8388608|FontID=1|Text=SF-0603S500-2CT-ND|Name=Supplier Part Number 1|ReadOnlyState=3
|RECORD=34|OwnerIndex=57|IndexInSheet=-1|OwnerPartId=-1|Location.X=338|Location.Y=920|Color=8388608|FontID=1|Text=F1|Name=Designator|ReadOnlyState=1
|RECORD=41|OwnerIndex=57|IndexInSheet=-1|OwnerPartId=-1|Location.X=360|Location.Y=892|Location.Y_Frac=10000|Color=8388608|FontID=1|IsHidden=T|Text=FUSE_0603_5.00A|Name=Comment
|RECORD=44|OwnerIndex=57
|RECORD=45|OwnerIndex=87|IndexInSheet=-1|Description=Chip Fuse, 0603, 2-Leads, Body 1.60x0.81mm, IPC Medium Density|UseComponentLibrary=T|ModelName=FUSM1608X60N|ModelType=PCBLIB|DatafileCount=1|ModelDatafileEntity0=FUSM1608X60N|ModelDatafileKind0=PCBLib|IsCurrent=T|DatalinksLocked=T|DatabaseDatalinksLocked=T|IntegratedModel=T|DatabaseModel=T
|RECORD=46|OwnerIndex=88
|RECORD=48|OwnerIndex=88
|RECORD=1|LibReference=CAP|ComponentDescription=C0603X104K5RACAUTO|PartCount=2|DisplayModeCount=2|IndexInSheet=9|OwnerPartId=-1|Location.X=592|Location.Y=857|Orientation=1|CurrentPartId=1|SourceLibraryName=Altium Content Vault|TargetFileName=*|AreaColor=11599871|Color=128|PartIDLocked=F|DesignItemId=CMP-2006-00003-1|AllPinCount=2
|RECORD=2|OwnerIndex=91|OwnerPartId=1|OwnerPartDisplayMode=1|FormalType=1|Electrical=4|PinConglomerate=35|PinLength=10|Location.X=602|Location.Y=857|Name=1|Designator=1|PinPropagationDelay=0.000000E+000
|RECORD=2|OwnerIndex=91|OwnerPartId=1|OwnerPartDisplayMode=1|FormalType=1|Electrical=4|PinConglomerate=33|PinLength=10|Location.X=602|Location.Y=867|Name=2|Designator=2|PinPropagationDelay=0.000000E+000
|RECORD=13|OwnerIndex=91|IsNotAccesible=T|IndexInSheet=2|OwnerPartId=1|OwnerPartDisplayMode=1|Location.X=610|Location.Y=857|Corner.X=594|Corner.Y=857|LineWidth=1|Color=16711680
|RECORD=13|OwnerIndex=91|IsNotAccesible=T|IndexInSheet=3|OwnerPartId=1|OwnerPartDisplayMode=1|Location.X=602|Location.Y=861|Corner.X=602|Corner.Y=867|LineWidth=1|Color=16711680
|RECORD=12|OwnerIndex=91|IsNotAccesible=T|IndexInSheet=4|OwnerPartId=1|OwnerPartDisplayMode=1|Location.X=602|Location.Y=877|Radius=16|LineWidth=1|StartAngle=241.000|EndAngle=270.000|Color=16711680
|RECORD=12|OwnerIndex=91|IsNotAccesible=T|IndexInSheet=5|OwnerPartId=1|OwnerPartDisplayMode=1|Location.X=602|Location.Y=877|Radius=16|LineWidth=1|StartAngle=270.000|EndAngle=299.000|Color=16711680
|RECORD=2|OwnerIndex=91|OwnerPartId=1|FormalType=1|Electrical=4|PinConglomerate=35|PinLength=10|Location.X=602|Location.Y=857|Name=1|Designator=1|PinPropagationDelay=0.000000E+000
|RECORD=2|OwnerIndex=91|OwnerPartId=1|FormalType=1|Electrical=4|PinConglomerate=33|PinLength=10|Location.X=602|Location.Y=867|Name=2|Designator=2|PinPropagationDelay=0.000000E+000
|RECORD=13|OwnerIndex=91|IsNotAccesible=T|IndexInSheet=8|OwnerPartId=1|Location.X=594|Location.Y=864|Corner.X=610|Corner.Y=864|LineWidth=1|Color=16711680
|RECORD=13|OwnerIndex=91|IsNotAccesible=T|IndexInSheet=9|OwnerPartId=1|Location.X=610|Location.Y=860|Corner.X=594|Corner.Y=860|LineWidth=1|Color=16711680
|RECORD=6|OwnerIndex=91|IsNotAccesible=T|IndexInSheet=10|OwnerPartId=1|LineWidth=1|Color=16711680|LocationCount=2|X1=602|Y1=857|X2=602|Y2=860
|RECORD=6|OwnerIndex=91|IsNotAccesible=T|IndexInSheet=11|OwnerPartId=1|LineWidth=1|Color=16711680|LocationCount=2|X1=602|Y1=867|X2=602|Y2=864
|RECORD=41|OwnerIndex=91|IndexInSheet=12|OwnerPartId=-1|Location.X=593|Location.Y=879|Color=8388608|FontID=1|IsHidden=T|Text=Kemet|Name=Manufacturer
|RECORD=41|OwnerIndex=91|IndexInSheet=13|OwnerPartId=-1|Location.X=593|Location.Y=879|Color=8388608|FontID=1|IsHidden=T|Text=C0603X104K5RACAUTO|Name=Part Number
|RECORD=34|OwnerIndex=91|IndexInSheet=-1|OwnerPartId=-1|Location.X=611|Location.Y=858|Color=8388608|FontID=1|Text=C2|Name=Designator|ReadOnlyState=1
|RECORD=41|OwnerIndex=91|IndexInSheet=-1|OwnerPartId=-1|Location.X=611|Location.Y=848|Color=8388608|FontID=1|Text=0.1uF|Name=Comment
|RECORD=44|OwnerIndex=91
|RECORD=45|OwnerIndex=112|IndexInSheet=-1|Description=Chip Capacitor, 2-Leads, Body 1.60x0.80mm, IPC Low Density|UseComponentLibrary=T|ModelName=CAPC1608X87X45ML20T05|ModelType=PCBLIB|DatafileCount=1|ModelDatafileEntity0=CAPC1608X87X45ML20T05|ModelDatafileKind0=PCBLib|IsCurrent=T|DatalinksLocked=T|DatabaseDatalinksLocked=T
|RECORD=46|OwnerIndex=113
|RECORD=48|OwnerIndex=113
|RECORD=41|OwnerIndex=115|IndexInSheet=-1|OwnerPartId=-1|Color=8388608|FontID=1|Text=2D|Name=Available Preview Images
|RECORD=45|OwnerIndex=112|IndexInSheet=-1|Description=Chip Capacitor, 2-Leads, Body 1.60x0.80mm, IPC High Density|UseComponentLibrary=T|ModelName=CAPC1608X87X45LL20T05|ModelType=PCBLIB|DatafileCount=1|ModelDatafileEntity0=CAPC1608X87X45LL20T05|ModelDatafileKind0=PCBLib|DatalinksLocked=T|DatabaseDatalinksLocked=T
|RECORD=46|OwnerIndex=117
|RECORD=48|OwnerIndex=117
|RECORD=41|OwnerIndex=119|IndexInSheet=-1|OwnerPartId=-1|Color=8388608|FontID=1|Text=2D|Name=Available Preview Images
|RECORD=45|OwnerIndex=112|IndexInSheet=-1|Description=Chip Capacitor, 2-Leads, Body 1.60x0.80mm, IPC Medium Density|UseComponentLibrary=T|ModelName=CAPC1608X87X45NL20T05|ModelType=PCBLIB|DatafileCount=1|ModelDatafileEntity0=CAPC1608X87X45NL20T05|ModelDatafileKind0=PCBLib|DatalinksLocked=T|DatabaseDatalinksLocked=T
|RECORD=46|OwnerIndex=121
|RECORD=48|OwnerIndex=121
|RECORD=41|OwnerIndex=123|IndexInSheet=-1|OwnerPartId=-1|Color=8388608|FontID=1|Text=2D|Name=Available Preview Images
|RECORD=41|IndexInSheet=10|OwnerPartId=-1|Color=8388608|FontID=1|IsHidden=T|Name=ConfigurationParameters|ReadOnlyState=1
|RECORD=41|IndexInSheet=11|OwnerPartId=-1|Color=8388608|FontID=1|IsHidden=T|Name=ConfiguratorName|ReadOnlyState=1
|RECORD=41|IndexInSheet=12|OwnerPartId=-1|Color=8388608|FontID=1|IsHidden=T|Name=VersionControl_RevNumber|ReadOnlyState=1
|RECORD=41|IndexInSheet=13|OwnerPartId=-1|Color=8388608|FontID=1|IsHidden=T|Name=IsUserConfigurable|ReadOnlyState=1
|RECORD=41|IndexInSheet=14|OwnerPartId=-1|Color=8388608|FontID=1|IsHidden=T|Name=VersionControl_ProjFolderRevNumber|ReadOnlyState=1
|RECORD=41|IndexInSheet=15|OwnerPartId=-1|Color=8388608|FontID=1|IsHidden=T|Text=|Name=SPICEModelCache|ReadOnlyState=1
|RECORD=41|IndexInSheet=16|OwnerPartId=-1|Color=8388608|FontID=1|IsHidden=T|Text=*|Name=CurrentTime|ReadOnlyState=1
|RECORD=41|IndexInSheet=17|OwnerPartId=-1|Color=8388608|FontID=1|IsHidden=T|Text=*|Name=CurrentDate|ReadOnlyState=1
|RECORD=41|IndexInSheet=18|OwnerPartId=-1|Color=8388608|FontID=1|IsHidden=T|Text=*|Name=Time|ReadOnlyState=1
|RECORD=41|IndexInSheet=19|OwnerPartId=-1|Color=8388608|FontID=1|IsHidden=T|Text=*|Name=Date|ReadOnlyState=1
|RECORD=41|IndexInSheet=20|OwnerPartId=-1|Color=8388608|FontID=1|IsHidden=T|Text=*|Name=DocumentFullPathAndName|ReadOnlyState=1
|RECORD=41|IndexInSheet=21|OwnerPartId=-1|Color=8388608|FontID=1|IsHidden=T|Text=*|Name=DocumentName|ReadOnlyState=1
|RECORD=41|IndexInSheet=22|OwnerPartId=-1|Color=8388608|FontID=1|IsHidden=T|Text=*|Name=ModifiedDate|ReadOnlyState=1
|RECORD=41|IndexInSheet=23|OwnerPartId=-1|Color=8388608|FontID=1|IsHidden=T|Text=*|Name=ApprovedBy|ReadOnlyState=1
|RECORD=41|IndexInSheet=24|OwnerPartId=-1|Color=8388608|FontID=1|IsHidden=T|Text=*|Name=CheckedBy|ReadOnlyState=1
|RECORD=41|IndexInSheet=25|OwnerPartId=-1|Color=8388608|FontID=1|IsHidden=T|Text=*|Name=Author|ReadOnlyState=1
|RECORD=41|IndexInSheet=26|OwnerPartId=-1|Color=8388608|FontID=1|IsHidden=T|Text=*|Name=CompanyName|ReadOnlyState=1
|RECORD=41|IndexInSheet=27|OwnerPartId=-1|Color=8388608|FontID=1|IsHidden=T|Text=*|Name=DrawnBy|ReadOnlyState=1
|RECORD=41|IndexInSheet=28|OwnerPartId=-1|Color=8388608|FontID=1|IsHidden=T|Text=*|Name=Engineer|ReadOnlyState=1
|RECORD=41|IndexInSheet=29|OwnerPartId=-1|Color=8388608|FontID=1|IsHidden=T|Text=*|Name=Organization|ReadOnlyState=1
|RECORD=41|IndexInSheet=30|OwnerPartId=-1|Color=8388608|FontID=1|IsHidden=T|Text=*|Name=Address1|ReadOnlyState=1
|RECORD=41|IndexInSheet=31|OwnerPartId=-1|Color=8388608|FontID=1|IsHidden=T|Text=*|Name=Address2|ReadOnlyState=1
|RECORD=41|IndexInSheet=32|OwnerPartId=-1|Color=8388608|FontID=1|IsHidden=T|Text=*|Name=Address3|ReadOnlyState=1
|RECORD=41|IndexInSheet=33|OwnerPartId=-1|Color=8388608|FontID=1|IsHidden=T|Text=*|Name=Address4|ReadOnlyState=1
|RECORD=41|IndexInSheet=34|OwnerPartId=-1|Color=8388608|FontID=1|IsHidden=T|Text=*|Name=Title|ReadOnlyState=1
|RECORD=41|IndexInSheet=35|OwnerPartId=-1|Color=8388608|FontID=1|IsHidden=T|Text=*|Name=DocumentNumber|ReadOnlyState=1
|RECORD=41|IndexInSheet=36|OwnerPartId=-1|Color=8388608|FontID=1|IsHidden=T|Text=*|Name=Revision|ReadOnlyState=1
|RECORD=41|IndexInSheet=37|OwnerPartId=-1|Color=8388608|FontID=1|IsHidden=T|Text=*|Name=SheetNumber|ReadOnlyState=1
|RECORD=41|IndexInSheet=38|OwnerPartId=-1|Color=8388608|FontID=1|IsHidden=T|Text=*|Name=SheetTotal|ReadOnlyState=1
|RECORD=41|IndexInSheet=39|OwnerPartId=-1|Color=8388608|FontID=1|IsHidden=T|Text=*|Name=Rule|ReadOnlyState=1
|RECORD=41|IndexInSheet=40|OwnerPartId=-1|Color=8388608|FontID=1|IsHidden=T|Text=*|Name=ImagePath|ReadOnlyState=1
|RECORD=41|IndexInSheet=41|OwnerPartId=-1|Color=8388608|FontID=1|IsHidden=T|Text=*|Name=ProjectName|ReadOnlyState=1
|RECORD=41|IndexInSheet=42|OwnerPartId=-1|Color=8388608|FontID=1|IsHidden=T|Text=*|Name=Application_BuildNumber|ReadOnlyState=1
|RECORD=17|IndexInSheet=43|OwnerPartId=-1|Style=4|ShowNetName=T|Location.X=170|Location.Y=900|Orientation=3|Color=128|FontID=1|Text=GND
|RECORD=17|IndexInSheet=44|OwnerPartId=-1|ShowNetName=T|Location.X=82|Location.Y=839|Orientation=1|Color=128|FontID=1|Text=+12V_PCIE
|RECORD=1|LibReference=RES|PartCount=2|DisplayModeCount=2|IndexInSheet=45|OwnerPartId=-1|Location.X=340|Location.Y=840|CurrentPartId=1|SourceLibraryName=Altium Content Vault|TargetFileName=*|AreaColor=11599871|Color=128|PartIDLocked=F|DesignItemId=CMP-2003-04873-1|AllPinCount=2|ComponentKindVersion2=5
|RECORD=2|OwnerIndex=160|OwnerPartId=1|OwnerPartDisplayMode=1|FormalType=1|Electrical=4|PinConglomerate=32|PinLength=10|Location.X=360|Location.Y=830|Name=2|Designator=2|PinPropagationDelay=0.000000E+000
|RECORD=2|OwnerIndex=160|OwnerPartId=1|OwnerPartDisplayMode=1|FormalType=1|Electrical=4|PinConglomerate=34|PinLength=10|Location.X=340|Location.Y=830|Name=1|Designator=1|PinPropagationDelay=0.000000E+000
|RECORD=14|OwnerIndex=160|IsNotAccesible=T|IndexInSheet=2|OwnerPartId=1|OwnerPartDisplayMode=1|Location.X=340|Location.Y=826|Corner.X=360|Corner.Y=834|LineWidth=1|Color=16711680|AreaColor=11599871
|RECORD=2|OwnerIndex=160|OwnerPartId=1|FormalType=1|Electrical=4|PinConglomerate=32|PinLength=10|Location.X=360|Location.Y=830|Name=2|Designator=2|PinPropagationDelay=0.000000E+000
|RECORD=2|OwnerIndex=160|OwnerPartId=1|FormalType=1|Electrical=4|PinConglomerate=34|PinLength=10|Location.X=340|Location.Y=830|Name=1|Designator=1|PinPropagationDelay=0.000000E+000
|RECORD=6|OwnerIndex=160|IsNotAccesible=T|IndexInSheet=5|OwnerPartId=1|LineWidth=1|Color=16711680|LocationCount=10|X1=360|Y1=830|X2=356|Y2=830|X3=355|Y3=828|X4=353|Y4=832|X5=351|Y5=828|X6=349|Y6=832|X7=347|Y7=828|X8=345|Y8=832|X9=344|Y9=830|X10=340|Y10=830
|RECORD=41|OwnerIndex=160|IndexInSheet=6|OwnerPartId=-1|Location.X=328|Location.Y=843|Color=8388608|FontID=1|IsHidden=T|Text=CRCW12060000Z0EAHP|Name=Part Number
|RECORD=41|OwnerIndex=160|IndexInSheet=7|OwnerPartId=-1|Location.X=328|Location.Y=843|Color=8388608|FontID=1|IsHidden=T|Text=Vishay Dale|Name=Manufacturer
|RECORD=34|OwnerIndex=160|IndexInSheet=-1|OwnerPartId=-1|Location.X=339|Location.Y=833|Color=8388608|FontID=1|Text=R44|Name=Designator|ReadOnlyState=1
|RECORD=41|OwnerIndex=160|IndexInSheet=-1|OwnerPartId=-1|Location.X=339|Location.Y=817|Color=8388608|FontID=1|Text=DNI_0_5%_1206|Name=Comment
|RECORD=44|OwnerIndex=160
|RECORD=45|OwnerIndex=175|IndexInSheet=-1|Description=Chip Resistor, 2-Leads, Body 3.10x1.60mm, IPC Low Density|UseComponentLibrary=T|ModelName=RESC3116X65X50ML20T20|ModelType=PCBLIB|DatafileCount=1|ModelDatafileEntity0=RESC3116X65X50ML20T20|ModelDatafileKind0=PCBLib|IsCurrent=T|DatalinksLocked=T|DatabaseDatalinksLocked=T
|RECORD=46|OwnerIndex=176
|RECORD=48|OwnerIndex=176
|RECORD=41|OwnerIndex=178|IndexInSheet=-1|OwnerPartId=-1|Color=8388608|FontID=1|IsHidden=T|Text=2D|Name=Available Preview Images
|RECORD=45|OwnerIndex=175|IndexInSheet=-1|Description=Chip Resistor, 2-Leads, Body 3.10x1.60mm, IPC High Density|UseComponentLibrary=T|ModelName=RESC3116X65X50LL20T20|ModelType=PCBLIB|DatafileCount=1|ModelDatafileEntity0=RESC3116X65X50LL20T20|ModelDatafileKind0=PCBLib|DatalinksLocked=T|DatabaseDatalinksLocked=T
|RECORD=46|OwnerIndex=180
|RECORD=48|OwnerIndex=180
|RECORD=41|OwnerIndex=182|IndexInSheet=-1|OwnerPartId=-1|Color=8388608|FontID=1|IsHidden=T|Text=2D|Name=Available Preview Images
|RECORD=45|OwnerIndex=175|IndexInSheet=-1|Description=Chip Resistor, 2-Leads, Body 3.10x1.60mm, IPC Medium Density|UseComponentLibrary=T|ModelName=RESC3116X65X50NL20T20|ModelType=PCBLIB|DatafileCount=1|ModelDatafileEntity0=RESC3116X65X50NL20T20|ModelDatafileKind0=PCBLib|DatalinksLocked=T|DatabaseDatalinksLocked=T
|RECORD=46|OwnerIndex=184
|RECORD=48|OwnerIndex=184
|RECORD=41|OwnerIndex=186|IndexInSheet=-1|OwnerPartId=-1|Color=8388608|FontID=1|IsHidden=T|Text=2D|Name=Available Preview Images
|RECORD=1|LibReference=ac72c5313ea981db199dbd0e8237b04|ComponentDescription=CONN HEADER R/A 4POS 4.2MM|PartCount=3|DisplayModeCount=1|IndexInSheet=46|OwnerPartId=-1|Location.X=105|Location.Y=930|CurrentPartId=1|LibraryPath=*|SourceLibraryName=Altium Content Vault|TargetFileName=*|AreaColor=11599871|Color=128|PartIDLocked=T|DesignItemId=CMP-2000-05600-2|AllPinCount=4
|RECORD=14|OwnerIndex=188|IsNotAccesible=T|OwnerPartId=1|Location.X=65|Location.Y=890|Corner.X=85|Corner.Y=950|LineWidth=1|Color=128|AreaColor=11599871|IsSolid=T
|RECORD=14|OwnerIndex=188|IsNotAccesible=T|IndexInSheet=1|OwnerPartId=1|Location.X=69|Location.Y=927|Corner.X=78|Corner.Y=933|LineWidth=1|Color=16711680|AreaColor=16711680|IsSolid=T
|RECORD=13|OwnerIndex=188|IsNotAccesible=T|IndexInSheet=2|OwnerPartId=1|Location.X=78|Location.Y=930|Corner.X=85|Corner.Y=930|LineWidth=1|Color=16711680
|RECORD=14|OwnerIndex=188|IsNotAccesible=T|IndexInSheet=3|OwnerPartId=1|Location.X=69|Location.Y=907|Corner.X=78|Corner.Y=913|LineWidth=1|Color=16711680|AreaColor=16711680|IsSolid=T
|RECORD=13|OwnerIndex=188|IsNotAccesible=T|IndexInSheet=4|OwnerPartId=1|Location.X=78|Location.Y=910|Corner.X=85|Corner.Y=910|LineWidth=1|Color=16711680
|RECORD=4|OwnerIndex=188|IsNotAccesible=T|IndexInSheet=5|OwnerPartId=1|Location.X=78|Location.Y=942|Justification=8|Color=8388608|FontID=1|Text=1
|RECORD=4|OwnerIndex=188|IsNotAccesible=T|IndexInSheet=6|OwnerPartId=1|Location.X=78|Location.Y=922|Justification=8|Color=8388608|FontID=1|Text=2
|RECORD=2|OwnerIndex=188|OwnerPartId=1|Electrical=4|PinConglomerate=48|PinLength=20|Location.X=85|Location.Y=930|Name=1|Designator=1|PinPropagationDelay=0.000000E+000
|RECORD=2|OwnerIndex=188|OwnerPartId=1|Electrical=4|PinConglomerate=48|PinLength=20|Location.X=85|Location.Y=910|Name=2|Designator=2|PinPropagationDelay=0.000000E+000
|RECORD=14|OwnerIndex=188|IsNotAccesible=T|IndexInSheet=9|OwnerPartId=2|Location.X=65|Location.Y=890|Corner.X=85|Corner.Y=950|LineWidth=1|Color=128|AreaColor=11599871|IsSolid=T
|RECORD=14|OwnerIndex=188|IsNotAccesible=T|IndexInSheet=10|OwnerPartId=2|Location.X=69|Location.Y=927|Corner.X=78|Corner.Y=933|LineWidth=1|Color=16711680|AreaColor=16711680|IsSolid=T
|RECORD=13|OwnerIndex=188|IsNotAccesible=T|IndexInSheet=11|OwnerPartId=2|Location.X=78|Location.Y=930|Corner.X=85|Corner.Y=930|LineWidth=1|Color=16711680
|RECORD=14|OwnerIndex=188|IsNotAccesible=T|IndexInSheet=12|OwnerPartId=2|Location.X=69|Location.Y=907|Corner.X=78|Corner.Y=913|LineWidth=1|Color=16711680|AreaColor=16711680|IsSolid=T
|RECORD=13|OwnerIndex=188|IsNotAccesible=T|IndexInSheet=13|OwnerPartId=2|Location.X=78|Location.Y=910|Corner.X=85|Corner.Y=910|LineWidth=1|Color=16711680
|RECORD=4|OwnerIndex=188|IsNotAccesible=T|IndexInSheet=14|OwnerPartId=2|Location.X=78|Location.Y=942|Justification=8|Color=8388608|FontID=1|Text=3
|RECORD=4|OwnerIndex=188|IsNotAccesible=T|IndexInSheet=15|OwnerPartId=2|Location.X=78|Location.Y=922|Justification=8|Color=8388608|FontID=1|Text=4
|RECORD=2|OwnerIndex=188|OwnerPartId=2|Electrical=4|PinConglomerate=48|PinLength=20|Location.X=85|Location.Y=930|Name=3|Designator=3|PinPropagationDelay=0.000000E+000
|RECORD=2|OwnerIndex=188|OwnerPartId=2|Electrical=4|PinConglomerate=48|PinLength=20|Location.X=85|Location.Y=910|Name=4|Designator=4|PinPropagationDelay=0.000000E+000
|RECORD=41|OwnerIndex=188|IndexInSheet=18|OwnerPartId=-1|Location.X=65|Location.Y=950|Color=8388608|FontID=1|IsHidden=T|Text=13A|Name=Current Rating
|RECORD=41|OwnerIndex=188|IndexInSheet=19|OwnerPartId=-1|Location.X=65|Location.Y=950|Color=8388608|FontID=1|IsHidden=T|Text=Connectors|Name=Device Class L1
|RECORD=41|OwnerIndex=188|IndexInSheet=20|OwnerPartId=-1|Location.X=65|Location.Y=950|Color=8388608|FontID=1|IsHidden=T|Text=4.2mm|Name=Pitch
|RECORD=41|OwnerIndex=188|IndexInSheet=21|OwnerPartId=-1|Location.X=65|Location.Y=950|Color=8388608|FontID=1|IsHidden=T|Text=39-30-0040|Name=Package
|RECORD=41|OwnerIndex=188|IndexInSheet=22|OwnerPartId=-1|Location.X=65|Location.Y=950|Color=8388608|FontID=3|IsHidden=T|Text=https://octopart.com/39-30-0040-molex-277428|Name=Octopart
|RECORD=41|OwnerIndex=188|IndexInSheet=23|OwnerPartId=-1|Location.X=65|Location.Y=950|Color=8388608|FontID=1|IsHidden=T|Text=Headers & Wire Housings 4 CKT R/A HEADER|Name=Mouser Description
|RECORD=41|OwnerIndex=188|IndexInSheet=24|OwnerPartId=-1|Location.X=65|Location.Y=950|Color=8388608|FontID=1|IsHidden=T|Text=+105°C|Name=Temperature Range High
|RECORD=41|OwnerIndex=188|IndexInSheet=25|OwnerPartId=-1|Location.X=65|Location.Y=950|Color=8388608|FontID=1|IsHidden=T|Text=2|Name=Number Of Rows
|RECORD=41|OwnerIndex=188|IndexInSheet=26|OwnerPartId=-1|Location.X=65|Location.Y=950|Color=8388608|FontID=1|IsHidden=T|Text=600V|Name=Voltage Rating
|RECORD=41|OwnerIndex=188|IndexInSheet=27|OwnerPartId=-1|Location.X=65|Location.Y=950|Color=8388608|FontID=1|IsHidden=T|Text=Datasheet|Name=ComponentLink2Description
|RECORD=41|OwnerIndex=188|IndexInSheet=28|OwnerPartId=-1|Location.X=65|Location.Y=950|Color=8388608|FontID=3|IsHidden=T|Text=https://www.molex.com/webdocs/datasheets/pdf/en-us/0039300040_PCB_HEADERS.pdf|Name=ComponentLink2URL
|RECORD=41|OwnerIndex=188|IndexInSheet=29|OwnerPartId=-1|Location.X=65|Location.Y=950|Color=8388608|FontID=1|IsHidden=T|Text=4|Name=Number Of Contacts
|RECORD=41|OwnerIndex=188|IndexInSheet=30|OwnerPartId=-1|Location.X=65|Location.Y=950|Color=8388608|FontID=1|IsHidden=T|Text=39-30-0040|Name=Manufacturer Part Number
|RECORD=41|OwnerIndex=188|IndexInSheet=31|OwnerPartId=-1|Location.X=65|Location.Y=950|Color=8388608|FontID=1|IsHidden=T|Text=Gold,Nickel|Name=Contact Material
|RECORD=41|OwnerIndex=188|IndexInSheet=32|OwnerPartId=-1|Location.X=65|Location.Y=950|Color=8388608|FontID=1|IsHidden=T|Text=CONN HEADER R/A 4POS 4.2MM|Name=Digikey Description
|RECORD=41|OwnerIndex=188|IndexInSheet=33|OwnerPartId=-1|Location.X=65|Location.Y=950|Color=8388608|FontID=1|IsHidden=T|Text=-40°C to +105°C|Name=Temperature
|RECORD=41|OwnerIndex=188|IndexInSheet=34|OwnerPartId=-1|Location.X=65|Location.Y=950|Color=8388608|FontID=1|IsHidden=T|Text=0.4mm|Name=Standoff Height
|RECORD=41|OwnerIndex=188|IndexInSheet=35|OwnerPartId=-1|Location.X=65|Location.Y=950|Color=8388608|FontID=1|IsHidden=T|Text=No|Name=Automotive
|RECORD=41|OwnerIndex=188|IndexInSheet=36|OwnerPartId=-1|Location.X=65|Location.Y=950|Color=8388608|FontID=1|IsHidden=T|Text=Headers and Wire Housings|Name=Device Class L2
|RECORD=41|OwnerIndex=188|IndexInSheet=37|OwnerPartId=-1|Location.X=65|Location.Y=950|Color=8388608|FontID=1|IsHidden=T|Text=Right Angle|Name=Conn Orientation
|RECORD=41|OwnerIndex=188|IndexInSheet=38|OwnerPartId=-1|Location.X=65|Location.Y=950|Color=8388608|FontID=1|IsHidden=T|Text=TRUE|Name=RoHS
|RECORD=41|OwnerIndex=188|IndexInSheet=39|OwnerPartId=-1|Location.X=65|Location.Y=950|Color=8388608|FontID=1|IsHidden=T|Text=Yes|Name=Lead Free
|RECORD=41|OwnerIndex=188|IndexInSheet=40|OwnerPartId=-1|Location.X=65|Location.Y=950|Color=8388608|FontID=1|IsHidden=T|Text=unset|Name=Device Class L3
|RECORD=41|OwnerIndex=188|IndexInSheet=41|OwnerPartId=-1|Location.X=65|Location.Y=950|Color=8388608|FontID=1|IsHidden=T|Text=Conn|Name=Category
|RECORD=41|OwnerIndex=188|IndexInSheet=42|OwnerPartId=-1|Location.X=65|Location.Y=950|Color=8388608|FontID=3|IsHidden=T|Text=https://www.molex.com/pdm_docs/sd/039300040_sd.pdf|Name=Footprint Url
|RECORD=41|OwnerIndex=188|IndexInSheet=43|OwnerPartId=-1|Location.X=65|Location.Y=950|Color=8388608|FontID=1|IsHidden=T|Text=-40°C|Name=Temperature Range Low
|RECORD=41|OwnerIndex=188|IndexInSheet=44|OwnerPartId=-1|Location.X=65|Location.Y=950|Color=8388608|FontID=1|IsHidden=T|Text=Male|Name=Conn Gender
|RECORD=41|OwnerIndex=188|IndexInSheet=45|OwnerPartId=-1|Location.X=65|Location.Y=950|Color=8388608|FontID=1|IsHidden=T|Text=Molex|Name=Manufacturer
|RECORD=34|OwnerIndex=188|IndexInSheet=-1|OwnerPartId=-1|Location.X=65|Location.Y=950|Color=8388608|FontID=1|Text=J38|Name=Designator|ReadOnlyState=1
|RECORD=41|OwnerIndex=188|IndexInSheet=-1|OwnerPartId=1|Location.X=65|Location.Y=880|Color=8388608|FontID=1|Text=39-30-0040|Name=Comment
|RECORD=44|OwnerIndex=188
|RECORD=45|OwnerIndex=241|IndexInSheet=-1|UseComponentLibrary=T|ModelName=FP-39-30-0040-MFG|ModelType=PCBLIB|DatafileCount=1|ModelDatafileEntity0=FP-39-30-0040-MFG|ModelDatafileKind0=PCBLib|IsCurrent=T|DatalinksLocked=T|DatabaseDatalinksLocked=T
|RECORD=46|OwnerIndex=242
|RECORD=48|OwnerIndex=242
|RECORD=1|LibReference=ac72c5313ea981db199dbd0e8237b04|ComponentDescription=CONN HEADER R/A 4POS 4.2MM|PartCount=3|DisplayModeCount=1|IndexInSheet=47|OwnerPartId=-1|Location.X=105|Location.Y=1010|CurrentPartId=2|LibraryPath=*|SourceLibraryName=Altium Content Vault|TargetFileName=*|AreaColor=11599871|Color=128|PartIDLocked=T|DesignItemId=CMP-2000-05600-2|AllPinCount=4
|RECORD=14|OwnerIndex=245|IsNotAccesible=T|OwnerPartId=1|Location.X=65|Location.Y=970|Corner.X=85|Corner.Y=1030|LineWidth=1|Color=128|AreaColor=11599871|IsSolid=T
|RECORD=14|OwnerIndex=245|IsNotAccesible=T|IndexInSheet=1|OwnerPartId=1|Location.X=69|Location.Y=1007|Corner.X=78|Corner.Y=1013|LineWidth=1|Color=16711680|AreaColor=16711680|IsSolid=T
|RECORD=13|OwnerIndex=245|IsNotAccesible=T|IndexInSheet=2|OwnerPartId=1|Location.X=78|Location.Y=1010|Corner.X=85|Corner.Y=1010|LineWidth=1|Color=16711680
|RECORD=14|OwnerIndex=245|IsNotAccesible=T|IndexInSheet=3|OwnerPartId=1|Location.X=69|Location.Y=987|Corner.X=78|Corner.Y=993|LineWidth=1|Color=16711680|AreaColor=16711680|IsSolid=T
|RECORD=13|OwnerIndex=245|IsNotAccesible=T|IndexInSheet=4|OwnerPartId=1|Location.X=78|Location.Y=990|Corner.X=85|Corner.Y=990|LineWidth=1|Color=16711680
|RECORD=4|OwnerIndex=245|IsNotAccesible=T|IndexInSheet=5|OwnerPartId=1|Location.X=78|Location.Y=1022|Justification=8|Color=8388608|FontID=1|Text=1
|RECORD=4|OwnerIndex=245|IsNotAccesible=T|IndexInSheet=6|OwnerPartId=1|Location.X=78|Location.Y=1002|Justification=8|Color=8388608|FontID=1|Text=2
|RECORD=2|OwnerIndex=245|OwnerPartId=1|Electrical=4|PinConglomerate=48|PinLength=20|Location.X=85|Location.Y=1010|Name=1|Designator=1|PinPropagationDelay=0.000000E+000
|RECORD=2|OwnerIndex=245|OwnerPartId=1|Electrical=4|PinConglomerate=48|PinLength=20|Location.X=85|Location.Y=990|Name=2|Designator=2|PinPropagationDelay=0.000000E+000
|RECORD=14|OwnerIndex=245|IsNotAccesible=T|IndexInSheet=9|OwnerPartId=2|Location.X=65|Location.Y=970|Corner.X=85|Corner.Y=1030|LineWidth=1|Color=128|AreaColor=11599871|IsSolid=T
|RECORD=14|OwnerIndex=245|IsNotAccesible=T|IndexInSheet=10|OwnerPartId=2|Location.X=69|Location.Y=1007|Corner.X=78|Corner.Y=1013|LineWidth=1|Color=16711680|AreaColor=16711680|IsSolid=T
|RECORD=13|OwnerIndex=245|IsNotAccesible=T|IndexInSheet=11|OwnerPartId=2|Location.X=78|Location.Y=1010|Corner.X=85|Corner.Y=1010|LineWidth=1|Color=16711680
|RECORD=14|OwnerIndex=245|IsNotAccesible=T|IndexInSheet=12|OwnerPartId=2|Location.X=69|Location.Y=987|Corner.X=78|Corner.Y=993|LineWidth=1|Color=16711680|AreaColor=16711680|IsSolid=T
|RECORD=13|OwnerIndex=245|IsNotAccesible=T|IndexInSheet=13|OwnerPartId=2|Location.X=78|Location.Y=990|Corner.X=85|Corner.Y=990|LineWidth=1|Color=16711680
|RECORD=4|OwnerIndex=245|IsNotAccesible=T|IndexInSheet=14|OwnerPartId=2|Location.X=78|Location.Y=1022|Justification=8|Color=8388608|FontID=1|Text=3
|RECORD=4|OwnerIndex=245|IsNotAccesible=T|IndexInSheet=15|OwnerPartId=2|Location.X=78|Location.Y=1002|Justification=8|Color=8388608|FontID=1|Text=4
|RECORD=2|OwnerIndex=245|OwnerPartId=2|Electrical=4|PinConglomerate=48|PinLength=20|Location.X=85|Location.Y=1010|Name=3|Designator=3|PinPropagationDelay=0.000000E+000
|RECORD=2|OwnerIndex=245|OwnerPartId=2|Electrical=4|PinConglomerate=48|PinLength=20|Location.X=85|Location.Y=990|Name=4|Designator=4|PinPropagationDelay=0.000000E+000
|RECORD=41|OwnerIndex=245|IndexInSheet=18|OwnerPartId=-1|Location.X=65|Location.Y=1030|Color=8388608|FontID=1|IsHidden=T|Text=13A|Name=Current Rating
|RECORD=41|OwnerIndex=245|IndexInSheet=19|OwnerPartId=-1|Location.X=65|Location.Y=1030|Color=8388608|FontID=1|IsHidden=T|Text=Connectors|Name=Device Class L1
|RECORD=41|OwnerIndex=245|IndexInSheet=20|OwnerPartId=-1|Location.X=65|Location.Y=1030|Color=8388608|FontID=1|IsHidden=T|Text=4.2mm|Name=Pitch
|RECORD=41|OwnerIndex=245|IndexInSheet=21|OwnerPartId=-1|Location.X=65|Location.Y=1030|Color=8388608|FontID=1|IsHidden=T|Text=39-30-0040|Name=Package
|RECORD=41|OwnerIndex=245|IndexInSheet=22|OwnerPartId=-1|Location.X=65|Location.Y=1030|Color=8388608|FontID=3|IsHidden=T|Text=https://octopart.com/39-30-0040-molex-277428|Name=Octopart
|RECORD=41|OwnerIndex=245|IndexInSheet=23|OwnerPartId=-1|Location.X=65|Location.Y=1030|Color=8388608|FontID=1|IsHidden=T|Text=Headers & Wire Housings 4 CKT R/A HEADER|Name=Mouser Description
|RECORD=41|OwnerIndex=245|IndexInSheet=24|OwnerPartId=-1|Location.X=65|Location.Y=1030|Color=8388608|FontID=1|IsHidden=T|Text=+105°C|Name=Temperature Range High
|RECORD=41|OwnerIndex=245|IndexInSheet=25|OwnerPartId=-1|Location.X=65|Location.Y=1030|Color=8388608|FontID=1|IsHidden=T|Text=2|Name=Number Of Rows
|RECORD=41|OwnerIndex=245|IndexInSheet=26|OwnerPartId=-1|Location.X=65|Location.Y=1030|Color=8388608|FontID=1|IsHidden=T|Text=600V|Name=Voltage Rating
|RECORD=41|OwnerIndex=245|IndexInSheet=27|OwnerPartId=-1|Location.X=65|Location.Y=1030|Color=8388608|FontID=1|IsHidden=T|Text=Datasheet|Name=ComponentLink2Description
|RECORD=41|OwnerIndex=245|IndexInSheet=28|OwnerPartId=-1|Location.X=65|Location.Y=1030|Color=8388608|FontID=3|IsHidden=T|Text=https://www.molex.com/webdocs/datasheets/pdf/en-us/0039300040_PCB_HEADERS.pdf|Name=ComponentLink2URL
|RECORD=41|OwnerIndex=245|IndexInSheet=29|OwnerPartId=-1|Location.X=65|Location.Y=1030|Color=8388608|FontID=1|IsHidden=T|Text=4|Name=Number Of Contacts
|RECORD=41|OwnerIndex=245|IndexInSheet=30|OwnerPartId=-1|Location.X=65|Location.Y=1030|Color=8388608|FontID=1|IsHidden=T|Text=39-30-0040|Name=Manufacturer Part Number
|RECORD=41|OwnerIndex=245|IndexInSheet=31|OwnerPartId=-1|Location.X=65|Location.Y=1030|Color=8388608|FontID=1|IsHidden=T|Text=Gold,Nickel|Name=Contact Material
|RECORD=41|OwnerIndex=245|IndexInSheet=32|OwnerPartId=-1|Location.X=65|Location.Y=1030|Color=8388608|FontID=1|IsHidden=T|Text=CONN HEADER R/A 4POS 4.2MM|Name=Digikey Description
|RECORD=41|OwnerIndex=245|IndexInSheet=33|OwnerPartId=-1|Location.X=65|Location.Y=1030|Color=8388608|FontID=1|IsHidden=T|Text=-40°C to +105°C|Name=Temperature
|RECORD=41|OwnerIndex=245|IndexInSheet=34|OwnerPartId=-1|Location.X=65|Location.Y=1030|Color=8388608|FontID=1|IsHidden=T|Text=0.4mm|Name=Standoff Height
|RECORD=41|OwnerIndex=245|IndexInSheet=35|OwnerPartId=-1|Location.X=65|Location.Y=1030|Color=8388608|FontID=1|IsHidden=T|Text=No|Name=Automotive
|RECORD=41|OwnerIndex=245|IndexInSheet=36|OwnerPartId=-1|Location.X=65|Location.Y=1030|Color=8388608|FontID=1|IsHidden=T|Text=Headers and Wire Housings|Name=Device Class L2
|RECORD=41|OwnerIndex=245|IndexInSheet=37|OwnerPartId=-1|Location.X=65|Location.Y=1030|Color=8388608|FontID=1|IsHidden=T|Text=Right Angle|Name=Conn Orientation
|RECORD=41|OwnerIndex=245|IndexInSheet=38|OwnerPartId=-1|Location.X=65|Location.Y=1030|Color=8388608|FontID=1|IsHidden=T|Text=TRUE|Name=RoHS
|RECORD=41|OwnerIndex=245|IndexInSheet=39|OwnerPartId=-1|Location.X=65|Location.Y=1030|Color=8388608|FontID=1|IsHidden=T|Text=Yes|Name=Lead Free
|RECORD=41|OwnerIndex=245|IndexInSheet=40|OwnerPartId=-1|Location.X=65|Location.Y=1030|Color=8388608|FontID=1|IsHidden=T|Text=unset|Name=Device Class L3
|RECORD=41|OwnerIndex=245|IndexInSheet=41|OwnerPartId=-1|Location.X=65|Location.Y=1030|Color=8388608|FontID=1|IsHidden=T|Text=Conn|Name=Category
|RECORD=41|OwnerIndex=245|IndexInSheet=42|OwnerPartId=-1|Location.X=65|Location.Y=1030|Color=8388608|FontID=3|IsHidden=T|Text=https://www.molex.com/pdm_docs/sd/039300040_sd.pdf|Name=Footprint Url
|RECORD=41|OwnerIndex=245|IndexInSheet=43|OwnerPartId=-1|Location.X=65|Location.Y=1030|Color=8388608|FontID=1|IsHidden=T|Text=-40°C|Name=Temperature Range Low
|RECORD=41|OwnerIndex=245|IndexInSheet=44|OwnerPartId=-1|Location.X=65|Location.Y=1030|Color=8388608|FontID=1|IsHidden=T|Text=Male|Name=Conn Gender
|RECORD=41|OwnerIndex=245|IndexInSheet=45|OwnerPartId=-1|Location.X=65|Location.Y=1030|Color=8388608|FontID=1|IsHidden=T|Text=Molex|Name=Manufacturer
|RECORD=34|OwnerIndex=245|IndexInSheet=-1|OwnerPartId=-1|Location.X=65|Location.Y=1030|Color=8388608|FontID=1|Text=J38|Name=Designator|ReadOnlyState=1
|RECORD=41|OwnerIndex=245|IndexInSheet=-1|OwnerPartId=1|Location.X=65|Location.Y=960|Color=8388608|FontID=1|Text=39-30-0040|Name=Comment
|RECORD=44|OwnerIndex=245
|RECORD=45|OwnerIndex=298|IndexInSheet=-1|UseComponentLibrary=T|ModelName=FP-39-30-0040-MFG|ModelType=PCBLIB|DatafileCount=1|ModelDatafileEntity0=FP-39-30-0040-MFG|ModelDatafileKind0=PCBLib|IsCurrent=T|DatalinksLocked=T|DatabaseDatalinksLocked=T
|RECORD=46|OwnerIndex=299
|RECORD=48|OwnerIndex=299
|RECORD=1|LibReference=41cc1aee4cbc9fa2660a15773fa0e79|ComponentDescription=IC MONITOR PWR/CURR BIDIR 8-SOIC|PartCount=2|DisplayModeCount=1|IndexInSheet=48|OwnerPartId=-1|Location.X=340|Location.Y=755|CurrentPartId=1|LibraryPath=*|SourceLibraryName=Altium Content Vault|TargetFileName=*|AreaColor=11599871|Color=128|PartIDLocked=T|DesignItemId=CMP-0704-00005-3|AllPinCount=8
|RECORD=14|OwnerIndex=302|IsNotAccesible=T|OwnerPartId=1|Location.X=360|Location.Y=675|Corner.X=450|Corner.Y=765|LineWidth=1|Color=128|AreaColor=11599871|IsSolid=T
|RECORD=2|OwnerIndex=302|OwnerPartId=1|PinConglomerate=58|PinLength=20|Location.X=360|Location.Y=695|Name=VIN+|Designator=8|PinName_PositionConglomerate=16|Name_CustomFontID=1|PinDesignator_PositionConglomerate=16|Designator_CustomFontID=1|PinPropagationDelay=0.000000E+000
|RECORD=2|OwnerIndex=302|OwnerPartId=1|PinConglomerate=58|PinLength=20|Location.X=360|Location.Y=685|Name=VIN-|Designator=7|PinName_PositionConglomerate=16|Name_CustomFontID=1|PinDesignator_PositionConglomerate=16|Designator_CustomFontID=1|PinPropagationDelay=0.000000E+000
|RECORD=2|OwnerIndex=302|OwnerPartId=1|PinConglomerate=56|PinLength=20|Location.X=450|Location.Y=715|Name=A0|Designator=2|PinName_PositionConglomerate=16|Name_CustomFontID=1|PinDesignator_PositionConglomerate=16|Designator_CustomFontID=1|PinPropagationDelay=0.000000E+000
|RECORD=2|OwnerIndex=302|OwnerPartId=1|PinConglomerate=56|PinLength=20|Location.X=450|Location.Y=705|Name=A1|Designator=1|PinName_PositionConglomerate=16|Name_CustomFontID=1|PinDesignator_PositionConglomerate=16|Designator_CustomFontID=1|PinPropagationDelay=0.000000E+000
|RECORD=2|OwnerIndex=302|OwnerPartId=1|SymBol_InnerEdge=3|Electrical=1|PinConglomerate=56|PinLength=20|Location.X=450|Location.Y=735|Name=SCL|Designator=4|PinName_PositionConglomerate=16|Name_CustomFontID=1|PinDesignator_PositionConglomerate=16|Designator_CustomFontID=1|PinPropagationDelay=0.000000E+000
|RECORD=2|OwnerIndex=302|OwnerPartId=1|Electrical=1|PinConglomerate=56|PinLength=20|Location.X=450|Location.Y=755|Name=SDA|Designator=3|PinName_PositionConglomerate=16|Name_CustomFontID=1|PinDesignator_PositionConglomerate=16|Designator_CustomFontID=1|PinPropagationDelay=0.000000E+000
|RECORD=2|OwnerIndex=302|OwnerPartId=1|Electrical=7|PinConglomerate=58|PinLength=20|Location.X=360|Location.Y=755|Name=VS|Designator=5|PinName_PositionConglomerate=16|Name_CustomFontID=1|PinDesignator_PositionConglomerate=16|Designator_CustomFontID=1|PinPropagationDelay=0.000000E+000
|RECORD=2|OwnerIndex=302|OwnerPartId=1|Electrical=7|PinConglomerate=56|PinLength=20|Location.X=450|Location.Y=685|Name=GND|Designator=6|PinName_PositionConglomerate=16|Name_CustomFontID=1|PinDesignator_PositionConglomerate=16|Designator_CustomFontID=1|PinPropagationDelay=0.000000E+000
|RECORD=41|OwnerIndex=302|IndexInSheet=9|OwnerPartId=-1|Location.X=338|Location.Y=765|Color=8388608|FontID=1|IsHidden=T|Text=3V|Name=Min Supply Voltage
|RECORD=41|OwnerIndex=302|IndexInSheet=10|OwnerPartId=-1|Location.X=338|Location.Y=765|Color=8388608|FontID=1|IsHidden=T|Text=100dB|Name=Common Mode Rejection Ratio
|RECORD=41|OwnerIndex=302|IndexInSheet=11|OwnerPartId=-1|Location.X=338|Location.Y=765|Color=8388608|FontID=1|IsHidden=T|Text=Tape and Reel|Name=Packaging
|RECORD=41|OwnerIndex=302|IndexInSheet=12|OwnerPartId=-1|Location.X=338|Location.Y=765|Color=8388608|FontID=1|IsHidden=T|Text=No SVHC|Name=REACH SVHC
|RECORD=41|OwnerIndex=302|IndexInSheet=13|OwnerPartId=-1|Location.X=338|Location.Y=765|Color=8388608|FontID=1|IsHidden=T|Text=125°C|Name=Max Operating Temperature
|RECORD=41|OwnerIndex=302|IndexInSheet=14|OwnerPartId=-1|Location.X=338|Location.Y=765|Color=8388608|FontID=1|IsHidden=T|Text=8|Name=Number of Pins
|RECORD=41|OwnerIndex=302|IndexInSheet=15|OwnerPartId=-1|Location.X=338|Location.Y=765|Color=8388608|FontID=1|IsHidden=T|Text=10mA|Name=Output Current
|RECORD=41|OwnerIndex=302|IndexInSheet=16|OwnerPartId=-1|Location.X=338|Location.Y=765|Color=8388608|FontID=1|IsHidden=T|Text=Lead Free|Name=Lead Free
|RECORD=41|OwnerIndex=302|IndexInSheet=17|OwnerPartId=-1|Location.X=338|Location.Y=765|Color=8388608|FontID=1|IsHidden=T|Text=1|Name=Package Quantity
|RECORD=41|OwnerIndex=302|IndexInSheet=18|OwnerPartId=-1|Location.X=338|Location.Y=765|Color=8388608|FontID=1|IsHidden=T|Text=No|Name=Radiation Hardening
|RECORD=41|OwnerIndex=302|IndexInSheet=19|OwnerPartId=-1|Location.X=338|Location.Y=765|Color=8388608|FontID=1|IsHidden=T|Text=SOIC|Name=Case/Package
|RECORD=41|OwnerIndex=302|IndexInSheet=20|OwnerPartId=-1|Location.X=338|Location.Y=765|Color=8388608|FontID=1|IsHidden=T|Text=1|Name=Number of Amplifiers
|RECORD=41|OwnerIndex=302|IndexInSheet=21|OwnerPartId=-1|Location.X=338|Location.Y=765|Color=8388608|FontID=1|IsHidden=T|Text=-40°C|Name=Min Operating Temperature
|RECORD=41|OwnerIndex=302|IndexInSheet=22|OwnerPartId=-1|Location.X=338|Location.Y=765|Color=8388608|FontID=1|IsHidden=T|Text=0.5%|Name=Accuracy
|RECORD=41|OwnerIndex=302|IndexInSheet=23|OwnerPartId=-1|Location.X=338|Location.Y=765|Color=8388608|FontID=1|IsHidden=T|Text=1mA|Name=Supply Current
|RECORD=41|OwnerIndex=302|IndexInSheet=24|OwnerPartId=-1|Location.X=338|Location.Y=765|Color=8388608|FontID=1|IsHidden=T|Text=Gold|Name=Contact Plating
|RECORD=41|OwnerIndex=302|IndexInSheet=25|OwnerPartId=-1|Location.X=338|Location.Y=765|Color=8388608|FontID=1|IsHidden=T|Text=700uA|Name=Quiescent Current
|RECORD=41|OwnerIndex=302|IndexInSheet=26|OwnerPartId=-1|Location.X=338|Location.Y=765|Color=8388608|FontID=1|IsHidden=T|Text=Zero-Drift|Name=Series
|RECORD=41|OwnerIndex=302|IndexInSheet=27|OwnerPartId=-1|Location.X=338|Location.Y=765|Color=8388608|FontID=1|IsHidden=T|Text=1mA|Name=Nominal Supply Current
|RECORD=41|OwnerIndex=302|IndexInSheet=28|OwnerPartId=-1|Location.X=338|Location.Y=765|Color=8388608|FontID=1|IsHidden=T|Text=11kHz|Name=Bandwidth
|RECORD=41|OwnerIndex=302|IndexInSheet=29|OwnerPartId=-1|Location.X=338|Location.Y=765|Color=8388608|FontID=1|IsHidden=T|Text=40uV|Name=Input Offset Voltage (Vos)
|RECORD=41|OwnerIndex=302|IndexInSheet=30|OwnerPartId=-1|Location.X=338|Location.Y=765|Color=8388608|FontID=1|IsHidden=T|Text=5.5V|Name=Max Supply Voltage
|RECORD=41|OwnerIndex=302|IndexInSheet=31|OwnerPartId=-1|Location.X=338|Location.Y=765|Color=8388608|FontID=1|IsHidden=T|Text=Yes|Name=RoHS Compliant
|RECORD=34|OwnerIndex=302|IndexInSheet=-1|OwnerPartId=-1|Location.X=360|Location.Y=765|Color=8388608|FontID=1|Text=U2|Name=Designator|ReadOnlyState=1
|RECORD=41|OwnerIndex=302|IndexInSheet=-1|OwnerPartId=1|Location.X=360|Location.Y=665|Color=8388608|FontID=1|Text=INA219BIDR|Name=Comment
|RECORD=44|OwnerIndex=302
|RECORD=45|OwnerIndex=345|IndexInSheet=-1|UseComponentLibrary=T|ModelName=FP-D0008A-MFG|ModelType=PCBLIB|DatafileCount=1|ModelDatafileEntity0=FP-D0008A-MFG|ModelDatafileKind0=PCBLib|IsCurrent=T|DatalinksLocked=T|DatabaseDatalinksLocked=T
|RECORD=46|OwnerIndex=346
|RECORD=48|OwnerIndex=346
|RECORD=45|OwnerIndex=345|IndexInSheet=-1|UseComponentLibrary=T|ModelName=FP-D0008A-IPC_A|ModelType=PCBLIB|DatafileCount=1|ModelDatafileEntity0=FP-D0008A-IPC_A|ModelDatafileKind0=PCBLib|DatalinksLocked=T|DatabaseDatalinksLocked=T
|RECORD=46|OwnerIndex=349
|RECORD=48|OwnerIndex=349
|RECORD=45|OwnerIndex=345|IndexInSheet=-1|UseComponentLibrary=T|ModelName=FP-D0008A-IPC_C|ModelType=PCBLIB|DatafileCount=1|ModelDatafileEntity0=FP-D0008A-IPC_C|ModelDatafileKind0=PCBLib|DatalinksLocked=T|DatabaseDatalinksLocked=T
|RECORD=46|OwnerIndex=352
|RECORD=48|OwnerIndex=352
|RECORD=45|OwnerIndex=345|IndexInSheet=-1|UseComponentLibrary=T|ModelName=FP-D0008A-IPC_B|ModelType=PCBLIB|DatafileCount=1|ModelDatafileEntity0=FP-D0008A-IPC_B|ModelDatafileKind0=PCBLib|DatalinksLocked=T|DatabaseDatalinksLocked=T
|RECORD=46|OwnerIndex=355
|RECORD=48|OwnerIndex=355
|RECORD=1|LibReference=RES|PartCount=2|DisplayModeCount=2|IndexInSheet=49|OwnerPartId=-1|Location.X=440|Location.Y=925|CurrentPartId=1|SourceLibraryName=Altium Content Vault|TargetFileName=*|AreaColor=11599871|Color=128|PartIDLocked=F|DesignItemId=CMP-2003-04334-1|AllPinCount=2
|RECORD=2|OwnerIndex=358|OwnerPartId=1|OwnerPartDisplayMode=1|FormalType=1|Electrical=4|PinConglomerate=32|PinLength=10|Location.X=460|Location.Y=915|Name=2|Designator=2|PinPropagationDelay=0.000000E+000
|RECORD=2|OwnerIndex=358|OwnerPartId=1|OwnerPartDisplayMode=1|FormalType=1|Electrical=4|PinConglomerate=34|PinLength=10|Location.X=440|Location.Y=915|Name=1|Designator=1|PinPropagationDelay=0.000000E+000
|RECORD=14|OwnerIndex=358|IsNotAccesible=T|IndexInSheet=2|OwnerPartId=1|OwnerPartDisplayMode=1|Location.X=440|Location.Y=911|Corner.X=460|Corner.Y=919|LineWidth=1|Color=16711680|AreaColor=11599871
|RECORD=2|OwnerIndex=358|OwnerPartId=1|FormalType=1|Electrical=4|PinConglomerate=32|PinLength=10|Location.X=460|Location.Y=915|Name=2|Designator=2|PinPropagationDelay=0.000000E+000
|RECORD=2|OwnerIndex=358|OwnerPartId=1|FormalType=1|Electrical=4|PinConglomerate=34|PinLength=10|Location.X=440|Location.Y=915|Name=1|Designator=1|PinPropagationDelay=0.000000E+000
|RECORD=6|OwnerIndex=358|IsNotAccesible=T|IndexInSheet=5|OwnerPartId=1|LineWidth=1|Color=16711680|LocationCount=10|X1=460|Y1=915|X2=456|Y2=915|X3=455|Y3=913|X4=453|Y4=917|X5=451|Y5=913|X6=449|Y6=917|X7=447|Y7=913|X8=445|Y8=917|X9=444|Y9=915|X10=440|Y10=915
|RECORD=41|OwnerIndex=358|IndexInSheet=6|OwnerPartId=-1|Location.X=428|Location.Y=928|Color=8388608|FontID=1|IsHidden=T|Text=Vishay Dale|Name=Manufacturer
|RECORD=41|OwnerIndex=358|IndexInSheet=7|OwnerPartId=-1|Location.X=428|Location.Y=928|Color=8388608|FontID=1|IsHidden=T|Text=WSL12062L000FEA18|Name=Part Number
|RECORD=34|OwnerIndex=358|IndexInSheet=-1|OwnerPartId=-1|Location.X=439|Location.Y=918|Color=8388608|FontID=1|Text=R7|Name=Designator|ReadOnlyState=1
|RECORD=41|OwnerIndex=358|IndexInSheet=-1|OwnerPartId=-1|Location.X=439|Location.Y=902|Color=8388608|FontID=1|Text=2mOhm_1%_1206|Name=Comment
|RECORD=44|OwnerIndex=358
|RECORD=45|OwnerIndex=373|IndexInSheet=-1|Description=Chip Resistor, 2-Leads, Body 3.20x1.60mm, IPC Medium Density|UseComponentLibrary=T|ModelName=RESC3216X89X64NL25T25|ModelType=PCBLIB|DatafileCount=1|ModelDatafileEntity0=RESC3216X89X64NL25T25|ModelDatafileKind0=PCBLib|IsCurrent=T|DatalinksLocked=T|DatabaseDatalinksLocked=T
|RECORD=46|OwnerIndex=374
|RECORD=48|OwnerIndex=374
|RECORD=41|OwnerIndex=376|IndexInSheet=-1|OwnerPartId=-1|Color=8388608|FontID=1|IsHidden=T|Text=2D|Name=Available Preview Images
|RECORD=45|OwnerIndex=373|IndexInSheet=-1|Description=Chip Resistor, 2-Leads, Body 3.20x1.60mm, IPC High Density|UseComponentLibrary=T|ModelName=RESC3216X89X64LL25T25|ModelType=PCBLIB|DatafileCount=1|ModelDatafileEntity0=RESC3216X89X64LL25T25|ModelDatafileKind0=PCBLib|DatalinksLocked=T|DatabaseDatalinksLocked=T
|RECORD=46|OwnerIndex=378
|RECORD=48|OwnerIndex=378
|RECORD=41|OwnerIndex=380|IndexInSheet=-1|OwnerPartId=-1|Color=8388608|FontID=1|IsHidden=T|Text=2D|Name=Available Preview Images
|RECORD=45|OwnerIndex=373|IndexInSheet=-1|Description=Chip Resistor, 2-Leads, Body 3.20x1.60mm, IPC Low Density|UseComponentLibrary=T|ModelName=RESC3216X89X64ML25T25|ModelType=PCBLIB|DatafileCount=1|ModelDatafileEntity0=RESC3216X89X64ML25T25|ModelDatafileKind0=PCBLib|DatalinksLocked=T|DatabaseDatalinksLocked=T
|RECORD=46|OwnerIndex=382
|RECORD=48|OwnerIndex=382
|RECORD=41|OwnerIndex=384|IndexInSheet=-1|OwnerPartId=-1|Color=8388608|FontID=1|IsHidden=T|Text=2D|Name=Available Preview Images
|RECORD=17|IndexInSheet=50|OwnerPartId=-1|ShowNetName=T|Location.X=405|Location.Y=980|Orientation=1|Color=128|FontID=1|Text=+12V_SENS
|RECORD=1|LibReference=b4654b650e69147ec39a6b967a45e02|ComponentDescription=Multilayer Ceramic Capacitor 10uF 16V X5R 20% SMD 0603 T/R|PartCount=2|DisplayModeCount=1|IndexInSheet=51|OwnerPartId=-1|Location.X=200|Location.Y=735|CurrentPartId=1|LibraryPath=*|SourceLibraryName=Altium Content Vault|TargetFileName=*|AreaColor=11599871|Color=128|PartIDLocked=T|DesignItemId=CMP-2000-06226-4|AllPinCount=2
|RECORD=2|OwnerIndex=387|OwnerPartId=1|Electrical=4|PinConglomerate=49|PinLength=7|Location.X=200|Location.Y=728|Name=1|Designator=1|PinPropagationDelay=0.000000E+000
|RECORD=2|OwnerIndex=387|OwnerPartId=1|Electrical=4|PinConglomerate=51|PinLength=6|Location.X=200|Location.Y=721|Name=2|Designator=2|PinPropagationDelay=0.000000E+000
|RECORD=13|OwnerIndex=387|IsNotAccesible=T|IndexInSheet=2|OwnerPartId=1|Location.X=210|Location.Y=728|Corner.X=190|Corner.Y=728|LineWidth=1|Color=16711680
|RECORD=13|OwnerIndex=387|IsNotAccesible=T|IndexInSheet=3|OwnerPartId=1|Location.X=210|Location.Y=722|Corner.X=190|Corner.Y=722|LineWidth=1|Color=16711680
|RECORD=13|OwnerIndex=387|IsNotAccesible=T|IndexInSheet=4|OwnerPartId=1|Location.X=200|Location.Y=728|Corner.X=200|Corner.Y=731|LineWidth=1|Color=16711680
|RECORD=13|OwnerIndex=387|IsNotAccesible=T|IndexInSheet=5|OwnerPartId=1|Location.X=200|Location.Y=721|Corner.X=200|Corner.Y=720|LineWidth=1|Color=16711680
|RECORD=41|OwnerIndex=387|IndexInSheet=6|OwnerPartId=-1|Location.X=189|Location.Y=737|Color=8388608|FontID=1|IsHidden=T|Text=Tape and Reel|Name=Packaging
|RECORD=41|OwnerIndex=387|IndexInSheet=7|OwnerPartId=-1|Location.X=189|Location.Y=737|Color=8388608|FontID=1|IsHidden=T|Text=Flat|Name=Construction
|RECORD=41|OwnerIndex=387|IndexInSheet=8|OwnerPartId=-1|Location.X=189|Location.Y=737|Color=8388608|FontID=1|IsHidden=T|Text=0.8mm|Name=Height
|RECORD=41|OwnerIndex=387|IndexInSheet=9|OwnerPartId=-1|Location.X=189|Location.Y=737|Color=8388608|FontID=1|IsHidden=T|Text=85°C|Name=Max Operating Temperature
|RECORD=41|OwnerIndex=387|IndexInSheet=10|OwnerPartId=-1|Location.X=189|Location.Y=737|Color=8388608|FontID=1|IsHidden=T|Text=X5R|Name=Dielectric
|RECORD=41|OwnerIndex=387|IndexInSheet=11|OwnerPartId=-1|Location.X=189|Location.Y=737|Color=8388608|FontID=1|IsHidden=T|Text=1608|Name=Case Code (Metric)
|RECORD=41|OwnerIndex=387|IndexInSheet=12|OwnerPartId=-1|Location.X=189|Location.Y=737|Color=8388608|FontID=1|IsHidden=T|Text=16V|Name=Voltage Rating (DC)
|RECORD=41|OwnerIndex=387|IndexInSheet=13|OwnerPartId=-1|Location.X=189|Location.Y=737|Color=8388608|FontID=1|IsHidden=T|Text=0.031inch|Name=Width
|RECORD=41|OwnerIndex=387|IndexInSheet=14|OwnerPartId=-1|Location.X=189|Location.Y=737|Color=8388608|FontID=1|IsHidden=T|Text=16V|Name=Voltage Rating
|RECORD=41|OwnerIndex=387|IndexInSheet=15|OwnerPartId=-1|Location.X=189|Location.Y=737|Color=8388608|FontID=1|IsHidden=T|Text=0.063inch|Name=Length
|RECORD=41|OwnerIndex=387|IndexInSheet=16|OwnerPartId=-1|Location.X=189|Location.Y=737|Color=8388608|FontID=1|IsHidden=T|Text=Yes|Name=RoHS Compliant
|RECORD=41|OwnerIndex=387|IndexInSheet=17|OwnerPartId=-1|Location.X=189|Location.Y=737|Color=8388608|FontID=1|IsHidden=T|Text=Halogen Free|Name=Halogen Free
|RECORD=41|OwnerIndex=387|IndexInSheet=18|OwnerPartId=-1|Location.X=189|Location.Y=737|Color=8388608|FontID=1|IsHidden=T|Text=0603|Name=Case Code (Imperial)
|RECORD=41|OwnerIndex=387|IndexInSheet=19|OwnerPartId=-1|Location.X=189|Location.Y=737|Color=8388608|FontID=1|IsHidden=T|Text=10uF|Name=Capacitance
|RECORD=41|OwnerIndex=387|IndexInSheet=20|OwnerPartId=-1|Location.X=189|Location.Y=737|Color=8388608|FontID=1|IsHidden=T|Text=Surface Mount|Name=Mount
|RECORD=41|OwnerIndex=387|IndexInSheet=21|OwnerPartId=-1|Location.X=189|Location.Y=737|Color=8388608|FontID=1|IsHidden=T|Text=0.031inch|Name=Thickness
|RECORD=41|OwnerIndex=387|IndexInSheet=22|OwnerPartId=-1|Location.X=189|Location.Y=737|Color=8388608|FontID=1|IsHidden=T|Text=20%|Name=Tolerance
|RECORD=41|OwnerIndex=387|IndexInSheet=23|OwnerPartId=-1|Location.X=189|Location.Y=737|Color=8388608|FontID=1|IsHidden=T|Text=-55°C|Name=Min Operating Temperature
|RECORD=41|OwnerIndex=387|IndexInSheet=24|OwnerPartId=-1|Location.X=189|Location.Y=737|Color=8388608|FontID=1|IsHidden=T|Text=M|Name=Series
|RECORD=41|OwnerIndex=387|IndexInSheet=25|OwnerPartId=-1|Location.X=189|Location.Y=737|Color=8388608|FontID=1|IsHidden=T|Text=SMD/SMT|Name=Termination
|RECORD=41|OwnerIndex=387|IndexInSheet=26|OwnerPartId=-1|Location.X=189|Location.Y=737|Color=8388608|FontID=1|IsHidden=T|Text=0603|Name=Case/Package
|RECORD=41|OwnerIndex=387|IndexInSheet=27|OwnerPartId=-1|Location.X=189|Location.Y=737|Color=8388608|FontID=1|IsHidden=T|Text=1|Name=Package Quantity
|RECORD=34|OwnerIndex=387|IndexInSheet=-1|OwnerPartId=-1|Location.X=190|Location.Y=715|Orientation=1|Color=8388608|FontID=2|Text=C20|Name=Designator|ReadOnlyState=1
|RECORD=41|OwnerIndex=387|IndexInSheet=-1|OwnerPartId=1|Location.X=220|Location.Y=700|Orientation=1|Color=8388608|FontID=2|Text=10uF_16V_0603|Name=Comment
|RECORD=44|OwnerIndex=387
|RECORD=45|OwnerIndex=420|IndexInSheet=-1|UseComponentLibrary=T|ModelName=FP-0603-L_1_6_0_2-W_0_8_0-MFG|ModelType=PCBLIB|DatafileCount=1|ModelDatafileEntity0=FP-0603-L_1_6_0_2-W_0_8_0-MFG|ModelDatafileKind0=PCBLib|IsCurrent=T|DatalinksLocked=T|DatabaseDatalinksLocked=T
|RECORD=46|OwnerIndex=421
|RECORD=48|OwnerIndex=421
|RECORD=45|OwnerIndex=420|IndexInSheet=-1|UseComponentLibrary=T|ModelName=FP-0603-L_1_6_0_2-W_0_8_0-IPC_B|ModelType=PCBLIB|DatafileCount=1|ModelDatafileEntity0=FP-0603-L_1_6_0_2-W_0_8_0-IPC_B|ModelDatafileKind0=PCBLib|DatalinksLocked=T|DatabaseDatalinksLocked=T
|RECORD=46|OwnerIndex=424
|RECORD=48|OwnerIndex=424
|RECORD=45|OwnerIndex=420|IndexInSheet=-1|UseComponentLibrary=T|ModelName=FP-0603-L_1_6_0_2-W_0_8_0-IPC_C|ModelType=PCBLIB|DatafileCount=1|ModelDatafileEntity0=FP-0603-L_1_6_0_2-W_0_8_0-IPC_C|ModelDatafileKind0=PCBLib|DatalinksLocked=T|DatabaseDatalinksLocked=T
|RECORD=46|OwnerIndex=427
|RECORD=48|OwnerIndex=427
|RECORD=45|OwnerIndex=420|IndexInSheet=-1|UseComponentLibrary=T|ModelName=FP-0603-L_1_6_0_2-W_0_8_0-IPC_A|ModelType=PCBLIB|DatafileCount=1|ModelDatafileEntity0=FP-0603-L_1_6_0_2-W_0_8_0-IPC_A|ModelDatafileKind0=PCBLib|DatalinksLocked=T|DatabaseDatalinksLocked=T
|RECORD=46|OwnerIndex=430
|RECORD=48|OwnerIndex=430
|RECORD=17|IndexInSheet=52|OwnerPartId=-1|ShowNetName=T|Location.X=200|Location.Y=775|Orientation=1|Color=128|FontID=1|Text=+3.3V
|RECORD=17|IndexInSheet=53|OwnerPartId=-1|Style=4|ShowNetName=T|Location.X=200|Location.Y=705|Orientation=3|Color=128|FontID=1|Text=GND
|RECORD=17|IndexInSheet=54|OwnerPartId=-1|Style=4|ShowNetName=T|Location.X=240|Location.Y=705|Orientation=3|Color=128|FontID=1|Text=GND
|RECORD=17|IndexInSheet=55|OwnerPartId=-1|ShowNetName=T|Location.X=320|Location.Y=720|Orientation=1|Color=128|FontID=1|Text=+12V_SENS
|RECORD=17|IndexInSheet=56|OwnerPartId=-1|ShowNetName=T|Location.X=280|Location.Y=720|Orientation=1|Color=128|FontID=1|Text=+12V
|RECORD=17|IndexInSheet=57|OwnerPartId=-1|Style=4|ShowNetName=T|Location.X=480|Location.Y=680|Orientation=3|Color=128|FontID=1|Text=GND
|RECORD=17|IndexInSheet=58|OwnerPartId=-1|ShowNetName=T|Location.X=515|Location.Y=735|Color=255|FontID=1|Text=SENS_I2C_SCL|IsCrossSheetConnector=T
|RECORD=17|IndexInSheet=59|OwnerPartId=-1|ShowNetName=T|Location.X=515|Location.Y=755|Color=255|FontID=1|Text=SENS_I2C_SDA|IsCrossSheetConnector=T
|RECORD=1|LibReference=RES-2|ComponentDescription=Chip Resistor, 0 Ohm, 0.1 W, -55 to 155 degC, 0402 (1005 Metric), RoHS, Tape and Reel|PartCount=2|DisplayModeCount=1|IndexInSheet=60|OwnerPartId=-1|Location.X=500|Location.Y=715|CurrentPartId=1|LibraryPath=*|SourceLibraryName=Altium Content Vault|TargetFileName=*|AreaColor=11599871|Color=128|PartIDLocked=T|DesignItemId=CMP-2000-07451-1|AllPinCount=2
|RECORD=2|OwnerIndex=441|OwnerPartId=1|FormalType=1|Electrical=4|PinConglomerate=32|PinLength=10|Location.X=520|Location.Y=715|Name=2|Designator=2|PinPropagationDelay=0.000000E+000
|RECORD=2|OwnerIndex=441|OwnerPartId=1|FormalType=1|Electrical=4|PinConglomerate=34|PinLength=10|Location.X=500|Location.Y=715|Name=1|Designator=1|PinPropagationDelay=0.000000E+000
|RECORD=6|OwnerIndex=441|IsNotAccesible=T|IndexInSheet=2|OwnerPartId=1|LineWidth=1|Color=16711680|LocationCount=10|X1=520|Y1=715|X2=516|Y2=715|X3=515|Y3=713|X4=513|Y4=717|X5=511|Y5=713|X6=509|Y6=717|X7=507|Y7=713|X8=505|Y8=717|X9=504|Y9=715|X10=500|Y10=715
|RECORD=41|OwnerIndex=441|IndexInSheet=3|OwnerPartId=-1|Location.X=488|Location.Y=730|Color=8388608|FontID=1|IsHidden=T|Text=50V|Name=Voltage Rating (DC)
|RECORD=41|OwnerIndex=441|IndexInSheet=4|OwnerPartId=-1|Location.X=488|Location.Y=730|Color=8388608|FontID=1|IsHidden=T|Text=2|Name=Number of Terminations
|RECORD=41|OwnerIndex=441|IndexInSheet=5|OwnerPartId=-1|Location.X=488|Location.Y=730|Color=8388608|FontID=1|IsHidden=T|Text=SurfaceMount|Name=Mount
|RECORD=41|OwnerIndex=441|IndexInSheet=6|OwnerPartId=-1|Location.X=488|Location.Y=730|Color=8388608|FontID=1|IsHidden=T|Text=0.35mm|Name=Height
|RECORD=41|OwnerIndex=441|IndexInSheet=7|OwnerPartId=-1|Location.X=488|Location.Y=730|Color=8388608|FontID=1|IsHidden=T|Text=TapeandReel|Name=Packaging
|RECORD=41|OwnerIndex=441|IndexInSheet=8|OwnerPartId=-1|Location.X=488|Location.Y=730|Color=8388608|FontID=1|IsHidden=T|Text=Tin|Name=Contact Plating
|RECORD=41|OwnerIndex=441|IndexInSheet=9|OwnerPartId=-1|Location.X=488|Location.Y=730|Color=8388608|FontID=3|IsHidden=T|Text=http://www.panasonic.com/|Name=Manufacturer URL
|RECORD=41|OwnerIndex=441|IndexInSheet=10|OwnerPartId=-1|Location.X=488|Location.Y=730|Color=8388608|FontID=1|IsHidden=T|Text=ThickFilm|Name=Composition
|RECORD=41|OwnerIndex=441|IndexInSheet=11|OwnerPartId=-1|Location.X=488|Location.Y=730|Color=8388608|FontID=1|IsHidden=T|Text=155degC|Name=Max Operating Temperature
|RECORD=41|OwnerIndex=441|IndexInSheet=12|OwnerPartId=-1|Location.X=488|Location.Y=730|Color=8388608|FontID=1|IsHidden=T|Text=600ppm/??C|Name=Temperature Coefficient
|RECORD=41|OwnerIndex=441|IndexInSheet=13|OwnerPartId=-1|Location.X=488|Location.Y=730|Color=8388608|FontID=1|IsHidden=T|Text=NoSVHC|Name=REACH SVHC
|RECORD=41|OwnerIndex=441|IndexInSheet=14|OwnerPartId=-1|Location.X=488|Location.Y=730|Color=8388608|FontID=1|IsHidden=T|Text=0402|Name=Case/Package
|RECORD=41|OwnerIndex=441|IndexInSheet=15|OwnerPartId=-1|Location.X=488|Location.Y=730|Color=8388608|FontID=1|IsHidden=T|Text=100mW|Name=Max Power Dissipation
|RECORD=41|OwnerIndex=441|IndexInSheet=16|OwnerPartId=-1|Location.X=488|Location.Y=730|Color=8388608|FontID=1|IsHidden=T|Text=402|Name=Package Reference
|RECORD=41|OwnerIndex=441|IndexInSheet=17|OwnerPartId=-1|Location.X=488|Location.Y=730|Color=8388608|FontID=1|IsHidden=T|Text=0.5mm|Name=Depth
|RECORD=41|OwnerIndex=441|IndexInSheet=18|OwnerPartId=-1|Location.X=488|Location.Y=730|Color=8388608|FontID=1|IsHidden=T|Text=Panasonic|Name=Manufacturer
|RECORD=41|OwnerIndex=441|IndexInSheet=19|OwnerPartId=-1|Location.X=488|Location.Y=730|Color=8388608|FontID=1|IsHidden=T|Text=2-Pin Surface Mount Device, Body 1 x 0.5 mm|Name=Package Description
|RECORD=41|OwnerIndex=441|IndexInSheet=20|OwnerPartId=-1|Location.X=488|Location.Y=730|Color=8388608|FontID=3|IsHidden=T|Text=https://industrial.panasonic.com/cdbs/www-data/pdf/RDA0000/AOA0000C301.pdf|Name=Datasheet URL
|RECORD=41|OwnerIndex=441|IndexInSheet=21|OwnerPartId=-1|Location.X=488|Location.Y=730|Color=8388608|FontID=1|IsHidden=T|Text=True|Name=RoHSCompliant
|RECORD=41|OwnerIndex=441|IndexInSheet=22|OwnerPartId=-1|Location.X=488|Location.Y=730|Color=8388608|FontID=1|IsHidden=T|Text=0402|Name=Case Code (Imperial)
|RECORD=41|OwnerIndex=441|IndexInSheet=23|OwnerPartId=-1|Location.X=488|Location.Y=730|Color=8388608|FontID=1|IsHidden=T|Text=0mOhm|Name=Resistance
|RECORD=41|OwnerIndex=441|IndexInSheet=24|OwnerPartId=-1|Location.X=488|Location.Y=730|Color=8388608|FontID=1|IsHidden=T|Text=Not|Name=Military Standard
|RECORD=41|OwnerIndex=441|IndexInSheet=25|OwnerPartId=-1|Location.X=488|Location.Y=730|Color=8388608|FontID=1|IsHidden=T|Text=5%|Name=Tolerance
|RECORD=41|OwnerIndex=441|IndexInSheet=26|OwnerPartId=-1|Location.X=488|Location.Y=730|Color=8388608|FontID=1|IsHidden=T|Text=-55degC|Name=Min Operating Temperature
|RECORD=41|OwnerIndex=441|IndexInSheet=27|OwnerPartId=-1|Location.X=488|Location.Y=730|Color=8388608|FontID=1|IsHidden=T|Text=100mW|Name=Power Rating
|RECORD=41|OwnerIndex=441|IndexInSheet=28|OwnerPartId=-1|Location.X=488|Location.Y=730|Color=8388608|FontID=1|IsHidden=T|Text=03/2015|Name=Datasheet Version
|RECORD=41|OwnerIndex=441|IndexInSheet=29|OwnerPartId=-1|Location.X=488|Location.Y=730|Color=8388608|FontID=1|IsHidden=T|Text=1mm|Name=Length
|RECORD=41|OwnerIndex=441|IndexInSheet=30|OwnerPartId=-1|Location.X=488|Location.Y=730|Color=8388608|FontID=1|IsHidden=T|Text=1005|Name=Case Code (Metric)
|RECORD=41|OwnerIndex=441|IndexInSheet=31|OwnerPartId=-1|Location.X=488|Location.Y=730|Color=8388608|FontID=1|IsHidden=T|Text=SMD/SMT|Name=Termination
|RECORD=41|OwnerIndex=441|IndexInSheet=32|OwnerPartId=-1|Location.X=488|Location.Y=730|Color=8388608|FontID=1|IsHidden=T|Text=SurfaceMount|Name=Mounting Technology
|RECORD=41|OwnerIndex=441|IndexInSheet=33|OwnerPartId=-1|Location.X=488|Location.Y=730|Color=8388608|FontID=1|IsHidden=T|Text=50V|Name=Voltage Rating
|RECORD=41|OwnerIndex=441|IndexInSheet=34|OwnerPartId=-1|Location.X=488|Location.Y=730|Color=8388608|FontID=1|IsHidden=T|Text=0.02inch|Name=Width
|RECORD=41|OwnerIndex=441|IndexInSheet=35|OwnerPartId=-1|Location.X=488|Location.Y=730|Color=8388608|FontID=1|IsHidden=T|Text=1|Name=Package Quantity
|RECORD=41|OwnerIndex=441|IndexInSheet=36|OwnerPartId=-1|Location.X=488|Location.Y=730|Color=8388608|FontID=1|IsHidden=T|Text=LeadFree|Name=Lead Free
|RECORD=41|OwnerIndex=441|IndexInSheet=37|OwnerPartId=-1|Location.X=488|Location.Y=730|Color=8388608|FontID=1|IsHidden=T|Text=No|Name=Radiation Hardening
|RECORD=34|OwnerIndex=441|IndexInSheet=-1|OwnerPartId=-1|Location.X=480|Location.Y=715|Color=8388608|FontID=1|Text=R62|Name=Designator|ReadOnlyState=1
|RECORD=41|OwnerIndex=441|IndexInSheet=-1|OwnerPartId=-1|Location.X=520|Location.Y=715|Color=8388608|FontID=1|Text=0_1%_0402|Name=Comment
|RECORD=44|OwnerIndex=441
|RECORD=45|OwnerIndex=484|IndexInSheet=-1|Description=Chip Resistor, 2-Leads, Body 1.05x0.55mm, IPC High Density|UseComponentLibrary=T|ModelName=RESC1005X40X25LL05T05|ModelType=PCBLIB|DatafileCount=1|ModelDatafileEntity0=RESC1005X40X25LL05T05|ModelDatafileKind0=PCBLib|IsCurrent=T|DatalinksLocked=T|DatabaseDatalinksLocked=T
|RECORD=46|OwnerIndex=485
|RECORD=48|OwnerIndex=485
|RECORD=41|OwnerIndex=487|IndexInSheet=-1|OwnerPartId=-1|Color=8388608|FontID=1|IsHidden=T|Text=2D|Name=Available Preview Images
|RECORD=45|OwnerIndex=484|IndexInSheet=-1|Description=Chip Resistor, 2-Leads, Body 1.05x0.55mm, IPC Low Density|UseComponentLibrary=T|ModelName=RESC1005X40X25ML05T05|ModelType=PCBLIB|DatafileCount=1|ModelDatafileEntity0=RESC1005X40X25ML05T05|ModelDatafileKind0=PCBLib|DatalinksLocked=T|DatabaseDatalinksLocked=T
|RECORD=46|OwnerIndex=489
|RECORD=48|OwnerIndex=489
|RECORD=41|OwnerIndex=491|IndexInSheet=-1|OwnerPartId=-1|Color=8388608|FontID=1|IsHidden=T|Text=2D|Name=Available Preview Images
|RECORD=45|OwnerIndex=484|IndexInSheet=-1|Description=Chip Resistor, 2-Leads, Body 1.05x0.55mm, IPC Medium Density|UseComponentLibrary=T|ModelName=RESC1005X40X25NL05T05|ModelType=PCBLIB|DatafileCount=1|ModelDatafileEntity0=RESC1005X40X25NL05T05|ModelDatafileKind0=PCBLib|DatalinksLocked=T|DatabaseDatalinksLocked=T
|RECORD=46|OwnerIndex=493
|RECORD=48|OwnerIndex=493
|RECORD=41|OwnerIndex=495|IndexInSheet=-1|OwnerPartId=-1|Color=8388608|FontID=1|IsHidden=T|Text=2D|Name=Available Preview Images
|RECORD=1|LibReference=RES-2|ComponentDescription=Chip Resistor, 0 Ohm, 0.1 W, -55 to 155 degC, 0402 (1005 Metric), RoHS, Tape and Reel|PartCount=2|DisplayModeCount=1|IndexInSheet=61|OwnerPartId=-1|Location.X=500|Location.Y=705|CurrentPartId=1|LibraryPath=*|SourceLibraryName=Altium Content Vault|TargetFileName=*|AreaColor=11599871|Color=128|PartIDLocked=T|DesignItemId=CMP-2000-07451-1|AllPinCount=2
|RECORD=2|OwnerIndex=497|OwnerPartId=1|FormalType=1|Electrical=4|PinConglomerate=32|PinLength=10|Location.X=520|Location.Y=705|Name=2|Designator=2|PinPropagationDelay=0.000000E+000
|RECORD=2|OwnerIndex=497|OwnerPartId=1|FormalType=1|Electrical=4|PinConglomerate=34|PinLength=10|Location.X=500|Location.Y=705|Name=1|Designator=1|PinPropagationDelay=0.000000E+000
|RECORD=6|OwnerIndex=497|IsNotAccesible=T|IndexInSheet=2|OwnerPartId=1|LineWidth=1|Color=16711680|LocationCount=10|X1=520|Y1=705|X2=516|Y2=705|X3=515|Y3=703|X4=513|Y4=707|X5=511|Y5=703|X6=509|Y6=707|X7=507|Y7=703|X8=505|Y8=707|X9=504|Y9=705|X10=500|Y10=705
|RECORD=41|OwnerIndex=497|IndexInSheet=3|OwnerPartId=-1|Location.X=488|Location.Y=720|Color=8388608|FontID=1|IsHidden=T|Text=50V|Name=Voltage Rating (DC)
|RECORD=41|OwnerIndex=497|IndexInSheet=4|OwnerPartId=-1|Location.X=488|Location.Y=720|Color=8388608|FontID=1|IsHidden=T|Text=2|Name=Number of Terminations
|RECORD=41|OwnerIndex=497|IndexInSheet=5|OwnerPartId=-1|Location.X=488|Location.Y=720|Color=8388608|FontID=1|IsHidden=T|Text=SurfaceMount|Name=Mount
|RECORD=41|OwnerIndex=497|IndexInSheet=6|OwnerPartId=-1|Location.X=488|Location.Y=720|Color=8388608|FontID=1|IsHidden=T|Text=0.35mm|Name=Height
|RECORD=41|OwnerIndex=497|IndexInSheet=7|OwnerPartId=-1|Location.X=488|Location.Y=720|Color=8388608|FontID=1|IsHidden=T|Text=TapeandReel|Name=Packaging
|RECORD=41|OwnerIndex=497|IndexInSheet=8|OwnerPartId=-1|Location.X=488|Location.Y=720|Color=8388608|FontID=1|IsHidden=T|Text=Tin|Name=Contact Plating
|RECORD=41|OwnerIndex=497|IndexInSheet=9|OwnerPartId=-1|Location.X=488|Location.Y=720|Color=8388608|FontID=3|IsHidden=T|Text=http://www.panasonic.com/|Name=Manufacturer URL
|RECORD=41|OwnerIndex=497|IndexInSheet=10|OwnerPartId=-1|Location.X=488|Location.Y=720|Color=8388608|FontID=1|IsHidden=T|Text=ThickFilm|Name=Composition
|RECORD=41|OwnerIndex=497|IndexInSheet=11|OwnerPartId=-1|Location.X=488|Location.Y=720|Color=8388608|FontID=1|IsHidden=T|Text=155degC|Name=Max Operating Temperature
|RECORD=41|OwnerIndex=497|IndexInSheet=12|OwnerPartId=-1|Location.X=488|Location.Y=720|Color=8388608|FontID=1|IsHidden=T|Text=600ppm/??C|Name=Temperature Coefficient
|RECORD=41|OwnerIndex=497|IndexInSheet=13|OwnerPartId=-1|Location.X=488|Location.Y=720|Color=8388608|FontID=1|IsHidden=T|Text=NoSVHC|Name=REACH SVHC
|RECORD=41|OwnerIndex=497|IndexInSheet=14|OwnerPartId=-1|Location.X=488|Location.Y=720|Color=8388608|FontID=1|IsHidden=T|Text=0402|Name=Case/Package
|RECORD=41|OwnerIndex=497|IndexInSheet=15|OwnerPartId=-1|Location.X=488|Location.Y=720|Color=8388608|FontID=1|IsHidden=T|Text=100mW|Name=Max Power Dissipation
|RECORD=41|OwnerIndex=497|IndexInSheet=16|OwnerPartId=-1|Location.X=488|Location.Y=720|Color=8388608|FontID=1|IsHidden=T|Text=402|Name=Package Reference
|RECORD=41|OwnerIndex=497|IndexInSheet=17|OwnerPartId=-1|Location.X=488|Location.Y=720|Color=8388608|FontID=1|IsHidden=T|Text=0.5mm|Name=Depth
|RECORD=41|OwnerIndex=497|IndexInSheet=18|OwnerPartId=-1|Location.X=488|Location.Y=720|Color=8388608|FontID=1|IsHidden=T|Text=Panasonic|Name=Manufacturer
|RECORD=41|OwnerIndex=497|IndexInSheet=19|OwnerPartId=-1|Location.X=488|Location.Y=720|Color=8388608|FontID=1|IsHidden=T|Text=2-Pin Surface Mount Device, Body 1 x 0.5 mm|Name=Package Description
|RECORD=41|OwnerIndex=497|IndexInSheet=20|OwnerPartId=-1|Location.X=488|Location.Y=720|Color=8388608|FontID=3|IsHidden=T|Text=https://industrial.panasonic.com/cdbs/www-data/pdf/RDA0000/AOA0000C301.pdf|Name=Datasheet URL
|RECORD=41|OwnerIndex=497|IndexInSheet=21|OwnerPartId=-1|Location.X=488|Location.Y=720|Color=8388608|FontID=1|IsHidden=T|Text=True|Name=RoHSCompliant
|RECORD=41|OwnerIndex=497|IndexInSheet=22|OwnerPartId=-1|Location.X=488|Location.Y=720|Color=8388608|FontID=1|IsHidden=T|Text=0402|Name=Case Code (Imperial)
|RECORD=41|OwnerIndex=497|IndexInSheet=23|OwnerPartId=-1|Location.X=488|Location.Y=720|Color=8388608|FontID=1|IsHidden=T|Text=0mOhm|Name=Resistance
|RECORD=41|OwnerIndex=497|IndexInSheet=24|OwnerPartId=-1|Location.X=488|Location.Y=720|Color=8388608|FontID=1|IsHidden=T|Text=Not|Name=Military Standard
|RECORD=41|OwnerIndex=497|IndexInSheet=25|OwnerPartId=-1|Location.X=488|Location.Y=720|Color=8388608|FontID=1|IsHidden=T|Text=5%|Name=Tolerance
|RECORD=41|OwnerIndex=497|IndexInSheet=26|OwnerPartId=-1|Location.X=488|Location.Y=720|Color=8388608|FontID=1|IsHidden=T|Text=-55degC|Name=Min Operating Temperature
|RECORD=41|OwnerIndex=497|IndexInSheet=27|OwnerPartId=-1|Location.X=488|Location.Y=720|Color=8388608|FontID=1|IsHidden=T|Text=100mW|Name=Power Rating
|RECORD=41|OwnerIndex=497|IndexInSheet=28|OwnerPartId=-1|Location.X=488|Location.Y=720|Color=8388608|FontID=1|IsHidden=T|Text=03/2015|Name=Datasheet Version
|RECORD=41|OwnerIndex=497|IndexInSheet=29|OwnerPartId=-1|Location.X=488|Location.Y=720|Color=8388608|FontID=1|IsHidden=T|Text=1mm|Name=Length
|RECORD=41|OwnerIndex=497|IndexInSheet=30|OwnerPartId=-1|Location.X=488|Location.Y=720|Color=8388608|FontID=1|IsHidden=T|Text=1005|Name=Case Code (Metric)
|RECORD=41|OwnerIndex=497|IndexInSheet=31|OwnerPartId=-1|Location.X=488|Location.Y=720|Color=8388608|FontID=1|IsHidden=T|Text=SMD/SMT|Name=Termination
|RECORD=41|OwnerIndex=497|IndexInSheet=32|OwnerPartId=-1|Location.X=488|Location.Y=720|Color=8388608|FontID=1|IsHidden=T|Text=SurfaceMount|Name=Mounting Technology
|RECORD=41|OwnerIndex=497|IndexInSheet=33|OwnerPartId=-1|Location.X=488|Location.Y=720|Color=8388608|FontID=1|IsHidden=T|Text=50V|Name=Voltage Rating
|RECORD=41|OwnerIndex=497|IndexInSheet=34|OwnerPartId=-1|Location.X=488|Location.Y=720|Color=8388608|FontID=1|IsHidden=T|Text=0.02inch|Name=Width
|RECORD=41|OwnerIndex=497|IndexInSheet=35|OwnerPartId=-1|Location.X=488|Location.Y=720|Color=8388608|FontID=1|IsHidden=T|Text=1|Name=Package Quantity
|RECORD=41|OwnerIndex=497|IndexInSheet=36|OwnerPartId=-1|Location.X=488|Location.Y=720|Color=8388608|FontID=1|IsHidden=T|Text=LeadFree|Name=Lead Free
|RECORD=41|OwnerIndex=497|IndexInSheet=37|OwnerPartId=-1|Location.X=488|Location.Y=720|Color=8388608|FontID=1|IsHidden=T|Text=No|Name=Radiation Hardening
|RECORD=34|OwnerIndex=497|IndexInSheet=-1|OwnerPartId=-1|Location.X=480|Location.Y=705|Color=8388608|FontID=1|Text=R64|Name=Designator|ReadOnlyState=1
|RECORD=41|OwnerIndex=497|IndexInSheet=-1|OwnerPartId=-1|Location.X=520|Location.Y=705|Color=8388608|FontID=1|Text=0_1%_0402|Name=Comment
|RECORD=44|OwnerIndex=497
|RECORD=45|OwnerIndex=540|IndexInSheet=-1|Description=Chip Resistor, 2-Leads, Body 1.05x0.55mm, IPC High Density|UseComponentLibrary=T|ModelName=RESC1005X40X25LL05T05|ModelType=PCBLIB|DatafileCount=1|ModelDatafileEntity0=RESC1005X40X25LL05T05|ModelDatafileKind0=PCBLib|IsCurrent=T|DatalinksLocked=T|DatabaseDatalinksLocked=T
|RECORD=46|OwnerIndex=541
|RECORD=48|OwnerIndex=541
|RECORD=41|OwnerIndex=543|IndexInSheet=-1|OwnerPartId=-1|Color=8388608|FontID=1|IsHidden=T|Text=2D|Name=Available Preview Images
|RECORD=45|OwnerIndex=540|IndexInSheet=-1|Description=Chip Resistor, 2-Leads, Body 1.05x0.55mm, IPC Low Density|UseComponentLibrary=T|ModelName=RESC1005X40X25ML05T05|ModelType=PCBLIB|DatafileCount=1|ModelDatafileEntity0=RESC1005X40X25ML05T05|ModelDatafileKind0=PCBLib|DatalinksLocked=T|DatabaseDatalinksLocked=T
|RECORD=46|OwnerIndex=545
|RECORD=48|OwnerIndex=545
|RECORD=41|OwnerIndex=547|IndexInSheet=-1|OwnerPartId=-1|Color=8388608|FontID=1|IsHidden=T|Text=2D|Name=Available Preview Images
|RECORD=45|OwnerIndex=540|IndexInSheet=-1|Description=Chip Resistor, 2-Leads, Body 1.05x0.55mm, IPC Medium Density|UseComponentLibrary=T|ModelName=RESC1005X40X25NL05T05|ModelType=PCBLIB|DatafileCount=1|ModelDatafileEntity0=RESC1005X40X25NL05T05|ModelDatafileKind0=PCBLib|DatalinksLocked=T|DatabaseDatalinksLocked=T
|RECORD=46|OwnerIndex=549
|RECORD=48|OwnerIndex=549
|RECORD=41|OwnerIndex=551|IndexInSheet=-1|OwnerPartId=-1|Color=8388608|FontID=1|IsHidden=T|Text=2D|Name=Available Preview Images
|RECORD=4|IndexInSheet=62|OwnerPartId=-1|Location.X=380|Location.Y=785|Color=8388608|FontID=1|Text=Address 0x40
|RECORD=17|IndexInSheet=63|OwnerPartId=-1|ShowNetName=T|Location.X=675|Location.Y=970|Orientation=1|Color=128|FontID=1|Text=+12V
|RECORD=1|LibReference=02cd4be3c70576c341d710602a673aa|ComponentDescription=Chip Multilayer Ceramic Capacitors for General Purpose, 1206, 4.7uF, X7R, 15%, 10%, 50V|PartCount=2|DisplayModeCount=1|IndexInSheet=64|OwnerPartId=-1|Location.X=725|Location.Y=925|CurrentPartId=1|LibraryPath=*|SourceLibraryName=Altium Content Vault|TargetFileName=*|AreaColor=11599871|Color=128|PartIDLocked=T|DesignItemId=CMP-1037-04923-3|AllPinCount=2
|RECORD=2|OwnerIndex=555|OwnerPartId=1|Electrical=4|PinConglomerate=49|PinLength=7|Location.X=725|Location.Y=918|Name=1|Designator=1|PinPropagationDelay=0.000000E+000
|RECORD=2|OwnerIndex=555|OwnerPartId=1|Electrical=4|PinConglomerate=51|PinLength=6|Location.X=725|Location.Y=911|Name=2|Designator=2|PinPropagationDelay=0.000000E+000
|RECORD=13|OwnerIndex=555|IsNotAccesible=T|IndexInSheet=2|OwnerPartId=1|Location.X=735|Location.Y=918|Corner.X=715|Corner.Y=918|LineWidth=1|Color=16711680
|RECORD=13|OwnerIndex=555|IsNotAccesible=T|IndexInSheet=3|OwnerPartId=1|Location.X=735|Location.Y=912|Corner.X=715|Corner.Y=912|LineWidth=1|Color=16711680
|RECORD=13|OwnerIndex=555|IsNotAccesible=T|IndexInSheet=4|OwnerPartId=1|Location.X=725|Location.Y=918|Corner.X=725|Corner.Y=921|LineWidth=1|Color=16711680
|RECORD=13|OwnerIndex=555|IsNotAccesible=T|IndexInSheet=5|OwnerPartId=1|Location.X=725|Location.Y=911|Corner.X=725|Corner.Y=910|LineWidth=1|Color=16711680
|RECORD=41|OwnerIndex=555|IndexInSheet=6|OwnerPartId=-1|Location.X=714|Location.Y=927|Color=8388608|FontID=1|IsHidden=T|Text=1.6mm|Name=Height
|RECORD=41|OwnerIndex=555|IndexInSheet=7|OwnerPartId=-1|Location.X=714|Location.Y=927|Color=8388608|FontID=1|IsHidden=T|Text=50V|Name=Voltage
|RECORD=41|OwnerIndex=555|IndexInSheet=8|OwnerPartId=-1|Location.X=714|Location.Y=927|Color=8388608|FontID=1|IsHidden=T|Text=4.7uF|Name=Capacitance
|RECORD=41|OwnerIndex=555|IndexInSheet=9|OwnerPartId=-1|Location.X=714|Location.Y=927|Color=8388608|FontID=1|IsHidden=T|Text=Lead Free|Name=Lead Free
|RECORD=41|OwnerIndex=555|IndexInSheet=10|OwnerPartId=-1|Location.X=714|Location.Y=927|Color=8388608|FontID=1|IsHidden=T|Text=125°C|Name=Max Operating Temperature
|RECORD=41|OwnerIndex=555|IndexInSheet=11|OwnerPartId=-1|Location.X=714|Location.Y=927|Color=8388608|FontID=1|IsHidden=T|Text=Tape and Reel|Name=Packaging
|RECORD=41|OwnerIndex=555|IndexInSheet=12|OwnerPartId=-1|Location.X=714|Location.Y=927|Color=8388608|FontID=1|IsHidden=T|Text=No SVHC|Name=REACH SVHC
|RECORD=41|OwnerIndex=555|IndexInSheet=13|OwnerPartId=-1|Location.X=714|Location.Y=927|Color=8388608|FontID=1|IsHidden=T|Text=50V|Name=Voltage Rating
|RECORD=41|OwnerIndex=555|IndexInSheet=14|OwnerPartId=-1|Location.X=714|Location.Y=927|Color=8388608|FontID=1|IsHidden=T|Text=Surface Mount|Name=Mount
|RECORD=41|OwnerIndex=555|IndexInSheet=15|OwnerPartId=-1|Location.X=714|Location.Y=927|Color=8388608|FontID=1|IsHidden=T|Text=SMD/SMT|Name=Termination
|RECORD=41|OwnerIndex=555|IndexInSheet=16|OwnerPartId=-1|Location.X=714|Location.Y=927|Color=8388608|FontID=1|IsHidden=T|Text=10%|Name=Tolerance
|RECORD=41|OwnerIndex=555|IndexInSheet=17|OwnerPartId=-1|Location.X=714|Location.Y=927|Color=8388608|FontID=1|IsHidden=T|Text=1206|Name=Case/Package
|RECORD=41|OwnerIndex=555|IndexInSheet=18|OwnerPartId=-1|Location.X=714|Location.Y=927|Color=8388608|FontID=1|IsHidden=T|Text=Ceramic|Name=Material
|RECORD=41|OwnerIndex=555|IndexInSheet=19|OwnerPartId=-1|Location.X=714|Location.Y=927|Color=8388608|FontID=1|IsHidden=T|Text=1.6mm|Name=Depth
|RECORD=41|OwnerIndex=555|IndexInSheet=20|OwnerPartId=-1|Location.X=714|Location.Y=927|Color=8388608|FontID=1|IsHidden=T|Text=3.2mm|Name=Length
|RECORD=41|OwnerIndex=555|IndexInSheet=21|OwnerPartId=-1|Location.X=714|Location.Y=927|Color=8388608|FontID=1|IsHidden=T|Text=3216|Name=Case Code (Metric)
|RECORD=41|OwnerIndex=555|IndexInSheet=22|OwnerPartId=-1|Location.X=714|Location.Y=927|Color=8388608|FontID=1|IsHidden=T|Text=50V|Name=Voltage Rating (DC)
|RECORD=41|OwnerIndex=555|IndexInSheet=23|OwnerPartId=-1|Location.X=714|Location.Y=927|Color=8388608|FontID=1|IsHidden=T|Text=1206|Name=Case Code (Imperial)
|RECORD=41|OwnerIndex=555|IndexInSheet=24|OwnerPartId=-1|Location.X=714|Location.Y=927|Color=8388608|FontID=1|IsHidden=T|Text=No|Name=Radiation Hardening
|RECORD=41|OwnerIndex=555|IndexInSheet=25|OwnerPartId=-1|Location.X=714|Location.Y=927|Color=8388608|FontID=1|IsHidden=T|Text=0.063inch|Name=Width
|RECORD=41|OwnerIndex=555|IndexInSheet=26|OwnerPartId=-1|Location.X=714|Location.Y=927|Color=8388608|FontID=1|IsHidden=T|Text=0.071inch|Name=Thickness
|RECORD=41|OwnerIndex=555|IndexInSheet=27|OwnerPartId=-1|Location.X=714|Location.Y=927|Color=8388608|FontID=1|IsHidden=T|Text=2000|Name=Package Quantity
|RECORD=41|OwnerIndex=555|IndexInSheet=28|OwnerPartId=-1|Location.X=714|Location.Y=927|Color=8388608|FontID=1|IsHidden=T|Text=-55°C|Name=Min Operating Temperature
|RECORD=41|OwnerIndex=555|IndexInSheet=29|OwnerPartId=-1|Location.X=714|Location.Y=927|Color=8388608|FontID=1|IsHidden=T|Text=X7R|Name=Dielectric
|RECORD=34|OwnerIndex=555|IndexInSheet=-1|OwnerPartId=-1|Location.X=715|Location.Y=905|Orientation=1|Color=8388608|FontID=2|Text=C11|Name=Designator|ReadOnlyState=1
|RECORD=41|OwnerIndex=555|IndexInSheet=-1|OwnerPartId=1|Location.X=745|Location.Y=890|Orientation=1|Color=8388608|FontID=2|Text=4.7uF_50V_1206|Name=Comment
|RECORD=44|OwnerIndex=555
|RECORD=45|OwnerIndex=590|IndexInSheet=-1|UseComponentLibrary=T|ModelName=FP-GRM31C-0_2-e0_3_0_8-IPC_C|ModelType=PCBLIB|DatafileCount=1|ModelDatafileEntity0=FP-GRM31C-0_2-e0_3_0_8-IPC_C|ModelDatafileKind0=PCBLib|IsCurrent=T|DatalinksLocked=T|DatabaseDatalinksLocked=T
|RECORD=46|OwnerIndex=591
|RECORD=48|OwnerIndex=591
|RECORD=45|OwnerIndex=590|IndexInSheet=-1|UseComponentLibrary=T|ModelName=FP-GRM31C-0_2-e0_3_0_8-IPC_B|ModelType=PCBLIB|DatafileCount=1|ModelDatafileEntity0=FP-GRM31C-0_2-e0_3_0_8-IPC_B|ModelDatafileKind0=PCBLib|DatalinksLocked=T|DatabaseDatalinksLocked=T
|RECORD=46|OwnerIndex=594
|RECORD=48|OwnerIndex=594
|RECORD=45|OwnerIndex=590|IndexInSheet=-1|UseComponentLibrary=T|ModelName=FP-GRM31C-0_2-e0_3_0_8-IPC_A|ModelType=PCBLIB|DatafileCount=1|ModelDatafileEntity0=FP-GRM31C-0_2-e0_3_0_8-IPC_A|ModelDatafileKind0=PCBLib|DatalinksLocked=T|DatabaseDatalinksLocked=T
|RECORD=46|OwnerIndex=597
|RECORD=48|OwnerIndex=597
|RECORD=45|OwnerIndex=590|IndexInSheet=-1|UseComponentLibrary=T|ModelName=FP-GRM31C-0_2-e0_3_0_8-MFG|ModelType=PCBLIB|DatafileCount=1|ModelDatafileEntity0=FP-GRM31C-0_2-e0_3_0_8-MFG|ModelDatafileKind0=PCBLib|DatalinksLocked=T|DatabaseDatalinksLocked=T
|RECORD=46|OwnerIndex=600
|RECORD=48|OwnerIndex=600
|RECORD=1|LibReference=02cd4be3c70576c341d710602a673aa|ComponentDescription=Chip Multilayer Ceramic Capacitors for General Purpose, 1206, 4.7uF, X7R, 15%, 10%, 50V|PartCount=2|DisplayModeCount=1|IndexInSheet=65|OwnerPartId=-1|Location.X=765|Location.Y=925|CurrentPartId=1|LibraryPath=*|SourceLibraryName=Altium Content Vault|TargetFileName=*|AreaColor=11599871|Color=128|PartIDLocked=T|DesignItemId=CMP-1037-04923-3|AllPinCount=2
|RECORD=2|OwnerIndex=603|OwnerPartId=1|Electrical=4|PinConglomerate=49|PinLength=7|Location.X=765|Location.Y=918|Name=1|Designator=1|PinPropagationDelay=0.000000E+000
|RECORD=2|OwnerIndex=603|OwnerPartId=1|Electrical=4|PinConglomerate=51|PinLength=6|Location.X=765|Location.Y=911|Name=2|Designator=2|PinPropagationDelay=0.000000E+000
|RECORD=13|OwnerIndex=603|IsNotAccesible=T|IndexInSheet=2|OwnerPartId=1|Location.X=775|Location.Y=918|Corner.X=755|Corner.Y=918|LineWidth=1|Color=16711680
|RECORD=13|OwnerIndex=603|IsNotAccesible=T|IndexInSheet=3|OwnerPartId=1|Location.X=775|Location.Y=912|Corner.X=755|Corner.Y=912|LineWidth=1|Color=16711680
|RECORD=13|OwnerIndex=603|IsNotAccesible=T|IndexInSheet=4|OwnerPartId=1|Location.X=765|Location.Y=918|Corner.X=765|Corner.Y=921|LineWidth=1|Color=16711680
|RECORD=13|OwnerIndex=603|IsNotAccesible=T|IndexInSheet=5|OwnerPartId=1|Location.X=765|Location.Y=911|Corner.X=765|Corner.Y=910|LineWidth=1|Color=16711680
|RECORD=41|OwnerIndex=603|IndexInSheet=6|OwnerPartId=-1|Location.X=754|Location.Y=927|Color=8388608|FontID=1|IsHidden=T|Text=1.6mm|Name=Height
|RECORD=41|OwnerIndex=603|IndexInSheet=7|OwnerPartId=-1|Location.X=754|Location.Y=927|Color=8388608|FontID=1|IsHidden=T|Text=50V|Name=Voltage
|RECORD=41|OwnerIndex=603|IndexInSheet=8|OwnerPartId=-1|Location.X=754|Location.Y=927|Color=8388608|FontID=1|IsHidden=T|Text=4.7uF|Name=Capacitance
|RECORD=41|OwnerIndex=603|IndexInSheet=9|OwnerPartId=-1|Location.X=754|Location.Y=927|Color=8388608|FontID=1|IsHidden=T|Text=Lead Free|Name=Lead Free
|RECORD=41|OwnerIndex=603|IndexInSheet=10|OwnerPartId=-1|Location.X=754|Location.Y=927|Color=8388608|FontID=1|IsHidden=T|Text=125°C|Name=Max Operating Temperature
|RECORD=41|OwnerIndex=603|IndexInSheet=11|OwnerPartId=-1|Location.X=754|Location.Y=927|Color=8388608|FontID=1|IsHidden=T|Text=Tape and Reel|Name=Packaging
|RECORD=41|OwnerIndex=603|IndexInSheet=12|OwnerPartId=-1|Location.X=754|Location.Y=927|Color=8388608|FontID=1|IsHidden=T|Text=No SVHC|Name=REACH SVHC
|RECORD=41|OwnerIndex=603|IndexInSheet=13|OwnerPartId=-1|Location.X=754|Location.Y=927|Color=8388608|FontID=1|IsHidden=T|Text=50V|Name=Voltage Rating
|RECORD=41|OwnerIndex=603|IndexInSheet=14|OwnerPartId=-1|Location.X=754|Location.Y=927|Color=8388608|FontID=1|IsHidden=T|Text=Surface Mount|Name=Mount
|RECORD=41|OwnerIndex=603|IndexInSheet=15|OwnerPartId=-1|Location.X=754|Location.Y=927|Color=8388608|FontID=1|IsHidden=T|Text=SMD/SMT|Name=Termination
|RECORD=41|OwnerIndex=603|IndexInSheet=16|OwnerPartId=-1|Location.X=754|Location.Y=927|Color=8388608|FontID=1|IsHidden=T|Text=10%|Name=Tolerance
|RECORD=41|OwnerIndex=603|IndexInSheet=17|OwnerPartId=-1|Location.X=754|Location.Y=927|Color=8388608|FontID=1|IsHidden=T|Text=1206|Name=Case/Package
|RECORD=41|OwnerIndex=603|IndexInSheet=18|OwnerPartId=-1|Location.X=754|Location.Y=927|Color=8388608|FontID=1|IsHidden=T|Text=Ceramic|Name=Material
|RECORD=41|OwnerIndex=603|IndexInSheet=19|OwnerPartId=-1|Location.X=754|Location.Y=927|Color=8388608|FontID=1|IsHidden=T|Text=1.6mm|Name=Depth
|RECORD=41|OwnerIndex=603|IndexInSheet=20|OwnerPartId=-1|Location.X=754|Location.Y=927|Color=8388608|FontID=1|IsHidden=T|Text=3.2mm|Name=Length
|RECORD=41|OwnerIndex=603|IndexInSheet=21|OwnerPartId=-1|Location.X=754|Location.Y=927|Color=8388608|FontID=1|IsHidden=T|Text=3216|Name=Case Code (Metric)
|RECORD=41|OwnerIndex=603|IndexInSheet=22|OwnerPartId=-1|Location.X=754|Location.Y=927|Color=8388608|FontID=1|IsHidden=T|Text=50V|Name=Voltage Rating (DC)
|RECORD=41|OwnerIndex=603|IndexInSheet=23|OwnerPartId=-1|Location.X=754|Location.Y=927|Color=8388608|FontID=1|IsHidden=T|Text=1206|Name=Case Code (Imperial)
|RECORD=41|OwnerIndex=603|IndexInSheet=24|OwnerPartId=-1|Location.X=754|Location.Y=927|Color=8388608|FontID=1|IsHidden=T|Text=No|Name=Radiation Hardening
|RECORD=41|OwnerIndex=603|IndexInSheet=25|OwnerPartId=-1|Location.X=754|Location.Y=927|Color=8388608|FontID=1|IsHidden=T|Text=0.063inch|Name=Width
|RECORD=41|OwnerIndex=603|IndexInSheet=26|OwnerPartId=-1|Location.X=754|Location.Y=927|Color=8388608|FontID=1|IsHidden=T|Text=0.071inch|Name=Thickness
|RECORD=41|OwnerIndex=603|IndexInSheet=27|OwnerPartId=-1|Location.X=754|Location.Y=927|Color=8388608|FontID=1|IsHidden=T|Text=2000|Name=Package Quantity
|RECORD=41|OwnerIndex=603|IndexInSheet=28|OwnerPartId=-1|Location.X=754|Location.Y=927|Color=8388608|FontID=1|IsHidden=T|Text=-55°C|Name=Min Operating Temperature
|RECORD=41|OwnerIndex=603|IndexInSheet=29|OwnerPartId=-1|Location.X=754|Location.Y=927|Color=8388608|FontID=1|IsHidden=T|Text=X7R|Name=Dielectric
|RECORD=34|OwnerIndex=603|IndexInSheet=-1|OwnerPartId=-1|Location.X=755|Location.Y=905|Orientation=1|Color=8388608|FontID=2|Text=C12|Name=Designator|ReadOnlyState=1
|RECORD=41|OwnerIndex=603|IndexInSheet=-1|OwnerPartId=1|Location.X=785|Location.Y=890|Orientation=1|Color=8388608|FontID=2|Text=4.7uF_50V_1206|Name=Comment
|RECORD=44|OwnerIndex=603
|RECORD=45|OwnerIndex=638|IndexInSheet=-1|UseComponentLibrary=T|ModelName=FP-GRM31C-0_2-e0_3_0_8-IPC_C|ModelType=PCBLIB|DatafileCount=1|ModelDatafileEntity0=FP-GRM31C-0_2-e0_3_0_8-IPC_C|ModelDatafileKind0=PCBLib|IsCurrent=T|DatalinksLocked=T|DatabaseDatalinksLocked=T
|RECORD=46|OwnerIndex=639
|RECORD=48|OwnerIndex=639
|RECORD=45|OwnerIndex=638|IndexInSheet=-1|UseComponentLibrary=T|ModelName=FP-GRM31C-0_2-e0_3_0_8-IPC_B|ModelType=PCBLIB|DatafileCount=1|ModelDatafileEntity0=FP-GRM31C-0_2-e0_3_0_8-IPC_B|ModelDatafileKind0=PCBLib|DatalinksLocked=T|DatabaseDatalinksLocked=T
|RECORD=46|OwnerIndex=642
|RECORD=48|OwnerIndex=642
|RECORD=45|OwnerIndex=638|IndexInSheet=-1|UseComponentLibrary=T|ModelName=FP-GRM31C-0_2-e0_3_0_8-IPC_A|ModelType=PCBLIB|DatafileCount=1|ModelDatafileEntity0=FP-GRM31C-0_2-e0_3_0_8-IPC_A|ModelDatafileKind0=PCBLib|DatalinksLocked=T|DatabaseDatalinksLocked=T
|RECORD=46|OwnerIndex=645
|RECORD=48|OwnerIndex=645
|RECORD=45|OwnerIndex=638|IndexInSheet=-1|UseComponentLibrary=T|ModelName=FP-GRM31C-0_2-e0_3_0_8-MFG|ModelType=PCBLIB|DatafileCount=1|ModelDatafileEntity0=FP-GRM31C-0_2-e0_3_0_8-MFG|ModelDatafileKind0=PCBLib|DatalinksLocked=T|DatabaseDatalinksLocked=T
|RECORD=46|OwnerIndex=648
|RECORD=48|OwnerIndex=648
|RECORD=1|LibReference=a00bbbee19879c290e62620ae7e47b1|ComponentDescription=CAP TANT 100UF 10% 16V 2917|PartCount=2|DisplayModeCount=1|IndexInSheet=66|OwnerPartId=-1|Location.X=675|Location.Y=925|CurrentPartId=1|LibraryPath=*|SourceLibraryName=Altium Content Vault|TargetFileName=*|AreaColor=11599871|Color=128|PartIDLocked=T|DesignItemId=CMP-2000-07207-2|AllPinCount=2
|RECORD=2|OwnerIndex=651|OwnerPartId=1|Electrical=4|PinConglomerate=51|PinLength=8|Location.X=675|Location.Y=913|Name=C|Designator=1|PinPropagationDelay=0.000000E+000
|RECORD=2|OwnerIndex=651|OwnerPartId=1|Electrical=4|PinConglomerate=49|PinLength=8|Location.X=675|Location.Y=917|Name=A|Designator=2|PinPropagationDelay=0.000000E+000
|RECORD=5|OwnerIndex=651|IsNotAccesible=T|IndexInSheet=2|OwnerPartId=1|LineWidth=1|Color=16711680|LocationCount=4|X1=665|Y1=909|X2=670|Y2=915|X3=680|Y3=915|X4=685|Y4=909
|RECORD=13|OwnerIndex=651|IsNotAccesible=T|IndexInSheet=3|OwnerPartId=1|Location.X=665|Location.Y=917|Corner.X=685|Corner.Y=917|LineWidth=1|Color=16711680
|RECORD=13|OwnerIndex=651|IsNotAccesible=T|IndexInSheet=4|OwnerPartId=1|Location.X=675|Location.Y=913|Corner.X=675|Corner.Y=911|LineWidth=1|Color=16711680
|RECORD=13|OwnerIndex=651|IsNotAccesible=T|IndexInSheet=5|OwnerPartId=1|Location.X=675|Location.Y=917|Corner.X=675|Corner.Y=920|LineWidth=1|Color=16711680
|RECORD=4|OwnerIndex=651|IsNotAccesible=T|IndexInSheet=6|OwnerPartId=1|Location.X=664|Location.Y=927|Justification=6|Color=8388608|FontID=1|Text=+
|RECORD=41|OwnerIndex=651|IndexInSheet=7|OwnerPartId=-1|Location.X=664|Location.Y=927|Color=8388608|FontID=1|IsHidden=T|Text=100uF|Name=Capacitance
|RECORD=41|OwnerIndex=651|IndexInSheet=8|OwnerPartId=-1|Location.X=664|Location.Y=927|Color=8388608|FontID=1|IsHidden=T|Text=No|Name=Radiation Hardening
|RECORD=41|OwnerIndex=651|IndexInSheet=9|OwnerPartId=-1|Location.X=664|Location.Y=927|Color=8388608|FontID=1|IsHidden=T|Text=Yes|Name=RoHS Compliant
|RECORD=41|OwnerIndex=651|IndexInSheet=10|OwnerPartId=-1|Location.X=664|Location.Y=927|Color=8388608|FontID=1|IsHidden=T|Text=7.3mm|Name=Length
|RECORD=41|OwnerIndex=651|IndexInSheet=11|OwnerPartId=-1|Location.X=664|Location.Y=927|Color=8388608|FontID=1|IsHidden=T|Text=General Purpose|Name=Features
|RECORD=41|OwnerIndex=651|IndexInSheet=12|OwnerPartId=-1|Location.X=664|Location.Y=927|Color=8388608|FontID=1|IsHidden=T|Text=Tape and Reel|Name=Packaging
|RECORD=41|OwnerIndex=651|IndexInSheet=13|OwnerPartId=-1|Location.X=664|Location.Y=927|Color=8388608|FontID=1|IsHidden=T|Text=1|Name=Package Quantity
|RECORD=41|OwnerIndex=651|IndexInSheet=14|OwnerPartId=-1|Location.X=664|Location.Y=927|Color=8388608|FontID=1|IsHidden=T|Text=0.023634oz|Name=Weight
|RECORD=41|OwnerIndex=651|IndexInSheet=15|OwnerPartId=-1|Location.X=664|Location.Y=927|Color=8388608|FontID=1|IsHidden=T|Text=2000Hour|Name=Life (Hours)
|RECORD=41|OwnerIndex=651|IndexInSheet=16|OwnerPartId=-1|Location.X=664|Location.Y=927|Color=8388608|FontID=1|IsHidden=T|Text=16V|Name=Voltage Rating
|RECORD=41|OwnerIndex=651|IndexInSheet=17|OwnerPartId=-1|Location.X=664|Location.Y=927|Color=8388608|FontID=1|IsHidden=T|Text=0.169inch|Name=Width
|RECORD=41|OwnerIndex=651|IndexInSheet=18|OwnerPartId=-1|Location.X=664|Location.Y=927|Color=8388608|FontID=1|IsHidden=T|Text=2917|Name=Case/Package
|RECORD=41|OwnerIndex=651|IndexInSheet=19|OwnerPartId=-1|Location.X=664|Location.Y=927|Color=8388608|FontID=1|IsHidden=T|Text=125mR|Name=ESR (Equivalent Series Resistance)
|RECORD=41|OwnerIndex=651|IndexInSheet=20|OwnerPartId=-1|Location.X=664|Location.Y=927|Color=8388608|FontID=1|IsHidden=T|Text=Surface Mount|Name=Mount
|RECORD=41|OwnerIndex=651|IndexInSheet=21|OwnerPartId=-1|Location.X=664|Location.Y=927|Color=8388608|FontID=1|IsHidden=T|Text=16V|Name=Voltage
|RECORD=41|OwnerIndex=651|IndexInSheet=22|OwnerPartId=-1|Location.X=664|Location.Y=927|Color=8388608|FontID=1|IsHidden=T|Text=-55°C|Name=Min Operating Temperature
|RECORD=41|OwnerIndex=651|IndexInSheet=23|OwnerPartId=-1|Location.X=664|Location.Y=927|Color=8388608|FontID=1|IsHidden=T|Text=10%|Name=Tolerance
|RECORD=41|OwnerIndex=651|IndexInSheet=24|OwnerPartId=-1|Location.X=664|Location.Y=927|Color=8388608|FontID=1|IsHidden=T|Text=No SVHC|Name=REACH SVHC
|RECORD=41|OwnerIndex=651|IndexInSheet=25|OwnerPartId=-1|Location.X=664|Location.Y=927|Color=8388608|FontID=1|IsHidden=T|Text=0.122inch|Name=Height - Seated (Max)
|RECORD=41|OwnerIndex=651|IndexInSheet=26|OwnerPartId=-1|Location.X=664|Location.Y=927|Color=8388608|FontID=1|IsHidden=T|Text=2|Name=Number of Pins
|RECORD=41|OwnerIndex=651|IndexInSheet=27|OwnerPartId=-1|Location.X=664|Location.Y=927|Color=8388608|FontID=1|IsHidden=T|Text=Flat|Name=Construction
|RECORD=41|OwnerIndex=651|IndexInSheet=28|OwnerPartId=-1|Location.X=664|Location.Y=927|Color=8388608|FontID=1|IsHidden=T|Text=4.3mm|Name=Depth
|RECORD=41|OwnerIndex=651|IndexInSheet=29|OwnerPartId=-1|Location.X=664|Location.Y=927|Color=8388608|FontID=1|IsHidden=T|Text=T495|Name=Series
|RECORD=41|OwnerIndex=651|IndexInSheet=30|OwnerPartId=-1|Location.X=664|Location.Y=927|Color=8388608|FontID=1|IsHidden=T|Text=125°C|Name=Max Operating Temperature
|RECORD=41|OwnerIndex=651|IndexInSheet=31|OwnerPartId=-1|Location.X=664|Location.Y=927|Color=8388608|FontID=1|IsHidden=T|Text=0.001%|Name=Failure Rate
|RECORD=41|OwnerIndex=651|IndexInSheet=32|OwnerPartId=-1|Location.X=664|Location.Y=927|Color=8388608|FontID=1|IsHidden=T|Text=SMD/SMT|Name=Termination
|RECORD=41|OwnerIndex=651|IndexInSheet=33|OwnerPartId=-1|Location.X=664|Location.Y=927|Color=8388608|FontID=1|IsHidden=T|Text=Polar|Name=Polarity
|RECORD=41|OwnerIndex=651|IndexInSheet=34|OwnerPartId=-1|Location.X=664|Location.Y=927|Color=8388608|FontID=1|IsHidden=T|Text=16V|Name=Voltage Rating (DC)
|RECORD=41|OwnerIndex=651|IndexInSheet=35|OwnerPartId=-1|Location.X=664|Location.Y=927|Color=8388608|FontID=1|IsHidden=T|Text=Tantalum|Name=Dielectric Material
|RECORD=41|OwnerIndex=651|IndexInSheet=36|OwnerPartId=-1|Location.X=664|Location.Y=927|Color=8388608|FontID=1|IsHidden=T|Text=2917|Name=Case Code (Imperial)
|RECORD=41|OwnerIndex=651|IndexInSheet=37|OwnerPartId=-1|Location.X=664|Location.Y=927|Color=8388608|FontID=1|IsHidden=T|Text=7343|Name=Case Code (Metric)
|RECORD=41|OwnerIndex=651|IndexInSheet=38|OwnerPartId=-1|Location.X=664|Location.Y=927|Color=8388608|FontID=1|IsHidden=T|Text=2.8mm|Name=Height
|RECORD=41|OwnerIndex=651|IndexInSheet=39|OwnerPartId=-1|Location.X=664|Location.Y=927|Color=8388608|FontID=1|IsHidden=T|Text=8%|Name=Dissipation Factor
|RECORD=34|OwnerIndex=651|IndexInSheet=-1|OwnerPartId=-1|Location.X=660|Location.Y=905|Orientation=1|Color=8388608|FontID=2|Text=C10|Name=Designator|ReadOnlyState=1
|RECORD=41|OwnerIndex=651|IndexInSheet=-1|OwnerPartId=1|Location.X=700|Location.Y=885|Orientation=1|Color=8388608|FontID=2|Text=100uF_16V_2917|Name=Comment
|RECORD=44|OwnerIndex=651
|RECORD=45|OwnerIndex=696|IndexInSheet=-1|UseComponentLibrary=T|ModelName=FP-T495D107K016ATE125-MFG|ModelType=PCBLIB|DatafileCount=1|ModelDatafileEntity0=FP-T495D107K016ATE125-MFG|ModelDatafileKind0=PCBLib|IsCurrent=T|DatalinksLocked=T|DatabaseDatalinksLocked=T
|RECORD=46|OwnerIndex=697
|RECORD=48|OwnerIndex=697
|RECORD=17|IndexInSheet=67|OwnerPartId=-1|ShowNetName=T|Location.X=1360|Location.Y=1005|Orientation=1|Color=128|FontID=1|Text=P5V_SENSE
|RECORD=1|LibReference=RES|PartCount=2|DisplayModeCount=2|IndexInSheet=68|OwnerPartId=-1|Location.X=1385|Location.Y=995|CurrentPartId=1|SourceLibraryName=Altium Content Vault|TargetFileName=*|AreaColor=11599871|Color=128|PartIDLocked=F|DesignItemId=CMP-2003-04334-1|AllPinCount=2
|RECORD=2|OwnerIndex=701|OwnerPartId=1|OwnerPartDisplayMode=1|FormalType=1|Electrical=4|PinConglomerate=32|PinLength=10|Location.X=1405|Location.Y=985|Name=2|Designator=2|PinPropagationDelay=0.000000E+000
|RECORD=2|OwnerIndex=701|OwnerPartId=1|OwnerPartDisplayMode=1|FormalType=1|Electrical=4|PinConglomerate=34|PinLength=10|Location.X=1385|Location.Y=985|Name=1|Designator=1|PinPropagationDelay=0.000000E+000
|RECORD=14|OwnerIndex=701|IsNotAccesible=T|IndexInSheet=2|OwnerPartId=1|OwnerPartDisplayMode=1|Location.X=1385|Location.Y=981|Corner.X=1405|Corner.Y=989|LineWidth=1|Color=16711680|AreaColor=11599871
|RECORD=2|OwnerIndex=701|OwnerPartId=1|FormalType=1|Electrical=4|PinConglomerate=32|PinLength=10|Location.X=1405|Location.Y=985|Name=2|Designator=2|PinPropagationDelay=0.000000E+000
|RECORD=2|OwnerIndex=701|OwnerPartId=1|FormalType=1|Electrical=4|PinConglomerate=34|PinLength=10|Location.X=1385|Location.Y=985|Name=1|Designator=1|PinPropagationDelay=0.000000E+000
|RECORD=6|OwnerIndex=701|IsNotAccesible=T|IndexInSheet=5|OwnerPartId=1|LineWidth=1|Color=16711680|LocationCount=10|X1=1405|Y1=985|X2=1401|Y2=985|X3=1400|Y3=983|X4=1398|Y4=987|X5=1396|Y5=983|X6=1394|Y6=987|X7=1392|Y7=983|X8=1390|Y8=987|X9=1389|Y9=985|X10=1385|Y10=985
|RECORD=41|OwnerIndex=701|IndexInSheet=6|OwnerPartId=-1|Location.X=1373|Location.Y=998|Color=8388608|FontID=1|IsHidden=T|Text=Vishay Dale|Name=Manufacturer
|RECORD=41|OwnerIndex=701|IndexInSheet=7|OwnerPartId=-1|Location.X=1373|Location.Y=998|Color=8388608|FontID=1|IsHidden=T|Text=WSL12062L000FEA18|Name=Part Number
|RECORD=34|OwnerIndex=701|IndexInSheet=-1|OwnerPartId=-1|Location.X=1384|Location.Y=988|Color=8388608|FontID=1|Text=R8|Name=Designator|ReadOnlyState=1
|RECORD=41|OwnerIndex=701|IndexInSheet=-1|OwnerPartId=-1|Location.X=1384|Location.Y=972|Color=8388608|FontID=1|Text=2mOhm_1%_1206|Name=Comment
|RECORD=44|OwnerIndex=701
|RECORD=45|OwnerIndex=716|IndexInSheet=-1|Description=Chip Resistor, 2-Leads, Body 3.20x1.60mm, IPC Medium Density|UseComponentLibrary=T|ModelName=RESC3216X89X64NL25T25|ModelType=PCBLIB|DatafileCount=1|ModelDatafileEntity0=RESC3216X89X64NL25T25|ModelDatafileKind0=PCBLib|IsCurrent=T|DatalinksLocked=T|DatabaseDatalinksLocked=T
|RECORD=46|OwnerIndex=717
|RECORD=48|OwnerIndex=717
|RECORD=41|OwnerIndex=719|IndexInSheet=-1|OwnerPartId=-1|Color=8388608|FontID=1|IsHidden=T|Text=2D|Name=Available Preview Images
|RECORD=45|OwnerIndex=716|IndexInSheet=-1|Description=Chip Resistor, 2-Leads, Body 3.20x1.60mm, IPC High Density|UseComponentLibrary=T|ModelName=RESC3216X89X64LL25T25|ModelType=PCBLIB|DatafileCount=1|ModelDatafileEntity0=RESC3216X89X64LL25T25|ModelDatafileKind0=PCBLib|DatalinksLocked=T|DatabaseDatalinksLocked=T
|RECORD=46|OwnerIndex=721
|RECORD=48|OwnerIndex=721
|RECORD=41|OwnerIndex=723|IndexInSheet=-1|OwnerPartId=-1|Color=8388608|FontID=1|IsHidden=T|Text=2D|Name=Available Preview Images
|RECORD=45|OwnerIndex=716|IndexInSheet=-1|Description=Chip Resistor, 2-Leads, Body 3.20x1.60mm, IPC Low Density|UseComponentLibrary=T|ModelName=RESC3216X89X64ML25T25|ModelType=PCBLIB|DatafileCount=1|ModelDatafileEntity0=RESC3216X89X64ML25T25|ModelDatafileKind0=PCBLib|DatalinksLocked=T|DatabaseDatalinksLocked=T
|RECORD=46|OwnerIndex=725
|RECORD=48|OwnerIndex=725
|RECORD=41|OwnerIndex=727|IndexInSheet=-1|OwnerPartId=-1|Color=8388608|FontID=1|IsHidden=T|Text=2D|Name=Available Preview Images
|RECORD=1|LibReference=b4654b650e69147ec39a6b967a45e02|ComponentDescription=Multilayer Ceramic Capacitor 10uF 16V X5R 20% SMD 0603 T/R|PartCount=2|DisplayModeCount=1|IndexInSheet=69|OwnerPartId=-1|Location.X=1515|Location.Y=925|CurrentPartId=1|LibraryPath=*|SourceLibraryName=Altium Content Vault|TargetFileName=*|AreaColor=11599871|Color=128|PartIDLocked=T|DesignItemId=CMP-2000-06226-4|AllPinCount=2
|RECORD=2|OwnerIndex=729|OwnerPartId=1|Electrical=4|PinConglomerate=49|PinLength=7|Location.X=1515|Location.Y=918|Name=1|Designator=1|PinPropagationDelay=0.000000E+000
|RECORD=2|OwnerIndex=729|OwnerPartId=1|Electrical=4|PinConglomerate=51|PinLength=6|Location.X=1515|Location.Y=911|Name=2|Designator=2|PinPropagationDelay=0.000000E+000
|RECORD=13|OwnerIndex=729|IsNotAccesible=T|IndexInSheet=2|OwnerPartId=1|Location.X=1525|Location.Y=918|Corner.X=1505|Corner.Y=918|LineWidth=1|Color=16711680
|RECORD=13|OwnerIndex=729|IsNotAccesible=T|IndexInSheet=3|OwnerPartId=1|Location.X=1525|Location.Y=912|Corner.X=1505|Corner.Y=912|LineWidth=1|Color=16711680
|RECORD=13|OwnerIndex=729|IsNotAccesible=T|IndexInSheet=4|OwnerPartId=1|Location.X=1515|Location.Y=918|Corner.X=1515|Corner.Y=921|LineWidth=1|Color=16711680
|RECORD=13|OwnerIndex=729|IsNotAccesible=T|IndexInSheet=5|OwnerPartId=1|Location.X=1515|Location.Y=911|Corner.X=1515|Corner.Y=910|LineWidth=1|Color=16711680
|RECORD=41|OwnerIndex=729|IndexInSheet=6|OwnerPartId=-1|Location.X=1504|Location.Y=927|Color=8388608|FontID=1|IsHidden=T|Text=Tape and Reel|Name=Packaging
|RECORD=41|OwnerIndex=729|IndexInSheet=7|OwnerPartId=-1|Location.X=1504|Location.Y=927|Color=8388608|FontID=1|IsHidden=T|Text=Flat|Name=Construction
|RECORD=41|OwnerIndex=729|IndexInSheet=8|OwnerPartId=-1|Location.X=1504|Location.Y=927|Color=8388608|FontID=1|IsHidden=T|Text=0.8mm|Name=Height
|RECORD=41|OwnerIndex=729|IndexInSheet=9|OwnerPartId=-1|Location.X=1504|Location.Y=927|Color=8388608|FontID=1|IsHidden=T|Text=85°C|Name=Max Operating Temperature
|RECORD=41|OwnerIndex=729|IndexInSheet=10|OwnerPartId=-1|Location.X=1504|Location.Y=927|Color=8388608|FontID=1|IsHidden=T|Text=X5R|Name=Dielectric
|RECORD=41|OwnerIndex=729|IndexInSheet=11|OwnerPartId=-1|Location.X=1504|Location.Y=927|Color=8388608|FontID=1|IsHidden=T|Text=1608|Name=Case Code (Metric)
|RECORD=41|OwnerIndex=729|IndexInSheet=12|OwnerPartId=-1|Location.X=1504|Location.Y=927|Color=8388608|FontID=1|IsHidden=T|Text=16V|Name=Voltage Rating (DC)
|RECORD=41|OwnerIndex=729|IndexInSheet=13|OwnerPartId=-1|Location.X=1504|Location.Y=927|Color=8388608|FontID=1|IsHidden=T|Text=0.031inch|Name=Width
|RECORD=41|OwnerIndex=729|IndexInSheet=14|OwnerPartId=-1|Location.X=1504|Location.Y=927|Color=8388608|FontID=1|IsHidden=T|Text=16V|Name=Voltage Rating
|RECORD=41|OwnerIndex=729|IndexInSheet=15|OwnerPartId=-1|Location.X=1504|Location.Y=927|Color=8388608|FontID=1|IsHidden=T|Text=0.063inch|Name=Length
|RECORD=41|OwnerIndex=729|IndexInSheet=16|OwnerPartId=-1|Location.X=1504|Location.Y=927|Color=8388608|FontID=1|IsHidden=T|Text=Yes|Name=RoHS Compliant
|RECORD=41|OwnerIndex=729|IndexInSheet=17|OwnerPartId=-1|Location.X=1504|Location.Y=927|Color=8388608|FontID=1|IsHidden=T|Text=Halogen Free|Name=Halogen Free
|RECORD=41|OwnerIndex=729|IndexInSheet=18|OwnerPartId=-1|Location.X=1504|Location.Y=927|Color=8388608|FontID=1|IsHidden=T|Text=0603|Name=Case Code (Imperial)
|RECORD=41|OwnerIndex=729|IndexInSheet=19|OwnerPartId=-1|Location.X=1504|Location.Y=927|Color=8388608|FontID=1|IsHidden=T|Text=10uF|Name=Capacitance
|RECORD=41|OwnerIndex=729|IndexInSheet=20|OwnerPartId=-1|Location.X=1504|Location.Y=927|Color=8388608|FontID=1|IsHidden=T|Text=Surface Mount|Name=Mount
|RECORD=41|OwnerIndex=729|IndexInSheet=21|OwnerPartId=-1|Location.X=1504|Location.Y=927|Color=8388608|FontID=1|IsHidden=T|Text=0.031inch|Name=Thickness
|RECORD=41|OwnerIndex=729|IndexInSheet=22|OwnerPartId=-1|Location.X=1504|Location.Y=927|Color=8388608|FontID=1|IsHidden=T|Text=20%|Name=Tolerance
|RECORD=41|OwnerIndex=729|IndexInSheet=23|OwnerPartId=-1|Location.X=1504|Location.Y=927|Color=8388608|FontID=1|IsHidden=T|Text=-55°C|Name=Min Operating Temperature
|RECORD=41|OwnerIndex=729|IndexInSheet=24|OwnerPartId=-1|Location.X=1504|Location.Y=927|Color=8388608|FontID=1|IsHidden=T|Text=M|Name=Series
|RECORD=41|OwnerIndex=729|IndexInSheet=25|OwnerPartId=-1|Location.X=1504|Location.Y=927|Color=8388608|FontID=1|IsHidden=T|Text=SMD/SMT|Name=Termination
|RECORD=41|OwnerIndex=729|IndexInSheet=26|OwnerPartId=-1|Location.X=1504|Location.Y=927|Color=8388608|FontID=1|IsHidden=T|Text=0603|Name=Case/Package
|RECORD=41|OwnerIndex=729|IndexInSheet=27|OwnerPartId=-1|Location.X=1504|Location.Y=927|Color=8388608|FontID=1|IsHidden=T|Text=1|Name=Package Quantity
|RECORD=34|OwnerIndex=729|IndexInSheet=-1|OwnerPartId=-1|Location.X=1505|Location.Y=905|Orientation=1|Color=8388608|FontID=2|Text=C15|Name=Designator|ReadOnlyState=1
|RECORD=41|OwnerIndex=729|IndexInSheet=-1|OwnerPartId=1|Location.X=1535|Location.Y=890|Orientation=1|Color=8388608|FontID=2|Text=10uF_16V_0603|Name=Comment
|RECORD=44|OwnerIndex=729
|RECORD=45|OwnerIndex=762|IndexInSheet=-1|UseComponentLibrary=T|ModelName=FP-0603-L_1_6_0_2-W_0_8_0-MFG|ModelType=PCBLIB|DatafileCount=1|ModelDatafileEntity0=FP-0603-L_1_6_0_2-W_0_8_0-MFG|ModelDatafileKind0=PCBLib|IsCurrent=T|DatalinksLocked=T|DatabaseDatalinksLocked=T
|RECORD=46|OwnerIndex=763
|RECORD=48|OwnerIndex=763
|RECORD=45|OwnerIndex=762|IndexInSheet=-1|UseComponentLibrary=T|ModelName=FP-0603-L_1_6_0_2-W_0_8_0-IPC_B|ModelType=PCBLIB|DatafileCount=1|ModelDatafileEntity0=FP-0603-L_1_6_0_2-W_0_8_0-IPC_B|ModelDatafileKind0=PCBLib|DatalinksLocked=T|DatabaseDatalinksLocked=T
|RECORD=46|OwnerIndex=766
|RECORD=48|OwnerIndex=766
|RECORD=45|OwnerIndex=762|IndexInSheet=-1|UseComponentLibrary=T|ModelName=FP-0603-L_1_6_0_2-W_0_8_0-IPC_C|ModelType=PCBLIB|DatafileCount=1|ModelDatafileEntity0=FP-0603-L_1_6_0_2-W_0_8_0-IPC_C|ModelDatafileKind0=PCBLib|DatalinksLocked=T|DatabaseDatalinksLocked=T
|RECORD=46|OwnerIndex=769
|RECORD=48|OwnerIndex=769
|RECORD=45|OwnerIndex=762|IndexInSheet=-1|UseComponentLibrary=T|ModelName=FP-0603-L_1_6_0_2-W_0_8_0-IPC_A|ModelType=PCBLIB|DatafileCount=1|ModelDatafileEntity0=FP-0603-L_1_6_0_2-W_0_8_0-IPC_A|ModelDatafileKind0=PCBLib|DatalinksLocked=T|DatabaseDatalinksLocked=T
|RECORD=46|OwnerIndex=772
|RECORD=48|OwnerIndex=772
|RECORD=1|LibReference=a00bbbee19879c290e62620ae7e47b1|ComponentDescription=CAP TANT 100UF 10% 16V 2917|PartCount=2|DisplayModeCount=1|IndexInSheet=70|OwnerPartId=-1|Location.X=1430|Location.Y=925|CurrentPartId=1|LibraryPath=*|SourceLibraryName=Altium Content Vault|TargetFileName=*|AreaColor=11599871|Color=128|PartIDLocked=T|DesignItemId=CMP-2000-07207-2|AllPinCount=2
|RECORD=2|OwnerIndex=775|OwnerPartId=1|Electrical=4|PinConglomerate=51|PinLength=8|Location.X=1430|Location.Y=913|Name=C|Designator=1|PinPropagationDelay=0.000000E+000
|RECORD=2|OwnerIndex=775|OwnerPartId=1|Electrical=4|PinConglomerate=49|PinLength=8|Location.X=1430|Location.Y=917|Name=A|Designator=2|PinPropagationDelay=0.000000E+000
|RECORD=5|OwnerIndex=775|IsNotAccesible=T|IndexInSheet=2|OwnerPartId=1|LineWidth=1|Color=16711680|LocationCount=4|X1=1420|Y1=909|X2=1425|Y2=915|X3=1435|Y3=915|X4=1440|Y4=909
|RECORD=13|OwnerIndex=775|IsNotAccesible=T|IndexInSheet=3|OwnerPartId=1|Location.X=1420|Location.Y=917|Corner.X=1440|Corner.Y=917|LineWidth=1|Color=16711680
|RECORD=13|OwnerIndex=775|IsNotAccesible=T|IndexInSheet=4|OwnerPartId=1|Location.X=1430|Location.Y=913|Corner.X=1430|Corner.Y=911|LineWidth=1|Color=16711680
|RECORD=13|OwnerIndex=775|IsNotAccesible=T|IndexInSheet=5|OwnerPartId=1|Location.X=1430|Location.Y=917|Corner.X=1430|Corner.Y=920|LineWidth=1|Color=16711680
|RECORD=4|OwnerIndex=775|IsNotAccesible=T|IndexInSheet=6|OwnerPartId=1|Location.X=1419|Location.Y=927|Justification=6|Color=8388608|FontID=1|Text=+
|RECORD=41|OwnerIndex=775|IndexInSheet=7|OwnerPartId=-1|Location.X=1419|Location.Y=927|Color=8388608|FontID=1|IsHidden=T|Text=100uF|Name=Capacitance
|RECORD=41|OwnerIndex=775|IndexInSheet=8|OwnerPartId=-1|Location.X=1419|Location.Y=927|Color=8388608|FontID=1|IsHidden=T|Text=No|Name=Radiation Hardening
|RECORD=41|OwnerIndex=775|IndexInSheet=9|OwnerPartId=-1|Location.X=1419|Location.Y=927|Color=8388608|FontID=1|IsHidden=T|Text=Yes|Name=RoHS Compliant
|RECORD=41|OwnerIndex=775|IndexInSheet=10|OwnerPartId=-1|Location.X=1419|Location.Y=927|Color=8388608|FontID=1|IsHidden=T|Text=7.3mm|Name=Length
|RECORD=41|OwnerIndex=775|IndexInSheet=11|OwnerPartId=-1|Location.X=1419|Location.Y=927|Color=8388608|FontID=1|IsHidden=T|Text=General Purpose|Name=Features
|RECORD=41|OwnerIndex=775|IndexInSheet=12|OwnerPartId=-1|Location.X=1419|Location.Y=927|Color=8388608|FontID=1|IsHidden=T|Text=Tape and Reel|Name=Packaging
|RECORD=41|OwnerIndex=775|IndexInSheet=13|OwnerPartId=-1|Location.X=1419|Location.Y=927|Color=8388608|FontID=1|IsHidden=T|Text=1|Name=Package Quantity
|RECORD=41|OwnerIndex=775|IndexInSheet=14|OwnerPartId=-1|Location.X=1419|Location.Y=927|Color=8388608|FontID=1|IsHidden=T|Text=0.023634oz|Name=Weight
|RECORD=41|OwnerIndex=775|IndexInSheet=15|OwnerPartId=-1|Location.X=1419|Location.Y=927|Color=8388608|FontID=1|IsHidden=T|Text=2000Hour|Name=Life (Hours)
|RECORD=41|OwnerIndex=775|IndexInSheet=16|OwnerPartId=-1|Location.X=1419|Location.Y=927|Color=8388608|FontID=1|IsHidden=T|Text=16V|Name=Voltage Rating
|RECORD=41|OwnerIndex=775|IndexInSheet=17|OwnerPartId=-1|Location.X=1419|Location.Y=927|Color=8388608|FontID=1|IsHidden=T|Text=0.169inch|Name=Width
|RECORD=41|OwnerIndex=775|IndexInSheet=18|OwnerPartId=-1|Location.X=1419|Location.Y=927|Color=8388608|FontID=1|IsHidden=T|Text=2917|Name=Case/Package
|RECORD=41|OwnerIndex=775|IndexInSheet=19|OwnerPartId=-1|Location.X=1419|Location.Y=927|Color=8388608|FontID=1|IsHidden=T|Text=125mR|Name=ESR (Equivalent Series Resistance)
|RECORD=41|OwnerIndex=775|IndexInSheet=20|OwnerPartId=-1|Location.X=1419|Location.Y=927|Color=8388608|FontID=1|IsHidden=T|Text=Surface Mount|Name=Mount
|RECORD=41|OwnerIndex=775|IndexInSheet=21|OwnerPartId=-1|Location.X=1419|Location.Y=927|Color=8388608|FontID=1|IsHidden=T|Text=16V|Name=Voltage
|RECORD=41|OwnerIndex=775|IndexInSheet=22|OwnerPartId=-1|Location.X=1419|Location.Y=927|Color=8388608|FontID=1|IsHidden=T|Text=-55°C|Name=Min Operating Temperature
|RECORD=41|OwnerIndex=775|IndexInSheet=23|OwnerPartId=-1|Location.X=1419|Location.Y=927|Color=8388608|FontID=1|IsHidden=T|Text=10%|Name=Tolerance
|RECORD=41|OwnerIndex=775|IndexInSheet=24|OwnerPartId=-1|Location.X=1419|Location.Y=927|Color=8388608|FontID=1|IsHidden=T|Text=No SVHC|Name=REACH SVHC
|RECORD=41|OwnerIndex=775|IndexInSheet=25|OwnerPartId=-1|Location.X=1419|Location.Y=927|Color=8388608|FontID=1|IsHidden=T|Text=0.122inch|Name=Height - Seated (Max)
|RECORD=41|OwnerIndex=775|IndexInSheet=26|OwnerPartId=-1|Location.X=1419|Location.Y=927|Color=8388608|FontID=1|IsHidden=T|Text=2|Name=Number of Pins
|RECORD=41|OwnerIndex=775|IndexInSheet=27|OwnerPartId=-1|Location.X=1419|Location.Y=927|Color=8388608|FontID=1|IsHidden=T|Text=Flat|Name=Construction
|RECORD=41|OwnerIndex=775|IndexInSheet=28|OwnerPartId=-1|Location.X=1419|Location.Y=927|Color=8388608|FontID=1|IsHidden=T|Text=4.3mm|Name=Depth
|RECORD=41|OwnerIndex=775|IndexInSheet=29|OwnerPartId=-1|Location.X=1419|Location.Y=927|Color=8388608|FontID=1|IsHidden=T|Text=T495|Name=Series
|RECORD=41|OwnerIndex=775|IndexInSheet=30|OwnerPartId=-1|Location.X=1419|Location.Y=927|Color=8388608|FontID=1|IsHidden=T|Text=125°C|Name=Max Operating Temperature
|RECORD=41|OwnerIndex=775|IndexInSheet=31|OwnerPartId=-1|Location.X=1419|Location.Y=927|Color=8388608|FontID=1|IsHidden=T|Text=0.001%|Name=Failure Rate
|RECORD=41|OwnerIndex=775|IndexInSheet=32|OwnerPartId=-1|Location.X=1419|Location.Y=927|Color=8388608|FontID=1|IsHidden=T|Text=SMD/SMT|Name=Termination
|RECORD=41|OwnerIndex=775|IndexInSheet=33|OwnerPartId=-1|Location.X=1419|Location.Y=927|Color=8388608|FontID=1|IsHidden=T|Text=Polar|Name=Polarity
|RECORD=41|OwnerIndex=775|IndexInSheet=34|OwnerPartId=-1|Location.X=1419|Location.Y=927|Color=8388608|FontID=1|IsHidden=T|Text=16V|Name=Voltage Rating (DC)
|RECORD=41|OwnerIndex=775|IndexInSheet=35|OwnerPartId=-1|Location.X=1419|Location.Y=927|Color=8388608|FontID=1|IsHidden=T|Text=Tantalum|Name=Dielectric Material
|RECORD=41|OwnerIndex=775|IndexInSheet=36|OwnerPartId=-1|Location.X=1419|Location.Y=927|Color=8388608|FontID=1|IsHidden=T|Text=2917|Name=Case Code (Imperial)
|RECORD=41|OwnerIndex=775|IndexInSheet=37|OwnerPartId=-1|Location.X=1419|Location.Y=927|Color=8388608|FontID=1|IsHidden=T|Text=7343|Name=Case Code (Metric)
|RECORD=41|OwnerIndex=775|IndexInSheet=38|OwnerPartId=-1|Location.X=1419|Location.Y=927|Color=8388608|FontID=1|IsHidden=T|Text=2.8mm|Name=Height
|RECORD=41|OwnerIndex=775|IndexInSheet=39|OwnerPartId=-1|Location.X=1419|Location.Y=927|Color=8388608|FontID=1|IsHidden=T|Text=8%|Name=Dissipation Factor
|RECORD=34|OwnerIndex=775|IndexInSheet=-1|OwnerPartId=-1|Location.X=1415|Location.Y=905|Orientation=1|Color=8388608|FontID=2|Text=C14|Name=Designator|ReadOnlyState=1
|RECORD=41|OwnerIndex=775|IndexInSheet=-1|OwnerPartId=1|Location.X=1455|Location.Y=885|Orientation=1|Color=8388608|FontID=2|Text=100uF_16V_2917|Name=Comment
|RECORD=44|OwnerIndex=775
|RECORD=45|OwnerIndex=820|IndexInSheet=-1|UseComponentLibrary=T|ModelName=FP-T495D107K016ATE125-MFG|ModelType=PCBLIB|DatafileCount=1|ModelDatafileEntity0=FP-T495D107K016ATE125-MFG|ModelDatafileKind0=PCBLib|IsCurrent=T|DatalinksLocked=T|DatabaseDatalinksLocked=T
|RECORD=46|OwnerIndex=821
|RECORD=48|OwnerIndex=821
|RECORD=1|LibReference=b4654b650e69147ec39a6b967a45e02|ComponentDescription=Multilayer Ceramic Capacitors 2.2µF ±10% 16V X5R SMD 0402|PartCount=2|DisplayModeCount=1|IndexInSheet=71|OwnerPartId=-1|Location.X=1560|Location.Y=925|CurrentPartId=1|LibraryPath=*|SourceLibraryName=Altium Content Vault|TargetFileName=*|AreaColor=11599871|Color=128|PartIDLocked=T|DesignItemId=CMP-2000-05998-2|AllPinCount=2
|RECORD=2|OwnerIndex=824|OwnerPartId=1|Electrical=4|PinConglomerate=49|PinLength=7|Location.X=1560|Location.Y=918|Name=1|Designator=1|PinPropagationDelay=0.000000E+000
|RECORD=2|OwnerIndex=824|OwnerPartId=1|Electrical=4|PinConglomerate=51|PinLength=6|Location.X=1560|Location.Y=911|Name=2|Designator=2|PinPropagationDelay=0.000000E+000
|RECORD=13|OwnerIndex=824|IsNotAccesible=T|IndexInSheet=2|OwnerPartId=1|Location.X=1570|Location.Y=918|Corner.X=1550|Corner.Y=918|LineWidth=1|Color=16711680
|RECORD=13|OwnerIndex=824|IsNotAccesible=T|IndexInSheet=3|OwnerPartId=1|Location.X=1570|Location.Y=912|Corner.X=1550|Corner.Y=912|LineWidth=1|Color=16711680
|RECORD=13|OwnerIndex=824|IsNotAccesible=T|IndexInSheet=4|OwnerPartId=1|Location.X=1560|Location.Y=918|Corner.X=1560|Corner.Y=921|LineWidth=1|Color=16711680
|RECORD=13|OwnerIndex=824|IsNotAccesible=T|IndexInSheet=5|OwnerPartId=1|Location.X=1560|Location.Y=911|Corner.X=1560|Corner.Y=910|LineWidth=1|Color=16711680
|RECORD=41|OwnerIndex=824|IndexInSheet=6|OwnerPartId=-1|Location.X=1549|Location.Y=927|Color=8388608|FontID=1|IsHidden=T|Text=No SVHC|Name=REACH SVHC
|RECORD=41|OwnerIndex=824|IndexInSheet=7|OwnerPartId=-1|Location.X=1549|Location.Y=927|Color=8388608|FontID=1|IsHidden=T|Text=C|Name=Series
|RECORD=41|OwnerIndex=824|IndexInSheet=8|OwnerPartId=-1|Location.X=1549|Location.Y=927|Color=8388608|FontID=1|IsHidden=T|Text=SMD/SMT|Name=Termination
|RECORD=41|OwnerIndex=824|IndexInSheet=9|OwnerPartId=-1|Location.X=1549|Location.Y=927|Color=8388608|FontID=1|IsHidden=T|Text=0402|Name=Case Code (Imperial)
|RECORD=41|OwnerIndex=824|IndexInSheet=10|OwnerPartId=-1|Location.X=1549|Location.Y=927|Color=8388608|FontID=1|IsHidden=T|Text=0.5mm|Name=Depth
|RECORD=41|OwnerIndex=824|IndexInSheet=11|OwnerPartId=-1|Location.X=1549|Location.Y=927|Color=8388608|FontID=1|IsHidden=T|Text=Surface Mount|Name=Mount
|RECORD=41|OwnerIndex=824|IndexInSheet=12|OwnerPartId=-1|Location.X=1549|Location.Y=927|Color=8388608|FontID=1|IsHidden=T|Text=0.02inch|Name=Width
|RECORD=41|OwnerIndex=824|IndexInSheet=13|OwnerPartId=-1|Location.X=1549|Location.Y=927|Color=8388608|FontID=1|IsHidden=T|Text=1|Name=Package Quantity
|RECORD=41|OwnerIndex=824|IndexInSheet=14|OwnerPartId=-1|Location.X=1549|Location.Y=927|Color=8388608|FontID=1|IsHidden=T|Text=Ceramic|Name=Dielectric Material
|RECORD=41|OwnerIndex=824|IndexInSheet=15|OwnerPartId=-1|Location.X=1549|Location.Y=927|Color=8388608|FontID=1|IsHidden=T|Text=1mm|Name=Length
|RECORD=41|OwnerIndex=824|IndexInSheet=16|OwnerPartId=-1|Location.X=1549|Location.Y=927|Color=8388608|FontID=1|IsHidden=T|Text=Tape and Reel|Name=Packaging
|RECORD=41|OwnerIndex=824|IndexInSheet=17|OwnerPartId=-1|Location.X=1549|Location.Y=927|Color=8388608|FontID=1|IsHidden=T|Text=1005|Name=Case Code (Metric)
|RECORD=41|OwnerIndex=824|IndexInSheet=18|OwnerPartId=-1|Location.X=1549|Location.Y=927|Color=8388608|FontID=1|IsHidden=T|Text=Yes|Name=RoHS Compliant
|RECORD=41|OwnerIndex=824|IndexInSheet=19|OwnerPartId=-1|Location.X=1549|Location.Y=927|Color=8388608|FontID=1|IsHidden=T|Text=X5R|Name=Dielectric
|RECORD=41|OwnerIndex=824|IndexInSheet=20|OwnerPartId=-1|Location.X=1549|Location.Y=927|Color=8388608|FontID=1|IsHidden=T|Text=85°C|Name=Max Operating Temperature
|RECORD=41|OwnerIndex=824|IndexInSheet=21|OwnerPartId=-1|Location.X=1549|Location.Y=927|Color=8388608|FontID=1|IsHidden=T|Text=Lead Free|Name=Lead Free
|RECORD=41|OwnerIndex=824|IndexInSheet=22|OwnerPartId=-1|Location.X=1549|Location.Y=927|Color=8388608|FontID=1|IsHidden=T|Text=2.3E-05oz|Name=Weight
|RECORD=41|OwnerIndex=824|IndexInSheet=23|OwnerPartId=-1|Location.X=1549|Location.Y=927|Color=8388608|FontID=1|IsHidden=T|Text=0.022inch|Name=Thickness
|RECORD=41|OwnerIndex=824|IndexInSheet=24|OwnerPartId=-1|Location.X=1549|Location.Y=927|Color=8388608|FontID=1|IsHidden=T|Text=2.2uF|Name=Capacitance
|RECORD=41|OwnerIndex=824|IndexInSheet=25|OwnerPartId=-1|Location.X=1549|Location.Y=927|Color=8388608|FontID=1|IsHidden=T|Text=16V|Name=Voltage Rating (DC)
|RECORD=41|OwnerIndex=824|IndexInSheet=26|OwnerPartId=-1|Location.X=1549|Location.Y=927|Color=8388608|FontID=1|IsHidden=T|Text=10%|Name=Tolerance
|RECORD=41|OwnerIndex=824|IndexInSheet=27|OwnerPartId=-1|Location.X=1549|Location.Y=927|Color=8388608|FontID=1|IsHidden=T|Text=16V|Name=Voltage Rating
|RECORD=41|OwnerIndex=824|IndexInSheet=28|OwnerPartId=-1|Location.X=1549|Location.Y=927|Color=8388608|FontID=1|IsHidden=T|Text=Ceramic|Name=Resistor Type
|RECORD=41|OwnerIndex=824|IndexInSheet=29|OwnerPartId=-1|Location.X=1549|Location.Y=927|Color=8388608|FontID=1|IsHidden=T|Text=0.5mm|Name=Height
|RECORD=41|OwnerIndex=824|IndexInSheet=30|OwnerPartId=-1|Location.X=1549|Location.Y=927|Color=8388608|FontID=1|IsHidden=T|Text=0402|Name=Case/Package
|RECORD=41|OwnerIndex=824|IndexInSheet=31|OwnerPartId=-1|Location.X=1549|Location.Y=927|Color=8388608|FontID=1|IsHidden=T|Text=-55°C|Name=Min Operating Temperature
|RECORD=34|OwnerIndex=824|IndexInSheet=-1|OwnerPartId=-1|Location.X=1550|Location.Y=905|Orientation=1|Color=8388608|FontID=2|Text=C16|Name=Designator|ReadOnlyState=1
|RECORD=41|OwnerIndex=824|IndexInSheet=-1|OwnerPartId=1|Location.X=1580|Location.Y=880|Orientation=1|Color=8388608|FontID=2|Text=2.2uF_16V_0402|Name=Comment
|RECORD=44|OwnerIndex=824
|RECORD=45|OwnerIndex=861|IndexInSheet=-1|UseComponentLibrary=T|ModelName=FP-C1005-050-0_05-IPC_A|ModelType=PCBLIB|DatafileCount=1|ModelDatafileEntity0=FP-C1005-050-0_05-IPC_A|ModelDatafileKind0=PCBLib|IsCurrent=T|DatalinksLocked=T|DatabaseDatalinksLocked=T
|RECORD=46|OwnerIndex=862
|RECORD=48|OwnerIndex=862
|RECORD=45|OwnerIndex=861|IndexInSheet=-1|UseComponentLibrary=T|ModelName=FP-C1005-050-0_05-MFG|ModelType=PCBLIB|DatafileCount=1|ModelDatafileEntity0=FP-C1005-050-0_05-MFG|ModelDatafileKind0=PCBLib|DatalinksLocked=T|DatabaseDatalinksLocked=T
|RECORD=46|OwnerIndex=865
|RECORD=48|OwnerIndex=865
|RECORD=45|OwnerIndex=861|IndexInSheet=-1|UseComponentLibrary=T|ModelName=FP-C1005-050-0_05-IPC_C|ModelType=PCBLIB|DatafileCount=1|ModelDatafileEntity0=FP-C1005-050-0_05-IPC_C|ModelDatafileKind0=PCBLib|DatalinksLocked=T|DatabaseDatalinksLocked=T
|RECORD=46|OwnerIndex=868
|RECORD=48|OwnerIndex=868
|RECORD=45|OwnerIndex=861|IndexInSheet=-1|UseComponentLibrary=T|ModelName=FP-C1005-050-0_05-IPC_B|ModelType=PCBLIB|DatafileCount=1|ModelDatafileEntity0=FP-C1005-050-0_05-IPC_B|ModelDatafileKind0=PCBLib|DatalinksLocked=T|DatabaseDatalinksLocked=T
|RECORD=46|OwnerIndex=871
|RECORD=48|OwnerIndex=871
|RECORD=1|LibReference=b4654b650e69147ec39a6b967a45e02|ComponentDescription=None|PartCount=2|DisplayModeCount=1|IndexInSheet=72|OwnerPartId=-1|Location.X=1605|Location.Y=925|CurrentPartId=1|LibraryPath=*|SourceLibraryName=Altium Content Vault|TargetFileName=*|AreaColor=11599871|Color=128|PartIDLocked=T|DesignItemId=CMP-14477-000104-2|AllPinCount=2
|RECORD=2|OwnerIndex=874|OwnerPartId=1|Electrical=4|PinConglomerate=49|PinLength=7|Location.X=1605|Location.Y=918|Name=1|Designator=1|PinPropagationDelay=0.000000E+000
|RECORD=2|OwnerIndex=874|OwnerPartId=1|Electrical=4|PinConglomerate=51|PinLength=6|Location.X=1605|Location.Y=911|Name=2|Designator=2|PinPropagationDelay=0.000000E+000
|RECORD=13|OwnerIndex=874|IsNotAccesible=T|IndexInSheet=2|OwnerPartId=1|Location.X=1615|Location.Y=918|Corner.X=1595|Corner.Y=918|LineWidth=1|Color=16711680
|RECORD=13|OwnerIndex=874|IsNotAccesible=T|IndexInSheet=3|OwnerPartId=1|Location.X=1615|Location.Y=912|Corner.X=1595|Corner.Y=912|LineWidth=1|Color=16711680
|RECORD=13|OwnerIndex=874|IsNotAccesible=T|IndexInSheet=4|OwnerPartId=1|Location.X=1605|Location.Y=918|Corner.X=1605|Corner.Y=921|LineWidth=1|Color=16711680
|RECORD=13|OwnerIndex=874|IsNotAccesible=T|IndexInSheet=5|OwnerPartId=1|Location.X=1605|Location.Y=911|Corner.X=1605|Corner.Y=910|LineWidth=1|Color=16711680
|RECORD=41|OwnerIndex=874|IndexInSheet=6|OwnerPartId=-1|Location.X=1594|Location.Y=927|Color=8388608|FontID=1|IsHidden=T|Text=Tape and Reel|Name=Packaging
|RECORD=41|OwnerIndex=874|IndexInSheet=7|OwnerPartId=-1|Location.X=1594|Location.Y=927|Color=8388608|FontID=1|IsHidden=T|Text=0.5mm|Name=Depth
|RECORD=41|OwnerIndex=874|IndexInSheet=8|OwnerPartId=-1|Location.X=1594|Location.Y=927|Color=8388608|FontID=1|IsHidden=T|Text=10%|Name=Tolerance
|RECORD=41|OwnerIndex=874|IndexInSheet=9|OwnerPartId=-1|Location.X=1594|Location.Y=927|Color=8388608|FontID=1|IsHidden=T|Text=Surface Mount|Name=Mount
|RECORD=41|OwnerIndex=874|IndexInSheet=10|OwnerPartId=-1|Location.X=1594|Location.Y=927|Color=8388608|FontID=1|IsHidden=T|Text=16V|Name=Voltage Rating
|RECORD=41|OwnerIndex=874|IndexInSheet=11|OwnerPartId=-1|Location.X=1594|Location.Y=927|Color=8388608|FontID=1|IsHidden=T|Text=0.022inch|Name=Thickness
|RECORD=41|OwnerIndex=874|IndexInSheet=12|OwnerPartId=-1|Location.X=1594|Location.Y=927|Color=8388608|FontID=1|IsHidden=T|Text=1|Name=Package Quantity
|RECORD=41|OwnerIndex=874|IndexInSheet=13|OwnerPartId=-1|Location.X=1594|Location.Y=927|Color=8388608|FontID=1|IsHidden=T|Text=-55°C|Name=Min Operating Temperature
|RECORD=41|OwnerIndex=874|IndexInSheet=14|OwnerPartId=-1|Location.X=1594|Location.Y=927|Color=8388608|FontID=1|IsHidden=T|Text=M|Name=Series
|RECORD=41|OwnerIndex=874|IndexInSheet=15|OwnerPartId=-1|Location.X=1594|Location.Y=927|Color=8388608|FontID=1|IsHidden=T|Text=16V|Name=Voltage Rating (DC)
|RECORD=41|OwnerIndex=874|IndexInSheet=16|OwnerPartId=-1|Location.X=1594|Location.Y=927|Color=8388608|FontID=1|IsHidden=T|Text=SMD/SMT|Name=Termination
|RECORD=41|OwnerIndex=874|IndexInSheet=17|OwnerPartId=-1|Location.X=1594|Location.Y=927|Color=8388608|FontID=1|IsHidden=T|Text=0402|Name=Case/Package
|RECORD=41|OwnerIndex=874|IndexInSheet=18|OwnerPartId=-1|Location.X=1594|Location.Y=927|Color=8388608|FontID=1|IsHidden=T|Text=X5R|Name=Dielectric
|RECORD=41|OwnerIndex=874|IndexInSheet=19|OwnerPartId=-1|Location.X=1594|Location.Y=927|Color=8388608|FontID=1|IsHidden=T|Text=2|Name=Number of Pins
|RECORD=41|OwnerIndex=874|IndexInSheet=20|OwnerPartId=-1|Location.X=1594|Location.Y=927|Color=8388608|FontID=1|IsHidden=T|Text=0402|Name=Case Code (Imperial)
|RECORD=41|OwnerIndex=874|IndexInSheet=21|OwnerPartId=-1|Location.X=1594|Location.Y=927|Color=8388608|FontID=1|IsHidden=T|Text=1uF|Name=Capacitance
|RECORD=41|OwnerIndex=874|IndexInSheet=22|OwnerPartId=-1|Location.X=1594|Location.Y=927|Color=8388608|FontID=1|IsHidden=T|Text=1mm|Name=Length
|RECORD=41|OwnerIndex=874|IndexInSheet=23|OwnerPartId=-1|Location.X=1594|Location.Y=927|Color=8388608|FontID=1|IsHidden=T|Text=Halogen Free|Name=Halogen Free
|RECORD=41|OwnerIndex=874|IndexInSheet=24|OwnerPartId=-1|Location.X=1594|Location.Y=927|Color=8388608|FontID=1|IsHidden=T|Text=1005|Name=Case Code (Metric)
|RECORD=41|OwnerIndex=874|IndexInSheet=25|OwnerPartId=-1|Location.X=1594|Location.Y=927|Color=8388608|FontID=1|IsHidden=T|Text=0.02inch|Name=Width
|RECORD=41|OwnerIndex=874|IndexInSheet=26|OwnerPartId=-1|Location.X=1594|Location.Y=927|Color=8388608|FontID=1|IsHidden=T|Text=Yes|Name=RoHS Compliant
|RECORD=41|OwnerIndex=874|IndexInSheet=27|OwnerPartId=-1|Location.X=1594|Location.Y=927|Color=8388608|FontID=1|IsHidden=T|Text=No|Name=Radiation Hardening
|RECORD=41|OwnerIndex=874|IndexInSheet=28|OwnerPartId=-1|Location.X=1594|Location.Y=927|Color=8388608|FontID=1|IsHidden=T|Text=85°C|Name=Max Operating Temperature
|RECORD=41|OwnerIndex=874|IndexInSheet=29|OwnerPartId=-1|Location.X=1594|Location.Y=927|Color=8388608|FontID=1|IsHidden=T|Text=0.5mm|Name=Height
|RECORD=41|OwnerIndex=874|IndexInSheet=30|OwnerPartId=-1|Location.X=1594|Location.Y=927|Color=8388608|FontID=1|IsHidden=T|Text=Flat|Name=Construction
|RECORD=34|OwnerIndex=874|IndexInSheet=-1|OwnerPartId=-1|Location.X=1590|Location.Y=905|Orientation=1|Color=8388608|FontID=2|Text=C17|Name=Designator|ReadOnlyState=1
|RECORD=41|OwnerIndex=874|IndexInSheet=-1|OwnerPartId=1|Location.X=1625|Location.Y=890|Orientation=1|Color=8388608|FontID=2|Text=1uF_16V_0402|Name=Comment
|RECORD=44|OwnerIndex=874
|RECORD=45|OwnerIndex=910|IndexInSheet=-1|UseComponentLibrary=T|ModelName=FP-0402-L_1_0_0_05-W_0_5-IPC_A|ModelType=PCBLIB|DatafileCount=1|ModelDatafileEntity0=FP-0402-L_1_0_0_05-W_0_5-IPC_A|ModelDatafileKind0=PCBLib|IsCurrent=T|DatalinksLocked=T|DatabaseDatalinksLocked=T
|RECORD=46|OwnerIndex=911
|RECORD=48|OwnerIndex=911
|RECORD=45|OwnerIndex=910|IndexInSheet=-1|UseComponentLibrary=T|ModelName=EMK105BJ105_V-F|ModelType=SIM|IsCurrent=T|DatalinksLocked=T|DatabaseDatalinksLocked=T
|RECORD=46|OwnerIndex=914
|RECORD=48|OwnerIndex=914
|RECORD=41|OwnerIndex=916|IndexInSheet=-1|OwnerPartId=-1|Color=8388608|FontID=1|IsHidden=T|Text=General|Name=Kind
|RECORD=41|OwnerIndex=916|IndexInSheet=-1|OwnerPartId=-1|Color=8388608|FontID=1|IsHidden=T|Text=Spice Subcircuit|Name=SubKind
|RECORD=41|OwnerIndex=916|IndexInSheet=-1|OwnerPartId=-1|Color=8388608|FontID=1|IsHidden=T|Name=Spice Prefix
|RECORD=41|OwnerIndex=916|IndexInSheet=-1|OwnerPartId=-1|Color=8388608|FontID=1|IsHidden=T|Name=Excluded Parts
|RECORD=41|OwnerIndex=916|IndexInSheet=-1|OwnerPartId=-1|Color=8388608|FontID=1|IsHidden=T|Name=Netlist
|RECORD=41|OwnerIndex=916|IndexInSheet=-1|OwnerPartId=-1|Color=8388608|FontID=1|IsHidden=T|Text=document_sim_cache\GNEMVTBT\0|Name=SimulationCacheLocation|ReadOnlyState=3
|RECORD=45|OwnerIndex=910|IndexInSheet=-1|UseComponentLibrary=T|ModelName=FP-0402-L_1_0_0_05-W_0_5-IPC_B|ModelType=PCBLIB|DatafileCount=1|ModelDatafileEntity0=FP-0402-L_1_0_0_05-W_0_5-IPC_B|ModelDatafileKind0=PCBLib|DatalinksLocked=T|DatabaseDatalinksLocked=T
|RECORD=46|OwnerIndex=923
|RECORD=48|OwnerIndex=923
|RECORD=45|OwnerIndex=910|IndexInSheet=-1|UseComponentLibrary=T|ModelName=FP-0402-L_1_0_0_05-W_0_5-IPC_C|ModelType=PCBLIB|DatafileCount=1|ModelDatafileEntity0=FP-0402-L_1_0_0_05-W_0_5-IPC_C|ModelDatafileKind0=PCBLib|DatalinksLocked=T|DatabaseDatalinksLocked=T
|RECORD=46|OwnerIndex=926
|RECORD=48|OwnerIndex=926
|RECORD=45|OwnerIndex=910|IndexInSheet=-1|UseComponentLibrary=T|ModelName=FP-0402-L_1_0_0_05-W_0_5-MFG|ModelType=PCBLIB|DatafileCount=1|ModelDatafileEntity0=FP-0402-L_1_0_0_05-W_0_5-MFG|ModelDatafileKind0=PCBLib|DatalinksLocked=T|DatabaseDatalinksLocked=T
|RECORD=46|OwnerIndex=929
|RECORD=48|OwnerIndex=929
|RECORD=1|LibReference=b4654b650e69147ec39a6b967a45e02|ComponentDescription=General Purpose Ceramic Capacitor, 0402, 100nF, 10%, X7R, 15%, 25V|PartCount=2|DisplayModeCount=1|IndexInSheet=73|OwnerPartId=-1|Location.X=1645|Location.Y=925|CurrentPartId=1|LibraryPath=*|SourceLibraryName=Altium Content Vault|TargetFileName=*|AreaColor=11599871|Color=128|PartIDLocked=T|DesignItemId=CMP-2008-02519-2|AllPinCount=2
|RECORD=2|OwnerIndex=932|OwnerPartId=1|Electrical=4|PinConglomerate=49|PinLength=7|Location.X=1645|Location.Y=918|Name=1|Designator=1|PinPropagationDelay=0.000000E+000
|RECORD=2|OwnerIndex=932|OwnerPartId=1|Electrical=4|PinConglomerate=51|PinLength=6|Location.X=1645|Location.Y=911|Name=2|Designator=2|PinPropagationDelay=0.000000E+000
|RECORD=13|OwnerIndex=932|IsNotAccesible=T|IndexInSheet=2|OwnerPartId=1|Location.X=1655|Location.Y=918|Corner.X=1635|Corner.Y=918|LineWidth=1|Color=16711680
|RECORD=13|OwnerIndex=932|IsNotAccesible=T|IndexInSheet=3|OwnerPartId=1|Location.X=1655|Location.Y=912|Corner.X=1635|Corner.Y=912|LineWidth=1|Color=16711680
|RECORD=13|OwnerIndex=932|IsNotAccesible=T|IndexInSheet=4|OwnerPartId=1|Location.X=1645|Location.Y=918|Corner.X=1645|Corner.Y=921|LineWidth=1|Color=16711680
|RECORD=13|OwnerIndex=932|IsNotAccesible=T|IndexInSheet=5|OwnerPartId=1|Location.X=1645|Location.Y=911|Corner.X=1645|Corner.Y=910|LineWidth=1|Color=16711680
|RECORD=41|OwnerIndex=932|IndexInSheet=6|OwnerPartId=-1|Location.X=1634|Location.Y=927|Color=8388608|FontID=1|IsHidden=T|Text=1|Name=Package Quantity
|RECORD=41|OwnerIndex=932|IndexInSheet=7|OwnerPartId=-1|Location.X=1634|Location.Y=927|Color=8388608|FontID=1|IsHidden=T|Text=100nF|Name=Capacitance
|RECORD=41|OwnerIndex=932|IndexInSheet=8|OwnerPartId=-1|Location.X=1634|Location.Y=927|Color=8388608|FontID=1|IsHidden=T|Text=-55°C|Name=Min Operating Temperature
|RECORD=41|OwnerIndex=932|IndexInSheet=9|OwnerPartId=-1|Location.X=1634|Location.Y=927|Color=8388608|FontID=1|IsHidden=T|Text=25V|Name=Voltage
|RECORD=41|OwnerIndex=932|IndexInSheet=10|OwnerPartId=-1|Location.X=1634|Location.Y=927|Color=8388608|FontID=1|IsHidden=T|Text=25V|Name=Voltage Rating
|RECORD=41|OwnerIndex=932|IndexInSheet=11|OwnerPartId=-1|Location.X=1634|Location.Y=927|Color=8388608|FontID=1|IsHidden=T|Text=Flat|Name=Construction
|RECORD=41|OwnerIndex=932|IndexInSheet=12|OwnerPartId=-1|Location.X=1634|Location.Y=927|Color=8388608|FontID=1|IsHidden=T|Text=125°C|Name=Max Operating Temperature
|RECORD=41|OwnerIndex=932|IndexInSheet=13|OwnerPartId=-1|Location.X=1634|Location.Y=927|Color=8388608|FontID=1|IsHidden=T|Text=No|Name=Radiation Hardening
|RECORD=41|OwnerIndex=932|IndexInSheet=14|OwnerPartId=-1|Location.X=1634|Location.Y=927|Color=8388608|FontID=1|IsHidden=T|Text=0.5mm|Name=Depth
|RECORD=41|OwnerIndex=932|IndexInSheet=15|OwnerPartId=-1|Location.X=1634|Location.Y=927|Color=8388608|FontID=1|IsHidden=T|Text=0.022inch|Name=Thickness
|RECORD=41|OwnerIndex=932|IndexInSheet=16|OwnerPartId=-1|Location.X=1634|Location.Y=927|Color=8388608|FontID=1|IsHidden=T|Text=25V|Name=Voltage Rating (DC)
|RECORD=41|OwnerIndex=932|IndexInSheet=17|OwnerPartId=-1|Location.X=1634|Location.Y=927|Color=8388608|FontID=1|IsHidden=T|Text=2|Name=Number of Pins
|RECORD=41|OwnerIndex=932|IndexInSheet=18|OwnerPartId=-1|Location.X=1634|Location.Y=927|Color=8388608|FontID=1|IsHidden=T|Text=Lead Free|Name=Lead Free
|RECORD=41|OwnerIndex=932|IndexInSheet=19|OwnerPartId=-1|Location.X=1634|Location.Y=927|Color=8388608|FontID=1|IsHidden=T|Text=-|Name=Series
|RECORD=41|OwnerIndex=932|IndexInSheet=20|OwnerPartId=-1|Location.X=1634|Location.Y=927|Color=8388608|FontID=1|IsHidden=T|Text=No SVHC|Name=REACH SVHC
|RECORD=41|OwnerIndex=932|IndexInSheet=21|OwnerPartId=-1|Location.X=1634|Location.Y=927|Color=8388608|FontID=1|IsHidden=T|Text=1mm|Name=Length
|RECORD=41|OwnerIndex=932|IndexInSheet=22|OwnerPartId=-1|Location.X=1634|Location.Y=927|Color=8388608|FontID=1|IsHidden=T|Text=X7R|Name=Dielectric
|RECORD=41|OwnerIndex=932|IndexInSheet=23|OwnerPartId=-1|Location.X=1634|Location.Y=927|Color=8388608|FontID=1|IsHidden=T|Text=Yes|Name=RoHS Compliant
|RECORD=41|OwnerIndex=932|IndexInSheet=24|OwnerPartId=-1|Location.X=1634|Location.Y=927|Color=8388608|FontID=1|IsHidden=T|Text=Surface Mount|Name=Mount
|RECORD=41|OwnerIndex=932|IndexInSheet=25|OwnerPartId=-1|Location.X=1634|Location.Y=927|Color=8388608|FontID=1|IsHidden=T|Text=Tape and Reel|Name=Packaging
|RECORD=41|OwnerIndex=932|IndexInSheet=26|OwnerPartId=-1|Location.X=1634|Location.Y=927|Color=8388608|FontID=1|IsHidden=T|Text=0402|Name=Case/Package
|RECORD=41|OwnerIndex=932|IndexInSheet=27|OwnerPartId=-1|Location.X=1634|Location.Y=927|Color=8388608|FontID=1|IsHidden=T|Text=0402|Name=Case Code (Imperial)
|RECORD=41|OwnerIndex=932|IndexInSheet=28|OwnerPartId=-1|Location.X=1634|Location.Y=927|Color=8388608|FontID=1|IsHidden=T|Text=SMD/SMT|Name=Termination
|RECORD=41|OwnerIndex=932|IndexInSheet=29|OwnerPartId=-1|Location.X=1634|Location.Y=927|Color=8388608|FontID=1|IsHidden=T|Text=0.02inch|Name=Width
|RECORD=41|OwnerIndex=932|IndexInSheet=30|OwnerPartId=-1|Location.X=1634|Location.Y=927|Color=8388608|FontID=1|IsHidden=T|Text=1005|Name=Case Code (Metric)
|RECORD=41|OwnerIndex=932|IndexInSheet=31|OwnerPartId=-1|Location.X=1634|Location.Y=927|Color=8388608|FontID=1|IsHidden=T|Text=10%|Name=Tolerance
|RECORD=34|OwnerIndex=932|IndexInSheet=-1|OwnerPartId=-1|Location.X=1635|Location.Y=905|Orientation=1|Color=8388608|FontID=2|Text=C18|Name=Designator|ReadOnlyState=1
|RECORD=41|OwnerIndex=932|IndexInSheet=-1|OwnerPartId=1|Location.X=1665|Location.Y=890|Orientation=1|Color=8388608|FontID=2|Text=0.1uF_25V_0402|Name=Comment
|RECORD=44|OwnerIndex=932
|RECORD=45|OwnerIndex=969|IndexInSheet=-1|UseComponentLibrary=T|ModelName=FP-0402-L_1_0_1-W_0_5_0_1-IPC_C|ModelType=PCBLIB|DatafileCount=1|ModelDatafileEntity0=FP-0402-L_1_0_1-W_0_5_0_1-IPC_C|ModelDatafileKind0=PCBLib|IsCurrent=T|DatalinksLocked=T|DatabaseDatalinksLocked=T
|RECORD=46|OwnerIndex=970
|RECORD=48|OwnerIndex=970
|RECORD=45|OwnerIndex=969|IndexInSheet=-1|UseComponentLibrary=T|ModelName=FP-0402-L_1_0_1-W_0_5_0_1-IPC_B|ModelType=PCBLIB|DatafileCount=1|ModelDatafileEntity0=FP-0402-L_1_0_1-W_0_5_0_1-IPC_B|ModelDatafileKind0=PCBLib|DatalinksLocked=T|DatabaseDatalinksLocked=T
|RECORD=46|OwnerIndex=973
|RECORD=48|OwnerIndex=973
|RECORD=45|OwnerIndex=969|IndexInSheet=-1|UseComponentLibrary=T|ModelName=FP-0402-L_1_0_1-W_0_5_0_1-MFG|ModelType=PCBLIB|DatafileCount=1|ModelDatafileEntity0=FP-0402-L_1_0_1-W_0_5_0_1-MFG|ModelDatafileKind0=PCBLib|DatalinksLocked=T|DatabaseDatalinksLocked=T
|RECORD=46|OwnerIndex=976
|RECORD=48|OwnerIndex=976
|RECORD=45|OwnerIndex=969|IndexInSheet=-1|UseComponentLibrary=T|ModelName=FP-0402-L_1_0_1-W_0_5_0_1-IPC_A|ModelType=PCBLIB|DatafileCount=1|ModelDatafileEntity0=FP-0402-L_1_0_1-W_0_5_0_1-IPC_A|ModelDatafileKind0=PCBLib|DatalinksLocked=T|DatabaseDatalinksLocked=T
|RECORD=46|OwnerIndex=979
|RECORD=48|OwnerIndex=979
|RECORD=1|LibReference=11868f565c42a9108669ba33697ecf6|ComponentDescription=Multilayer Ceramic Capacitors 47uF ±20% 16V X5R SMD 1206|PartCount=2|DisplayModeCount=1|IndexInSheet=74|OwnerPartId=-1|Location.X=1475|Location.Y=925|CurrentPartId=1|LibraryPath=*|SourceLibraryName=Altium Content Vault|TargetFileName=*|AreaColor=11599871|Color=128|PartIDLocked=T|DesignItemId=CMP-2000-07442-2|AllPinCount=2
|RECORD=2|OwnerIndex=982|OwnerPartId=1|Electrical=4|PinConglomerate=49|PinLength=7|Location.X=1475|Location.Y=918|Name=1|Designator=1|PinPropagationDelay=0.000000E+000
|RECORD=2|OwnerIndex=982|OwnerPartId=1|Electrical=4|PinConglomerate=51|PinLength=6|Location.X=1475|Location.Y=911|Name=2|Designator=2|PinPropagationDelay=0.000000E+000
|RECORD=13|OwnerIndex=982|IsNotAccesible=T|IndexInSheet=2|OwnerPartId=1|Location.X=1485|Location.Y=918|Corner.X=1465|Corner.Y=918|LineWidth=1|Color=16711680
|RECORD=13|OwnerIndex=982|IsNotAccesible=T|IndexInSheet=3|OwnerPartId=1|Location.X=1485|Location.Y=912|Corner.X=1465|Corner.Y=912|LineWidth=1|Color=16711680
|RECORD=13|OwnerIndex=982|IsNotAccesible=T|IndexInSheet=4|OwnerPartId=1|Location.X=1475|Location.Y=918|Corner.X=1475|Corner.Y=921|LineWidth=1|Color=16711680
|RECORD=13|OwnerIndex=982|IsNotAccesible=T|IndexInSheet=5|OwnerPartId=1|Location.X=1475|Location.Y=911|Corner.X=1475|Corner.Y=910|LineWidth=1|Color=16711680
|RECORD=41|OwnerIndex=982|IndexInSheet=6|OwnerPartId=-1|Location.X=1464|Location.Y=927|Color=8388608|FontID=1|IsHidden=T|Text=Ceramic|Name=Resistor Type
|RECORD=41|OwnerIndex=982|IndexInSheet=7|OwnerPartId=-1|Location.X=1464|Location.Y=927|Color=8388608|FontID=1|IsHidden=T|Text=0.063inch|Name=Width
|RECORD=41|OwnerIndex=982|IndexInSheet=8|OwnerPartId=-1|Location.X=1464|Location.Y=927|Color=8388608|FontID=1|IsHidden=T|Text=1206|Name=Case Code (Imperial)
|RECORD=41|OwnerIndex=982|IndexInSheet=9|OwnerPartId=-1|Location.X=1464|Location.Y=927|Color=8388608|FontID=1|IsHidden=T|Text=No|Name=Radiation Hardening
|RECORD=41|OwnerIndex=982|IndexInSheet=10|OwnerPartId=-1|Location.X=1464|Location.Y=927|Color=8388608|FontID=1|IsHidden=T|Text=0.071inch|Name=Thickness
|RECORD=41|OwnerIndex=982|IndexInSheet=11|OwnerPartId=-1|Location.X=1464|Location.Y=927|Color=8388608|FontID=1|IsHidden=T|Text=X5R|Name=Dielectric
|RECORD=41|OwnerIndex=982|IndexInSheet=12|OwnerPartId=-1|Location.X=1464|Location.Y=927|Color=8388608|FontID=1|IsHidden=T|Text=0.000571oz|Name=Weight
|RECORD=41|OwnerIndex=982|IndexInSheet=13|OwnerPartId=-1|Location.X=1464|Location.Y=927|Color=8388608|FontID=1|IsHidden=T|Text=SMD/SMT|Name=Termination
|RECORD=41|OwnerIndex=982|IndexInSheet=14|OwnerPartId=-1|Location.X=1464|Location.Y=927|Color=8388608|FontID=1|IsHidden=T|Text=Ceramic|Name=Dielectric Material
|RECORD=41|OwnerIndex=982|IndexInSheet=15|OwnerPartId=-1|Location.X=1464|Location.Y=927|Color=8388608|FontID=1|IsHidden=T|Text=-55°C|Name=Min Operating Temperature
|RECORD=41|OwnerIndex=982|IndexInSheet=16|OwnerPartId=-1|Location.X=1464|Location.Y=927|Color=8388608|FontID=1|IsHidden=T|Text=1.6mm|Name=Depth
|RECORD=41|OwnerIndex=982|IndexInSheet=17|OwnerPartId=-1|Location.X=1464|Location.Y=927|Color=8388608|FontID=1|IsHidden=T|Text=3216|Name=Case Code (Metric)
|RECORD=41|OwnerIndex=982|IndexInSheet=18|OwnerPartId=-1|Location.X=1464|Location.Y=927|Color=8388608|FontID=1|IsHidden=T|Text=85°C|Name=Max Operating Temperature
|RECORD=41|OwnerIndex=982|IndexInSheet=19|OwnerPartId=-1|Location.X=1464|Location.Y=927|Color=8388608|FontID=1|IsHidden=T|Text=Yes|Name=RoHS Compliant
|RECORD=41|OwnerIndex=982|IndexInSheet=20|OwnerPartId=-1|Location.X=1464|Location.Y=927|Color=8388608|FontID=1|IsHidden=T|Text=No SVHC|Name=REACH SVHC
|RECORD=41|OwnerIndex=982|IndexInSheet=21|OwnerPartId=-1|Location.X=1464|Location.Y=927|Color=8388608|FontID=1|IsHidden=T|Text=Surface Mount|Name=Mount
|RECORD=41|OwnerIndex=982|IndexInSheet=22|OwnerPartId=-1|Location.X=1464|Location.Y=927|Color=8388608|FontID=1|IsHidden=T|Text=Lead Free|Name=Lead Free
|RECORD=41|OwnerIndex=982|IndexInSheet=23|OwnerPartId=-1|Location.X=1464|Location.Y=927|Color=8388608|FontID=1|IsHidden=T|Text=1.6mm|Name=Height
|RECORD=41|OwnerIndex=982|IndexInSheet=24|OwnerPartId=-1|Location.X=1464|Location.Y=927|Color=8388608|FontID=1|IsHidden=T|Text=3.2mm|Name=Length
|RECORD=41|OwnerIndex=982|IndexInSheet=25|OwnerPartId=-1|Location.X=1464|Location.Y=927|Color=8388608|FontID=1|IsHidden=T|Text=20%|Name=Tolerance
|RECORD=41|OwnerIndex=982|IndexInSheet=26|OwnerPartId=-1|Location.X=1464|Location.Y=927|Color=8388608|FontID=1|IsHidden=T|Text=16V|Name=Voltage Rating (DC)
|RECORD=41|OwnerIndex=982|IndexInSheet=27|OwnerPartId=-1|Location.X=1464|Location.Y=927|Color=8388608|FontID=1|IsHidden=T|Text=47uF|Name=Capacitance
|RECORD=41|OwnerIndex=982|IndexInSheet=28|OwnerPartId=-1|Location.X=1464|Location.Y=927|Color=8388608|FontID=1|IsHidden=T|Text=1|Name=Package Quantity
|RECORD=41|OwnerIndex=982|IndexInSheet=29|OwnerPartId=-1|Location.X=1464|Location.Y=927|Color=8388608|FontID=1|IsHidden=T|Text=Flat|Name=Construction
|RECORD=41|OwnerIndex=982|IndexInSheet=30|OwnerPartId=-1|Location.X=1464|Location.Y=927|Color=8388608|FontID=1|IsHidden=T|Text=Tape and Reel|Name=Packaging
|RECORD=41|OwnerIndex=982|IndexInSheet=31|OwnerPartId=-1|Location.X=1464|Location.Y=927|Color=8388608|FontID=1|IsHidden=T|Text=C|Name=Series
|RECORD=41|OwnerIndex=982|IndexInSheet=32|OwnerPartId=-1|Location.X=1464|Location.Y=927|Color=8388608|FontID=1|IsHidden=T|Text=1206|Name=Case/Package
|RECORD=41|OwnerIndex=982|IndexInSheet=33|OwnerPartId=-1|Location.X=1464|Location.Y=927|Color=8388608|FontID=1|IsHidden=T|Text=16V|Name=Voltage Rating
|RECORD=34|OwnerIndex=982|IndexInSheet=-1|OwnerPartId=-1|Location.X=1465|Location.Y=910|Orientation=1|Color=8388608|FontID=2|Text=C13|Name=Designator|ReadOnlyState=1
|RECORD=41|OwnerIndex=982|IndexInSheet=-1|OwnerPartId=1|Location.X=1495|Location.Y=885|Orientation=1|Color=8388608|FontID=2|Text=47uF_16V_1206|Name=Comment
|RECORD=44|OwnerIndex=982
|RECORD=45|OwnerIndex=1021|IndexInSheet=-1|UseComponentLibrary=T|ModelName=FP-C3216-160-0_2-MFG|ModelType=PCBLIB|DatafileCount=1|ModelDatafileEntity0=FP-C3216-160-0_2-MFG|ModelDatafileKind0=PCBLib|IsCurrent=T|DatalinksLocked=T|DatabaseDatalinksLocked=T
|RECORD=46|OwnerIndex=1022
|RECORD=48|OwnerIndex=1022
|RECORD=45|OwnerIndex=1021|IndexInSheet=-1|UseComponentLibrary=T|ModelName=FP-C3216-160-0_2-IPC_B|ModelType=PCBLIB|DatafileCount=1|ModelDatafileEntity0=FP-C3216-160-0_2-IPC_B|ModelDatafileKind0=PCBLib|DatalinksLocked=T|DatabaseDatalinksLocked=T
|RECORD=46|OwnerIndex=1025
|RECORD=48|OwnerIndex=1025
|RECORD=45|OwnerIndex=1021|IndexInSheet=-1|UseComponentLibrary=T|ModelName=FP-C3216-160-0_2-IPC_C|ModelType=PCBLIB|DatafileCount=1|ModelDatafileEntity0=FP-C3216-160-0_2-IPC_C|ModelDatafileKind0=PCBLib|DatalinksLocked=T|DatabaseDatalinksLocked=T
|RECORD=46|OwnerIndex=1028
|RECORD=48|OwnerIndex=1028
|RECORD=45|OwnerIndex=1021|IndexInSheet=-1|UseComponentLibrary=T|ModelName=FP-C3216-160-0_2-IPC_A|ModelType=PCBLIB|DatafileCount=1|ModelDatafileEntity0=FP-C3216-160-0_2-IPC_A|ModelDatafileKind0=PCBLib|DatalinksLocked=T|DatabaseDatalinksLocked=T
|RECORD=46|OwnerIndex=1031
|RECORD=48|OwnerIndex=1031
|RECORD=17|IndexInSheet=75|OwnerPartId=-1|Style=4|ShowNetName=T|Location.X=1430|Location.Y=865|Orientation=3|Color=128|FontID=1|Text=GND
|RECORD=1|LibReference=41cc1aee4cbc9fa2660a15773fa0e79|ComponentDescription=IC MONITOR PWR/CURR BIDIR 8-SOIC|PartCount=2|DisplayModeCount=1|IndexInSheet=76|OwnerPartId=-1|Location.X=1385|Location.Y=780|CurrentPartId=1|LibraryPath=*|SourceLibraryName=Altium Content Vault|TargetFileName=*|AreaColor=11599871|Color=128|PartIDLocked=T|DesignItemId=CMP-0704-00005-3|AllPinCount=8
|RECORD=14|OwnerIndex=1035|IsNotAccesible=T|OwnerPartId=1|Location.X=1405|Location.Y=700|Corner.X=1495|Corner.Y=790|LineWidth=1|Color=128|AreaColor=11599871|IsSolid=T
|RECORD=2|OwnerIndex=1035|OwnerPartId=1|PinConglomerate=58|PinLength=20|Location.X=1405|Location.Y=720|Name=VIN+|Designator=8|PinName_PositionConglomerate=16|Name_CustomFontID=1|PinDesignator_PositionConglomerate=16|Designator_CustomFontID=1|PinPropagationDelay=0.000000E+000
|RECORD=2|OwnerIndex=1035|OwnerPartId=1|PinConglomerate=58|PinLength=20|Location.X=1405|Location.Y=710|Name=VIN-|Designator=7|PinName_PositionConglomerate=16|Name_CustomFontID=1|PinDesignator_PositionConglomerate=16|Designator_CustomFontID=1|PinPropagationDelay=0.000000E+000
|RECORD=2|OwnerIndex=1035|OwnerPartId=1|PinConglomerate=56|PinLength=20|Location.X=1495|Location.Y=740|Name=A0|Designator=2|PinName_PositionConglomerate=16|Name_CustomFontID=1|PinDesignator_PositionConglomerate=16|Designator_CustomFontID=1|PinPropagationDelay=0.000000E+000
|RECORD=2|OwnerIndex=1035|OwnerPartId=1|PinConglomerate=56|PinLength=20|Location.X=1495|Location.Y=730|Name=A1|Designator=1|PinName_PositionConglomerate=16|Name_CustomFontID=1|PinDesignator_PositionConglomerate=16|Designator_CustomFontID=1|PinPropagationDelay=0.000000E+000
|RECORD=2|OwnerIndex=1035|OwnerPartId=1|SymBol_InnerEdge=3|Electrical=1|PinConglomerate=56|PinLength=20|Location.X=1495|Location.Y=760|Name=SCL|Designator=4|PinName_PositionConglomerate=16|Name_CustomFontID=1|PinDesignator_PositionConglomerate=16|Designator_CustomFontID=1|PinPropagationDelay=0.000000E+000
|RECORD=2|OwnerIndex=1035|OwnerPartId=1|Electrical=1|PinConglomerate=56|PinLength=20|Location.X=1495|Location.Y=780|Name=SDA|Designator=3|PinName_PositionConglomerate=16|Name_CustomFontID=1|PinDesignator_PositionConglomerate=16|Designator_CustomFontID=1|PinPropagationDelay=0.000000E+000
|RECORD=2|OwnerIndex=1035|OwnerPartId=1|Electrical=7|PinConglomerate=58|PinLength=20|Location.X=1405|Location.Y=780|Name=VS|Designator=5|PinName_PositionConglomerate=16|Name_CustomFontID=1|PinDesignator_PositionConglomerate=16|Designator_CustomFontID=1|PinPropagationDelay=0.000000E+000
|RECORD=2|OwnerIndex=1035|OwnerPartId=1|Electrical=7|PinConglomerate=56|PinLength=20|Location.X=1495|Location.Y=710|Name=GND|Designator=6|PinName_PositionConglomerate=16|Name_CustomFontID=1|PinDesignator_PositionConglomerate=16|Designator_CustomFontID=1|PinPropagationDelay=0.000000E+000
|RECORD=41|OwnerIndex=1035|IndexInSheet=9|OwnerPartId=-1|Location.X=1383|Location.Y=790|Color=8388608|FontID=1|IsHidden=T|Text=3V|Name=Min Supply Voltage
|RECORD=41|OwnerIndex=1035|IndexInSheet=10|OwnerPartId=-1|Location.X=1383|Location.Y=790|Color=8388608|FontID=1|IsHidden=T|Text=100dB|Name=Common Mode Rejection Ratio
|RECORD=41|OwnerIndex=1035|IndexInSheet=11|OwnerPartId=-1|Location.X=1383|Location.Y=790|Color=8388608|FontID=1|IsHidden=T|Text=Tape and Reel|Name=Packaging
|RECORD=41|OwnerIndex=1035|IndexInSheet=12|OwnerPartId=-1|Location.X=1383|Location.Y=790|Color=8388608|FontID=1|IsHidden=T|Text=No SVHC|Name=REACH SVHC
|RECORD=41|OwnerIndex=1035|IndexInSheet=13|OwnerPartId=-1|Location.X=1383|Location.Y=790|Color=8388608|FontID=1|IsHidden=T|Text=125°C|Name=Max Operating Temperature
|RECORD=41|OwnerIndex=1035|IndexInSheet=14|OwnerPartId=-1|Location.X=1383|Location.Y=790|Color=8388608|FontID=1|IsHidden=T|Text=8|Name=Number of Pins
|RECORD=41|OwnerIndex=1035|IndexInSheet=15|OwnerPartId=-1|Location.X=1383|Location.Y=790|Color=8388608|FontID=1|IsHidden=T|Text=10mA|Name=Output Current
|RECORD=41|OwnerIndex=1035|IndexInSheet=16|OwnerPartId=-1|Location.X=1383|Location.Y=790|Color=8388608|FontID=1|IsHidden=T|Text=Lead Free|Name=Lead Free
|RECORD=41|OwnerIndex=1035|IndexInSheet=17|OwnerPartId=-1|Location.X=1383|Location.Y=790|Color=8388608|FontID=1|IsHidden=T|Text=1|Name=Package Quantity
|RECORD=41|OwnerIndex=1035|IndexInSheet=18|OwnerPartId=-1|Location.X=1383|Location.Y=790|Color=8388608|FontID=1|IsHidden=T|Text=No|Name=Radiation Hardening
|RECORD=41|OwnerIndex=1035|IndexInSheet=19|OwnerPartId=-1|Location.X=1383|Location.Y=790|Color=8388608|FontID=1|IsHidden=T|Text=SOIC|Name=Case/Package
|RECORD=41|OwnerIndex=1035|IndexInSheet=20|OwnerPartId=-1|Location.X=1383|Location.Y=790|Color=8388608|FontID=1|IsHidden=T|Text=1|Name=Number of Amplifiers
|RECORD=41|OwnerIndex=1035|IndexInSheet=21|OwnerPartId=-1|Location.X=1383|Location.Y=790|Color=8388608|FontID=1|IsHidden=T|Text=-40°C|Name=Min Operating Temperature
|RECORD=41|OwnerIndex=1035|IndexInSheet=22|OwnerPartId=-1|Location.X=1383|Location.Y=790|Color=8388608|FontID=1|IsHidden=T|Text=0.5%|Name=Accuracy
|RECORD=41|OwnerIndex=1035|IndexInSheet=23|OwnerPartId=-1|Location.X=1383|Location.Y=790|Color=8388608|FontID=1|IsHidden=T|Text=1mA|Name=Supply Current
|RECORD=41|OwnerIndex=1035|IndexInSheet=24|OwnerPartId=-1|Location.X=1383|Location.Y=790|Color=8388608|FontID=1|IsHidden=T|Text=Gold|Name=Contact Plating
|RECORD=41|OwnerIndex=1035|IndexInSheet=25|OwnerPartId=-1|Location.X=1383|Location.Y=790|Color=8388608|FontID=1|IsHidden=T|Text=700uA|Name=Quiescent Current
|RECORD=41|OwnerIndex=1035|IndexInSheet=26|OwnerPartId=-1|Location.X=1383|Location.Y=790|Color=8388608|FontID=1|IsHidden=T|Text=Zero-Drift|Name=Series
|RECORD=41|OwnerIndex=1035|IndexInSheet=27|OwnerPartId=-1|Location.X=1383|Location.Y=790|Color=8388608|FontID=1|IsHidden=T|Text=1mA|Name=Nominal Supply Current
|RECORD=41|OwnerIndex=1035|IndexInSheet=28|OwnerPartId=-1|Location.X=1383|Location.Y=790|Color=8388608|FontID=1|IsHidden=T|Text=11kHz|Name=Bandwidth
|RECORD=41|OwnerIndex=1035|IndexInSheet=29|OwnerPartId=-1|Location.X=1383|Location.Y=790|Color=8388608|FontID=1|IsHidden=T|Text=40uV|Name=Input Offset Voltage (Vos)
|RECORD=41|OwnerIndex=1035|IndexInSheet=30|OwnerPartId=-1|Location.X=1383|Location.Y=790|Color=8388608|FontID=1|IsHidden=T|Text=5.5V|Name=Max Supply Voltage
|RECORD=41|OwnerIndex=1035|IndexInSheet=31|OwnerPartId=-1|Location.X=1383|Location.Y=790|Color=8388608|FontID=1|IsHidden=T|Text=Yes|Name=RoHS Compliant
|RECORD=34|OwnerIndex=1035|IndexInSheet=-1|OwnerPartId=-1|Location.X=1405|Location.Y=790|Color=8388608|FontID=1|Text=U17|Name=Designator|ReadOnlyState=1
|RECORD=41|OwnerIndex=1035|IndexInSheet=-1|OwnerPartId=1|Location.X=1405|Location.Y=690|Color=8388608|FontID=1|Text=INA219BIDR|Name=Comment
|RECORD=44|OwnerIndex=1035
|RECORD=45|OwnerIndex=1078|IndexInSheet=-1|UseComponentLibrary=T|ModelName=FP-D0008A-MFG|ModelType=PCBLIB|DatafileCount=1|ModelDatafileEntity0=FP-D0008A-MFG|ModelDatafileKind0=PCBLib|IsCurrent=T|DatalinksLocked=T|DatabaseDatalinksLocked=T
|RECORD=46|OwnerIndex=1079
|RECORD=48|OwnerIndex=1079
|RECORD=45|OwnerIndex=1078|IndexInSheet=-1|UseComponentLibrary=T|ModelName=FP-D0008A-IPC_A|ModelType=PCBLIB|DatafileCount=1|ModelDatafileEntity0=FP-D0008A-IPC_A|ModelDatafileKind0=PCBLib|DatalinksLocked=T|DatabaseDatalinksLocked=T
|RECORD=46|OwnerIndex=1082
|RECORD=48|OwnerIndex=1082
|RECORD=45|OwnerIndex=1078|IndexInSheet=-1|UseComponentLibrary=T|ModelName=FP-D0008A-IPC_C|ModelType=PCBLIB|DatafileCount=1|ModelDatafileEntity0=FP-D0008A-IPC_C|ModelDatafileKind0=PCBLib|DatalinksLocked=T|DatabaseDatalinksLocked=T
|RECORD=46|OwnerIndex=1085
|RECORD=48|OwnerIndex=1085
|RECORD=45|OwnerIndex=1078|IndexInSheet=-1|UseComponentLibrary=T|ModelName=FP-D0008A-IPC_B|ModelType=PCBLIB|DatafileCount=1|ModelDatafileEntity0=FP-D0008A-IPC_B|ModelDatafileKind0=PCBLib|DatalinksLocked=T|DatabaseDatalinksLocked=T
|RECORD=46|OwnerIndex=1088
|RECORD=48|OwnerIndex=1088
|RECORD=1|LibReference=b4654b650e69147ec39a6b967a45e02|ComponentDescription=Multilayer Ceramic Capacitor 10uF 16V X5R 20% SMD 0603 T/R|PartCount=2|DisplayModeCount=1|IndexInSheet=77|OwnerPartId=-1|Location.X=1245|Location.Y=760|CurrentPartId=1|LibraryPath=*|SourceLibraryName=Altium Content Vault|TargetFileName=*|AreaColor=11599871|Color=128|PartIDLocked=T|DesignItemId=CMP-2000-06226-4|AllPinCount=2
|RECORD=2|OwnerIndex=1091|OwnerPartId=1|Electrical=4|PinConglomerate=49|PinLength=7|Location.X=1245|Location.Y=753|Name=1|Designator=1|PinPropagationDelay=0.000000E+000
|RECORD=2|OwnerIndex=1091|OwnerPartId=1|Electrical=4|PinConglomerate=51|PinLength=6|Location.X=1245|Location.Y=746|Name=2|Designator=2|PinPropagationDelay=0.000000E+000
|RECORD=13|OwnerIndex=1091|IsNotAccesible=T|IndexInSheet=2|OwnerPartId=1|Location.X=1255|Location.Y=753|Corner.X=1235|Corner.Y=753|LineWidth=1|Color=16711680
|RECORD=13|OwnerIndex=1091|IsNotAccesible=T|IndexInSheet=3|OwnerPartId=1|Location.X=1255|Location.Y=747|Corner.X=1235|Corner.Y=747|LineWidth=1|Color=16711680
|RECORD=13|OwnerIndex=1091|IsNotAccesible=T|IndexInSheet=4|OwnerPartId=1|Location.X=1245|Location.Y=753|Corner.X=1245|Corner.Y=756|LineWidth=1|Color=16711680
|RECORD=13|OwnerIndex=1091|IsNotAccesible=T|IndexInSheet=5|OwnerPartId=1|Location.X=1245|Location.Y=746|Corner.X=1245|Corner.Y=745|LineWidth=1|Color=16711680
|RECORD=41|OwnerIndex=1091|IndexInSheet=6|OwnerPartId=-1|Location.X=1234|Location.Y=762|Color=8388608|FontID=1|IsHidden=T|Text=Tape and Reel|Name=Packaging
|RECORD=41|OwnerIndex=1091|IndexInSheet=7|OwnerPartId=-1|Location.X=1234|Location.Y=762|Color=8388608|FontID=1|IsHidden=T|Text=Flat|Name=Construction
|RECORD=41|OwnerIndex=1091|IndexInSheet=8|OwnerPartId=-1|Location.X=1234|Location.Y=762|Color=8388608|FontID=1|IsHidden=T|Text=0.8mm|Name=Height
|RECORD=41|OwnerIndex=1091|IndexInSheet=9|OwnerPartId=-1|Location.X=1234|Location.Y=762|Color=8388608|FontID=1|IsHidden=T|Text=85°C|Name=Max Operating Temperature
|RECORD=41|OwnerIndex=1091|IndexInSheet=10|OwnerPartId=-1|Location.X=1234|Location.Y=762|Color=8388608|FontID=1|IsHidden=T|Text=X5R|Name=Dielectric
|RECORD=41|OwnerIndex=1091|IndexInSheet=11|OwnerPartId=-1|Location.X=1234|Location.Y=762|Color=8388608|FontID=1|IsHidden=T|Text=1608|Name=Case Code (Metric)
|RECORD=41|OwnerIndex=1091|IndexInSheet=12|OwnerPartId=-1|Location.X=1234|Location.Y=762|Color=8388608|FontID=1|IsHidden=T|Text=16V|Name=Voltage Rating (DC)
|RECORD=41|OwnerIndex=1091|IndexInSheet=13|OwnerPartId=-1|Location.X=1234|Location.Y=762|Color=8388608|FontID=1|IsHidden=T|Text=0.031inch|Name=Width
|RECORD=41|OwnerIndex=1091|IndexInSheet=14|OwnerPartId=-1|Location.X=1234|Location.Y=762|Color=8388608|FontID=1|IsHidden=T|Text=16V|Name=Voltage Rating
|RECORD=41|OwnerIndex=1091|IndexInSheet=15|OwnerPartId=-1|Location.X=1234|Location.Y=762|Color=8388608|FontID=1|IsHidden=T|Text=0.063inch|Name=Length
|RECORD=41|OwnerIndex=1091|IndexInSheet=16|OwnerPartId=-1|Location.X=1234|Location.Y=762|Color=8388608|FontID=1|IsHidden=T|Text=Yes|Name=RoHS Compliant
|RECORD=41|OwnerIndex=1091|IndexInSheet=17|OwnerPartId=-1|Location.X=1234|Location.Y=762|Color=8388608|FontID=1|IsHidden=T|Text=Halogen Free|Name=Halogen Free
|RECORD=41|OwnerIndex=1091|IndexInSheet=18|OwnerPartId=-1|Location.X=1234|Location.Y=762|Color=8388608|FontID=1|IsHidden=T|Text=0603|Name=Case Code (Imperial)
|RECORD=41|OwnerIndex=1091|IndexInSheet=19|OwnerPartId=-1|Location.X=1234|Location.Y=762|Color=8388608|FontID=1|IsHidden=T|Text=10uF|Name=Capacitance
|RECORD=41|OwnerIndex=1091|IndexInSheet=20|OwnerPartId=-1|Location.X=1234|Location.Y=762|Color=8388608|FontID=1|IsHidden=T|Text=Surface Mount|Name=Mount
|RECORD=41|OwnerIndex=1091|IndexInSheet=21|OwnerPartId=-1|Location.X=1234|Location.Y=762|Color=8388608|FontID=1|IsHidden=T|Text=0.031inch|Name=Thickness
|RECORD=41|OwnerIndex=1091|IndexInSheet=22|OwnerPartId=-1|Location.X=1234|Location.Y=762|Color=8388608|FontID=1|IsHidden=T|Text=20%|Name=Tolerance
|RECORD=41|OwnerIndex=1091|IndexInSheet=23|OwnerPartId=-1|Location.X=1234|Location.Y=762|Color=8388608|FontID=1|IsHidden=T|Text=-55°C|Name=Min Operating Temperature
|RECORD=41|OwnerIndex=1091|IndexInSheet=24|OwnerPartId=-1|Location.X=1234|Location.Y=762|Color=8388608|FontID=1|IsHidden=T|Text=M|Name=Series
|RECORD=41|OwnerIndex=1091|IndexInSheet=25|OwnerPartId=-1|Location.X=1234|Location.Y=762|Color=8388608|FontID=1|IsHidden=T|Text=SMD/SMT|Name=Termination
|RECORD=41|OwnerIndex=1091|IndexInSheet=26|OwnerPartId=-1|Location.X=1234|Location.Y=762|Color=8388608|FontID=1|IsHidden=T|Text=0603|Name=Case/Package
|RECORD=41|OwnerIndex=1091|IndexInSheet=27|OwnerPartId=-1|Location.X=1234|Location.Y=762|Color=8388608|FontID=1|IsHidden=T|Text=1|Name=Package Quantity
|RECORD=34|OwnerIndex=1091|IndexInSheet=-1|OwnerPartId=-1|Location.X=1235|Location.Y=740|Orientation=1|Color=8388608|FontID=2|Text=C22|Name=Designator|ReadOnlyState=1
|RECORD=41|OwnerIndex=1091|IndexInSheet=-1|OwnerPartId=1|Location.X=1265|Location.Y=725|Orientation=1|Color=8388608|FontID=2|Text=10uF_16V_0603|Name=Comment
|RECORD=44|OwnerIndex=1091
|RECORD=45|OwnerIndex=1124|IndexInSheet=-1|UseComponentLibrary=T|ModelName=FP-0603-L_1_6_0_2-W_0_8_0-MFG|ModelType=PCBLIB|DatafileCount=1|ModelDatafileEntity0=FP-0603-L_1_6_0_2-W_0_8_0-MFG|ModelDatafileKind0=PCBLib|IsCurrent=T|DatalinksLocked=T|DatabaseDatalinksLocked=T
|RECORD=46|OwnerIndex=1125
|RECORD=48|OwnerIndex=1125
|RECORD=45|OwnerIndex=1124|IndexInSheet=-1|UseComponentLibrary=T|ModelName=FP-0603-L_1_6_0_2-W_0_8_0-IPC_B|ModelType=PCBLIB|DatafileCount=1|ModelDatafileEntity0=FP-0603-L_1_6_0_2-W_0_8_0-IPC_B|ModelDatafileKind0=PCBLib|DatalinksLocked=T|DatabaseDatalinksLocked=T
|RECORD=46|OwnerIndex=1128
|RECORD=48|OwnerIndex=1128
|RECORD=45|OwnerIndex=1124|IndexInSheet=-1|UseComponentLibrary=T|ModelName=FP-0603-L_1_6_0_2-W_0_8_0-IPC_C|ModelType=PCBLIB|DatafileCount=1|ModelDatafileEntity0=FP-0603-L_1_6_0_2-W_0_8_0-IPC_C|ModelDatafileKind0=PCBLib|DatalinksLocked=T|DatabaseDatalinksLocked=T
|RECORD=46|OwnerIndex=1131
|RECORD=48|OwnerIndex=1131
|RECORD=45|OwnerIndex=1124|IndexInSheet=-1|UseComponentLibrary=T|ModelName=FP-0603-L_1_6_0_2-W_0_8_0-IPC_A|ModelType=PCBLIB|DatafileCount=1|ModelDatafileEntity0=FP-0603-L_1_6_0_2-W_0_8_0-IPC_A|ModelDatafileKind0=PCBLib|DatalinksLocked=T|DatabaseDatalinksLocked=T
|RECORD=46|OwnerIndex=1134
|RECORD=48|OwnerIndex=1134
|RECORD=17|IndexInSheet=78|OwnerPartId=-1|ShowNetName=T|Location.X=1245|Location.Y=800|Orientation=1|Color=128|FontID=1|Text=+3.3V
|RECORD=17|IndexInSheet=79|OwnerPartId=-1|Style=4|ShowNetName=T|Location.X=1245|Location.Y=730|Orientation=3|Color=128|FontID=1|Text=GND
|RECORD=17|IndexInSheet=80|OwnerPartId=-1|Style=4|ShowNetName=T|Location.X=1285|Location.Y=730|Orientation=3|Color=128|FontID=1|Text=GND
|RECORD=17|IndexInSheet=81|OwnerPartId=-1|ShowNetName=T|Location.X=1365|Location.Y=745|Orientation=1|Color=128|FontID=1|Text=P5V_SENSE
|RECORD=17|IndexInSheet=82|OwnerPartId=-1|Style=4|ShowNetName=T|Location.X=1525|Location.Y=705|Orientation=3|Color=128|FontID=1|Text=GND
|RECORD=17|IndexInSheet=83|OwnerPartId=-1|ShowNetName=T|Location.X=1560|Location.Y=760|Color=255|FontID=1|Text=SENS_I2C_SCL|IsCrossSheetConnector=T
|RECORD=17|IndexInSheet=84|OwnerPartId=-1|ShowNetName=T|Location.X=1560|Location.Y=780|Color=255|FontID=1|Text=SENS_I2C_SDA|IsCrossSheetConnector=T
|RECORD=1|LibReference=RES-2|ComponentDescription=Chip Resistor, 0 Ohm, 0.1 W, -55 to 155 degC, 0402 (1005 Metric), RoHS, Tape and Reel|PartCount=2|DisplayModeCount=1|IndexInSheet=85|OwnerPartId=-1|Location.X=1545|Location.Y=740|CurrentPartId=1|LibraryPath=*|SourceLibraryName=Altium Content Vault|TargetFileName=*|AreaColor=11599871|Color=128|PartIDLocked=T|DesignItemId=CMP-2000-07451-1|AllPinCount=2
|RECORD=2|OwnerIndex=1144|OwnerPartId=1|FormalType=1|Electrical=4|PinConglomerate=32|PinLength=10|Location.X=1565|Location.Y=740|Name=2|Designator=2|PinPropagationDelay=0.000000E+000
|RECORD=2|OwnerIndex=1144|OwnerPartId=1|FormalType=1|Electrical=4|PinConglomerate=34|PinLength=10|Location.X=1545|Location.Y=740|Name=1|Designator=1|PinPropagationDelay=0.000000E+000
|RECORD=6|OwnerIndex=1144|IsNotAccesible=T|IndexInSheet=2|OwnerPartId=1|LineWidth=1|Color=16711680|LocationCount=10|X1=1565|Y1=740|X2=1561|Y2=740|X3=1560|Y3=738|X4=1558|Y4=742|X5=1556|Y5=738|X6=1554|Y6=742|X7=1552|Y7=738|X8=1550|Y8=742|X9=1549|Y9=740|X10=1545|Y10=740
|RECORD=41|OwnerIndex=1144|IndexInSheet=3|OwnerPartId=-1|Location.X=1533|Location.Y=755|Color=8388608|FontID=1|IsHidden=T|Text=50V|Name=Voltage Rating (DC)
|RECORD=41|OwnerIndex=1144|IndexInSheet=4|OwnerPartId=-1|Location.X=1533|Location.Y=755|Color=8388608|FontID=1|IsHidden=T|Text=2|Name=Number of Terminations
|RECORD=41|OwnerIndex=1144|IndexInSheet=5|OwnerPartId=-1|Location.X=1533|Location.Y=755|Color=8388608|FontID=1|IsHidden=T|Text=SurfaceMount|Name=Mount
|RECORD=41|OwnerIndex=1144|IndexInSheet=6|OwnerPartId=-1|Location.X=1533|Location.Y=755|Color=8388608|FontID=1|IsHidden=T|Text=0.35mm|Name=Height
|RECORD=41|OwnerIndex=1144|IndexInSheet=7|OwnerPartId=-1|Location.X=1533|Location.Y=755|Color=8388608|FontID=1|IsHidden=T|Text=TapeandReel|Name=Packaging
|RECORD=41|OwnerIndex=1144|IndexInSheet=8|OwnerPartId=-1|Location.X=1533|Location.Y=755|Color=8388608|FontID=1|IsHidden=T|Text=Tin|Name=Contact Plating
|RECORD=41|OwnerIndex=1144|IndexInSheet=9|OwnerPartId=-1|Location.X=1533|Location.Y=755|Color=8388608|FontID=3|IsHidden=T|Text=http://www.panasonic.com/|Name=Manufacturer URL
|RECORD=41|OwnerIndex=1144|IndexInSheet=10|OwnerPartId=-1|Location.X=1533|Location.Y=755|Color=8388608|FontID=1|IsHidden=T|Text=ThickFilm|Name=Composition
|RECORD=41|OwnerIndex=1144|IndexInSheet=11|OwnerPartId=-1|Location.X=1533|Location.Y=755|Color=8388608|FontID=1|IsHidden=T|Text=155degC|Name=Max Operating Temperature
|RECORD=41|OwnerIndex=1144|IndexInSheet=12|OwnerPartId=-1|Location.X=1533|Location.Y=755|Color=8388608|FontID=1|IsHidden=T|Text=600ppm/??C|Name=Temperature Coefficient
|RECORD=41|OwnerIndex=1144|IndexInSheet=13|OwnerPartId=-1|Location.X=1533|Location.Y=755|Color=8388608|FontID=1|IsHidden=T|Text=NoSVHC|Name=REACH SVHC
|RECORD=41|OwnerIndex=1144|IndexInSheet=14|OwnerPartId=-1|Location.X=1533|Location.Y=755|Color=8388608|FontID=1|IsHidden=T|Text=0402|Name=Case/Package
|RECORD=41|OwnerIndex=1144|IndexInSheet=15|OwnerPartId=-1|Location.X=1533|Location.Y=755|Color=8388608|FontID=1|IsHidden=T|Text=100mW|Name=Max Power Dissipation
|RECORD=41|OwnerIndex=1144|IndexInSheet=16|OwnerPartId=-1|Location.X=1533|Location.Y=755|Color=8388608|FontID=1|IsHidden=T|Text=402|Name=Package Reference
|RECORD=41|OwnerIndex=1144|IndexInSheet=17|OwnerPartId=-1|Location.X=1533|Location.Y=755|Color=8388608|FontID=1|IsHidden=T|Text=0.5mm|Name=Depth
|RECORD=41|OwnerIndex=1144|IndexInSheet=18|OwnerPartId=-1|Location.X=1533|Location.Y=755|Color=8388608|FontID=1|IsHidden=T|Text=Panasonic|Name=Manufacturer
|RECORD=41|OwnerIndex=1144|IndexInSheet=19|OwnerPartId=-1|Location.X=1533|Location.Y=755|Color=8388608|FontID=1|IsHidden=T|Text=2-Pin Surface Mount Device, Body 1 x 0.5 mm|Name=Package Description
|RECORD=41|OwnerIndex=1144|IndexInSheet=20|OwnerPartId=-1|Location.X=1533|Location.Y=755|Color=8388608|FontID=3|IsHidden=T|Text=https://industrial.panasonic.com/cdbs/www-data/pdf/RDA0000/AOA0000C301.pdf|Name=Datasheet URL
|RECORD=41|OwnerIndex=1144|IndexInSheet=21|OwnerPartId=-1|Location.X=1533|Location.Y=755|Color=8388608|FontID=1|IsHidden=T|Text=True|Name=RoHSCompliant
|RECORD=41|OwnerIndex=1144|IndexInSheet=22|OwnerPartId=-1|Location.X=1533|Location.Y=755|Color=8388608|FontID=1|IsHidden=T|Text=0402|Name=Case Code (Imperial)
|RECORD=41|OwnerIndex=1144|IndexInSheet=23|OwnerPartId=-1|Location.X=1533|Location.Y=755|Color=8388608|FontID=1|IsHidden=T|Text=0mOhm|Name=Resistance
|RECORD=41|OwnerIndex=1144|IndexInSheet=24|OwnerPartId=-1|Location.X=1533|Location.Y=755|Color=8388608|FontID=1|IsHidden=T|Text=Not|Name=Military Standard
|RECORD=41|OwnerIndex=1144|IndexInSheet=25|OwnerPartId=-1|Location.X=1533|Location.Y=755|Color=8388608|FontID=1|IsHidden=T|Text=5%|Name=Tolerance
|RECORD=41|OwnerIndex=1144|IndexInSheet=26|OwnerPartId=-1|Location.X=1533|Location.Y=755|Color=8388608|FontID=1|IsHidden=T|Text=-55degC|Name=Min Operating Temperature
|RECORD=41|OwnerIndex=1144|IndexInSheet=27|OwnerPartId=-1|Location.X=1533|Location.Y=755|Color=8388608|FontID=1|IsHidden=T|Text=100mW|Name=Power Rating
|RECORD=41|OwnerIndex=1144|IndexInSheet=28|OwnerPartId=-1|Location.X=1533|Location.Y=755|Color=8388608|FontID=1|IsHidden=T|Text=03/2015|Name=Datasheet Version
|RECORD=41|OwnerIndex=1144|IndexInSheet=29|OwnerPartId=-1|Location.X=1533|Location.Y=755|Color=8388608|FontID=1|IsHidden=T|Text=1mm|Name=Length
|RECORD=41|OwnerIndex=1144|IndexInSheet=30|OwnerPartId=-1|Location.X=1533|Location.Y=755|Color=8388608|FontID=1|IsHidden=T|Text=1005|Name=Case Code (Metric)
|RECORD=41|OwnerIndex=1144|IndexInSheet=31|OwnerPartId=-1|Location.X=1533|Location.Y=755|Color=8388608|FontID=1|IsHidden=T|Text=SMD/SMT|Name=Termination
|RECORD=41|OwnerIndex=1144|IndexInSheet=32|OwnerPartId=-1|Location.X=1533|Location.Y=755|Color=8388608|FontID=1|IsHidden=T|Text=SurfaceMount|Name=Mounting Technology
|RECORD=41|OwnerIndex=1144|IndexInSheet=33|OwnerPartId=-1|Location.X=1533|Location.Y=755|Color=8388608|FontID=1|IsHidden=T|Text=50V|Name=Voltage Rating
|RECORD=41|OwnerIndex=1144|IndexInSheet=34|OwnerPartId=-1|Location.X=1533|Location.Y=755|Color=8388608|FontID=1|IsHidden=T|Text=0.02inch|Name=Width
|RECORD=41|OwnerIndex=1144|IndexInSheet=35|OwnerPartId=-1|Location.X=1533|Location.Y=755|Color=8388608|FontID=1|IsHidden=T|Text=1|Name=Package Quantity
|RECORD=41|OwnerIndex=1144|IndexInSheet=36|OwnerPartId=-1|Location.X=1533|Location.Y=755|Color=8388608|FontID=1|IsHidden=T|Text=LeadFree|Name=Lead Free
|RECORD=41|OwnerIndex=1144|IndexInSheet=37|OwnerPartId=-1|Location.X=1533|Location.Y=755|Color=8388608|FontID=1|IsHidden=T|Text=No|Name=Radiation Hardening
|RECORD=34|OwnerIndex=1144|IndexInSheet=-1|OwnerPartId=-1|Location.X=1525|Location.Y=740|Color=8388608|FontID=1|Text=R65|Name=Designator|ReadOnlyState=1
|RECORD=41|OwnerIndex=1144|IndexInSheet=-1|OwnerPartId=-1|Location.X=1565|Location.Y=740|Color=8388608|FontID=1|Text=0_1%_0402|Name=Comment
|RECORD=44|OwnerIndex=1144
|RECORD=45|OwnerIndex=1187|IndexInSheet=-1|Description=Chip Resistor, 2-Leads, Body 1.05x0.55mm, IPC High Density|UseComponentLibrary=T|ModelName=RESC1005X40X25LL05T05|ModelType=PCBLIB|DatafileCount=1|ModelDatafileEntity0=RESC1005X40X25LL05T05|ModelDatafileKind0=PCBLib|IsCurrent=T|DatalinksLocked=T|DatabaseDatalinksLocked=T
|RECORD=46|OwnerIndex=1188
|RECORD=48|OwnerIndex=1188
|RECORD=41|OwnerIndex=1190|IndexInSheet=-1|OwnerPartId=-1|Color=8388608|FontID=1|IsHidden=T|Text=2D|Name=Available Preview Images
|RECORD=45|OwnerIndex=1187|IndexInSheet=-1|Description=Chip Resistor, 2-Leads, Body 1.05x0.55mm, IPC Low Density|UseComponentLibrary=T|ModelName=RESC1005X40X25ML05T05|ModelType=PCBLIB|DatafileCount=1|ModelDatafileEntity0=RESC1005X40X25ML05T05|ModelDatafileKind0=PCBLib|DatalinksLocked=T|DatabaseDatalinksLocked=T
|RECORD=46|OwnerIndex=1192
|RECORD=48|OwnerIndex=1192
|RECORD=41|OwnerIndex=1194|IndexInSheet=-1|OwnerPartId=-1|Color=8388608|FontID=1|IsHidden=T|Text=2D|Name=Available Preview Images
|RECORD=45|OwnerIndex=1187|IndexInSheet=-1|Description=Chip Resistor, 2-Leads, Body 1.05x0.55mm, IPC Medium Density|UseComponentLibrary=T|ModelName=RESC1005X40X25NL05T05|ModelType=PCBLIB|DatafileCount=1|ModelDatafileEntity0=RESC1005X40X25NL05T05|ModelDatafileKind0=PCBLib|DatalinksLocked=T|DatabaseDatalinksLocked=T
|RECORD=46|OwnerIndex=1196
|RECORD=48|OwnerIndex=1196
|RECORD=41|OwnerIndex=1198|IndexInSheet=-1|OwnerPartId=-1|Color=8388608|FontID=1|IsHidden=T|Text=2D|Name=Available Preview Images
|RECORD=1|LibReference=RES-2|ComponentDescription=Chip Resistor, 0 Ohm, 0.1 W, -55 to 155 degC, 0402 (1005 Metric), RoHS, Tape and Reel|PartCount=2|DisplayModeCount=1|IndexInSheet=86|OwnerPartId=-1|Location.X=1545|Location.Y=730|CurrentPartId=1|LibraryPath=*|SourceLibraryName=Altium Content Vault|TargetFileName=*|AreaColor=11599871|Color=128|PartIDLocked=T|DesignItemId=CMP-2000-07451-1|AllPinCount=2
|RECORD=2|OwnerIndex=1200|OwnerPartId=1|FormalType=1|Electrical=4|PinConglomerate=32|PinLength=10|Location.X=1565|Location.Y=730|Name=2|Designator=2|PinPropagationDelay=0.000000E+000
|RECORD=2|OwnerIndex=1200|OwnerPartId=1|FormalType=1|Electrical=4|PinConglomerate=34|PinLength=10|Location.X=1545|Location.Y=730|Name=1|Designator=1|PinPropagationDelay=0.000000E+000
|RECORD=6|OwnerIndex=1200|IsNotAccesible=T|IndexInSheet=2|OwnerPartId=1|LineWidth=1|Color=16711680|LocationCount=10|X1=1565|Y1=730|X2=1561|Y2=730|X3=1560|Y3=728|X4=1558|Y4=732|X5=1556|Y5=728|X6=1554|Y6=732|X7=1552|Y7=728|X8=1550|Y8=732|X9=1549|Y9=730|X10=1545|Y10=730
|RECORD=41|OwnerIndex=1200|IndexInSheet=3|OwnerPartId=-1|Location.X=1533|Location.Y=745|Color=8388608|FontID=1|IsHidden=T|Text=50V|Name=Voltage Rating (DC)
|RECORD=41|OwnerIndex=1200|IndexInSheet=4|OwnerPartId=-1|Location.X=1533|Location.Y=745|Color=8388608|FontID=1|IsHidden=T|Text=2|Name=Number of Terminations
|RECORD=41|OwnerIndex=1200|IndexInSheet=5|OwnerPartId=-1|Location.X=1533|Location.Y=745|Color=8388608|FontID=1|IsHidden=T|Text=SurfaceMount|Name=Mount
|RECORD=41|OwnerIndex=1200|IndexInSheet=6|OwnerPartId=-1|Location.X=1533|Location.Y=745|Color=8388608|FontID=1|IsHidden=T|Text=0.35mm|Name=Height
|RECORD=41|OwnerIndex=1200|IndexInSheet=7|OwnerPartId=-1|Location.X=1533|Location.Y=745|Color=8388608|FontID=1|IsHidden=T|Text=TapeandReel|Name=Packaging
|RECORD=41|OwnerIndex=1200|IndexInSheet=8|OwnerPartId=-1|Location.X=1533|Location.Y=745|Color=8388608|FontID=1|IsHidden=T|Text=Tin|Name=Contact Plating
|RECORD=41|OwnerIndex=1200|IndexInSheet=9|OwnerPartId=-1|Location.X=1533|Location.Y=745|Color=8388608|FontID=3|IsHidden=T|Text=http://www.panasonic.com/|Name=Manufacturer URL
|RECORD=41|OwnerIndex=1200|IndexInSheet=10|OwnerPartId=-1|Location.X=1533|Location.Y=745|Color=8388608|FontID=1|IsHidden=T|Text=ThickFilm|Name=Composition
|RECORD=41|OwnerIndex=1200|IndexInSheet=11|OwnerPartId=-1|Location.X=1533|Location.Y=745|Color=8388608|FontID=1|IsHidden=T|Text=155degC|Name=Max Operating Temperature
|RECORD=41|OwnerIndex=1200|IndexInSheet=12|OwnerPartId=-1|Location.X=1533|Location.Y=745|Color=8388608|FontID=1|IsHidden=T|Text=600ppm/??C|Name=Temperature Coefficient
|RECORD=41|OwnerIndex=1200|IndexInSheet=13|OwnerPartId=-1|Location.X=1533|Location.Y=745|Color=8388608|FontID=1|IsHidden=T|Text=NoSVHC|Name=REACH SVHC
|RECORD=41|OwnerIndex=1200|IndexInSheet=14|OwnerPartId=-1|Location.X=1533|Location.Y=745|Color=8388608|FontID=1|IsHidden=T|Text=0402|Name=Case/Package
|RECORD=41|OwnerIndex=1200|IndexInSheet=15|OwnerPartId=-1|Location.X=1533|Location.Y=745|Color=8388608|FontID=1|IsHidden=T|Text=100mW|Name=Max Power Dissipation
|RECORD=41|OwnerIndex=1200|IndexInSheet=16|OwnerPartId=-1|Location.X=1533|Location.Y=745|Color=8388608|FontID=1|IsHidden=T|Text=402|Name=Package Reference
|RECORD=41|OwnerIndex=1200|IndexInSheet=17|OwnerPartId=-1|Location.X=1533|Location.Y=745|Color=8388608|FontID=1|IsHidden=T|Text=0.5mm|Name=Depth
|RECORD=41|OwnerIndex=1200|IndexInSheet=18|OwnerPartId=-1|Location.X=1533|Location.Y=745|Color=8388608|FontID=1|IsHidden=T|Text=Panasonic|Name=Manufacturer
|RECORD=41|OwnerIndex=1200|IndexInSheet=19|OwnerPartId=-1|Location.X=1533|Location.Y=745|Color=8388608|FontID=1|IsHidden=T|Text=2-Pin Surface Mount Device, Body 1 x 0.5 mm|Name=Package Description
|RECORD=41|OwnerIndex=1200|IndexInSheet=20|OwnerPartId=-1|Location.X=1533|Location.Y=745|Color=8388608|FontID=3|IsHidden=T|Text=https://industrial.panasonic.com/cdbs/www-data/pdf/RDA0000/AOA0000C301.pdf|Name=Datasheet URL
|RECORD=41|OwnerIndex=1200|IndexInSheet=21|OwnerPartId=-1|Location.X=1533|Location.Y=745|Color=8388608|FontID=1|IsHidden=T|Text=True|Name=RoHSCompliant
|RECORD=41|OwnerIndex=1200|IndexInSheet=22|OwnerPartId=-1|Location.X=1533|Location.Y=745|Color=8388608|FontID=1|IsHidden=T|Text=0402|Name=Case Code (Imperial)
|RECORD=41|OwnerIndex=1200|IndexInSheet=23|OwnerPartId=-1|Location.X=1533|Location.Y=745|Color=8388608|FontID=1|IsHidden=T|Text=0mOhm|Name=Resistance
|RECORD=41|OwnerIndex=1200|IndexInSheet=24|OwnerPartId=-1|Location.X=1533|Location.Y=745|Color=8388608|FontID=1|IsHidden=T|Text=Not|Name=Military Standard
|RECORD=41|OwnerIndex=1200|IndexInSheet=25|OwnerPartId=-1|Location.X=1533|Location.Y=745|Color=8388608|FontID=1|IsHidden=T|Text=5%|Name=Tolerance
|RECORD=41|OwnerIndex=1200|IndexInSheet=26|OwnerPartId=-1|Location.X=1533|Location.Y=745|Color=8388608|FontID=1|IsHidden=T|Text=-55degC|Name=Min Operating Temperature
|RECORD=41|OwnerIndex=1200|IndexInSheet=27|OwnerPartId=-1|Location.X=1533|Location.Y=745|Color=8388608|FontID=1|IsHidden=T|Text=100mW|Name=Power Rating
|RECORD=41|OwnerIndex=1200|IndexInSheet=28|OwnerPartId=-1|Location.X=1533|Location.Y=745|Color=8388608|FontID=1|IsHidden=T|Text=03/2015|Name=Datasheet Version
|RECORD=41|OwnerIndex=1200|IndexInSheet=29|OwnerPartId=-1|Location.X=1533|Location.Y=745|Color=8388608|FontID=1|IsHidden=T|Text=1mm|Name=Length
|RECORD=41|OwnerIndex=1200|IndexInSheet=30|OwnerPartId=-1|Location.X=1533|Location.Y=745|Color=8388608|FontID=1|IsHidden=T|Text=1005|Name=Case Code (Metric)
|RECORD=41|OwnerIndex=1200|IndexInSheet=31|OwnerPartId=-1|Location.X=1533|Location.Y=745|Color=8388608|FontID=1|IsHidden=T|Text=SMD/SMT|Name=Termination
|RECORD=41|OwnerIndex=1200|IndexInSheet=32|OwnerPartId=-1|Location.X=1533|Location.Y=745|Color=8388608|FontID=1|IsHidden=T|Text=SurfaceMount|Name=Mounting Technology
|RECORD=41|OwnerIndex=1200|IndexInSheet=33|OwnerPartId=-1|Location.X=1533|Location.Y=745|Color=8388608|FontID=1|IsHidden=T|Text=50V|Name=Voltage Rating
|RECORD=41|OwnerIndex=1200|IndexInSheet=34|OwnerPartId=-1|Location.X=1533|Location.Y=745|Color=8388608|FontID=1|IsHidden=T|Text=0.02inch|Name=Width
|RECORD=41|OwnerIndex=1200|IndexInSheet=35|OwnerPartId=-1|Location.X=1533|Location.Y=745|Color=8388608|FontID=1|IsHidden=T|Text=1|Name=Package Quantity
|RECORD=41|OwnerIndex=1200|IndexInSheet=36|OwnerPartId=-1|Location.X=1533|Location.Y=745|Color=8388608|FontID=1|IsHidden=T|Text=LeadFree|Name=Lead Free
|RECORD=41|OwnerIndex=1200|IndexInSheet=37|OwnerPartId=-1|Location.X=1533|Location.Y=745|Color=8388608|FontID=1|IsHidden=T|Text=No|Name=Radiation Hardening
|RECORD=34|OwnerIndex=1200|IndexInSheet=-1|OwnerPartId=-1|Location.X=1525|Location.Y=730|Color=8388608|FontID=1|Text=R66|Name=Designator|ReadOnlyState=1
|RECORD=41|OwnerIndex=1200|IndexInSheet=-1|OwnerPartId=-1|Location.X=1565|Location.Y=730|Color=8388608|FontID=1|Text=0_1%_0402|Name=Comment
|RECORD=44|OwnerIndex=1200
|RECORD=45|OwnerIndex=1243|IndexInSheet=-1|Description=Chip Resistor, 2-Leads, Body 1.05x0.55mm, IPC High Density|UseComponentLibrary=T|ModelName=RESC1005X40X25LL05T05|ModelType=PCBLIB|DatafileCount=1|ModelDatafileEntity0=RESC1005X40X25LL05T05|ModelDatafileKind0=PCBLib|IsCurrent=T|DatalinksLocked=T|DatabaseDatalinksLocked=T
|RECORD=46|OwnerIndex=1244
|RECORD=48|OwnerIndex=1244
|RECORD=41|OwnerIndex=1246|IndexInSheet=-1|OwnerPartId=-1|Color=8388608|FontID=1|IsHidden=T|Text=2D|Name=Available Preview Images
|RECORD=45|OwnerIndex=1243|IndexInSheet=-1|Description=Chip Resistor, 2-Leads, Body 1.05x0.55mm, IPC Low Density|UseComponentLibrary=T|ModelName=RESC1005X40X25ML05T05|ModelType=PCBLIB|DatafileCount=1|ModelDatafileEntity0=RESC1005X40X25ML05T05|ModelDatafileKind0=PCBLib|DatalinksLocked=T|DatabaseDatalinksLocked=T
|RECORD=46|OwnerIndex=1248
|RECORD=48|OwnerIndex=1248
|RECORD=41|OwnerIndex=1250|IndexInSheet=-1|OwnerPartId=-1|Color=8388608|FontID=1|IsHidden=T|Text=2D|Name=Available Preview Images
|RECORD=45|OwnerIndex=1243|IndexInSheet=-1|Description=Chip Resistor, 2-Leads, Body 1.05x0.55mm, IPC Medium Density|UseComponentLibrary=T|ModelName=RESC1005X40X25NL05T05|ModelType=PCBLIB|DatafileCount=1|ModelDatafileEntity0=RESC1005X40X25NL05T05|ModelDatafileKind0=PCBLib|DatalinksLocked=T|DatabaseDatalinksLocked=T
|RECORD=46|OwnerIndex=1252
|RECORD=48|OwnerIndex=1252
|RECORD=41|OwnerIndex=1254|IndexInSheet=-1|OwnerPartId=-1|Color=8388608|FontID=1|IsHidden=T|Text=2D|Name=Available Preview Images
|RECORD=4|IndexInSheet=87|OwnerPartId=-1|Location.X=1425|Location.Y=810|Color=8388608|FontID=1|Text=Address 0x41
|RECORD=17|IndexInSheet=88|OwnerPartId=-1|ShowNetName=T|Location.X=1620|Location.Y=795|Orientation=1|Color=128|FontID=1|Text=+3.3V
|RECORD=17|IndexInSheet=89|OwnerPartId=-1|ShowNetName=T|Location.X=340|Location.Y=395|Orientation=1|Color=128|FontID=1|Text=+12V
|RECORD=1|LibReference=02cd4be3c70576c341d710602a673aa|ComponentDescription=Chip Multilayer Ceramic Capacitors for General Purpose, 1206, 4.7uF, X7R, 15%, 10%, 50V|PartCount=2|DisplayModeCount=1|IndexInSheet=90|OwnerPartId=-1|Location.X=390|Location.Y=345|CurrentPartId=1|LibraryPath=*|SourceLibraryName=Altium Content Vault|TargetFileName=*|AreaColor=11599871|Color=128|PartIDLocked=T|DesignItemId=CMP-1037-04923-3|AllPinCount=2
|RECORD=2|OwnerIndex=1259|OwnerPartId=1|Electrical=4|PinConglomerate=49|PinLength=7|Location.X=390|Location.Y=338|Name=1|Designator=1|PinPropagationDelay=0.000000E+000
|RECORD=2|OwnerIndex=1259|OwnerPartId=1|Electrical=4|PinConglomerate=51|PinLength=6|Location.X=390|Location.Y=331|Name=2|Designator=2|PinPropagationDelay=0.000000E+000
|RECORD=13|OwnerIndex=1259|IsNotAccesible=T|IndexInSheet=2|OwnerPartId=1|Location.X=400|Location.Y=338|Corner.X=380|Corner.Y=338|LineWidth=1|Color=16711680
|RECORD=13|OwnerIndex=1259|IsNotAccesible=T|IndexInSheet=3|OwnerPartId=1|Location.X=400|Location.Y=332|Corner.X=380|Corner.Y=332|LineWidth=1|Color=16711680
|RECORD=13|OwnerIndex=1259|IsNotAccesible=T|IndexInSheet=4|OwnerPartId=1|Location.X=390|Location.Y=338|Corner.X=390|Corner.Y=341|LineWidth=1|Color=16711680
|RECORD=13|OwnerIndex=1259|IsNotAccesible=T|IndexInSheet=5|OwnerPartId=1|Location.X=390|Location.Y=331|Corner.X=390|Corner.Y=330|LineWidth=1|Color=16711680
|RECORD=41|OwnerIndex=1259|IndexInSheet=6|OwnerPartId=-1|Location.X=379|Location.Y=347|Color=8388608|FontID=1|IsHidden=T|Text=1.6mm|Name=Height
|RECORD=41|OwnerIndex=1259|IndexInSheet=7|OwnerPartId=-1|Location.X=379|Location.Y=347|Color=8388608|FontID=1|IsHidden=T|Text=50V|Name=Voltage
|RECORD=41|OwnerIndex=1259|IndexInSheet=8|OwnerPartId=-1|Location.X=379|Location.Y=347|Color=8388608|FontID=1|IsHidden=T|Text=4.7uF|Name=Capacitance
|RECORD=41|OwnerIndex=1259|IndexInSheet=9|OwnerPartId=-1|Location.X=379|Location.Y=347|Color=8388608|FontID=1|IsHidden=T|Text=Lead Free|Name=Lead Free
|RECORD=41|OwnerIndex=1259|IndexInSheet=10|OwnerPartId=-1|Location.X=379|Location.Y=347|Color=8388608|FontID=1|IsHidden=T|Text=125°C|Name=Max Operating Temperature
|RECORD=41|OwnerIndex=1259|IndexInSheet=11|OwnerPartId=-1|Location.X=379|Location.Y=347|Color=8388608|FontID=1|IsHidden=T|Text=Tape and Reel|Name=Packaging
|RECORD=41|OwnerIndex=1259|IndexInSheet=12|OwnerPartId=-1|Location.X=379|Location.Y=347|Color=8388608|FontID=1|IsHidden=T|Text=No SVHC|Name=REACH SVHC
|RECORD=41|OwnerIndex=1259|IndexInSheet=13|OwnerPartId=-1|Location.X=379|Location.Y=347|Color=8388608|FontID=1|IsHidden=T|Text=50V|Name=Voltage Rating
|RECORD=41|OwnerIndex=1259|IndexInSheet=14|OwnerPartId=-1|Location.X=379|Location.Y=347|Color=8388608|FontID=1|IsHidden=T|Text=Surface Mount|Name=Mount
|RECORD=41|OwnerIndex=1259|IndexInSheet=15|OwnerPartId=-1|Location.X=379|Location.Y=347|Color=8388608|FontID=1|IsHidden=T|Text=SMD/SMT|Name=Termination
|RECORD=41|OwnerIndex=1259|IndexInSheet=16|OwnerPartId=-1|Location.X=379|Location.Y=347|Color=8388608|FontID=1|IsHidden=T|Text=10%|Name=Tolerance
|RECORD=41|OwnerIndex=1259|IndexInSheet=17|OwnerPartId=-1|Location.X=379|Location.Y=347|Color=8388608|FontID=1|IsHidden=T|Text=1206|Name=Case/Package
|RECORD=41|OwnerIndex=1259|IndexInSheet=18|OwnerPartId=-1|Location.X=379|Location.Y=347|Color=8388608|FontID=1|IsHidden=T|Text=Ceramic|Name=Material
|RECORD=41|OwnerIndex=1259|IndexInSheet=19|OwnerPartId=-1|Location.X=379|Location.Y=347|Color=8388608|FontID=1|IsHidden=T|Text=1.6mm|Name=Depth
|RECORD=41|OwnerIndex=1259|IndexInSheet=20|OwnerPartId=-1|Location.X=379|Location.Y=347|Color=8388608|FontID=1|IsHidden=T|Text=3.2mm|Name=Length
|RECORD=41|OwnerIndex=1259|IndexInSheet=21|OwnerPartId=-1|Location.X=379|Location.Y=347|Color=8388608|FontID=1|IsHidden=T|Text=3216|Name=Case Code (Metric)
|RECORD=41|OwnerIndex=1259|IndexInSheet=22|OwnerPartId=-1|Location.X=379|Location.Y=347|Color=8388608|FontID=1|IsHidden=T|Text=50V|Name=Voltage Rating (DC)
|RECORD=41|OwnerIndex=1259|IndexInSheet=23|OwnerPartId=-1|Location.X=379|Location.Y=347|Color=8388608|FontID=1|IsHidden=T|Text=1206|Name=Case Code (Imperial)
|RECORD=41|OwnerIndex=1259|IndexInSheet=24|OwnerPartId=-1|Location.X=379|Location.Y=347|Color=8388608|FontID=1|IsHidden=T|Text=No|Name=Radiation Hardening
|RECORD=41|OwnerIndex=1259|IndexInSheet=25|OwnerPartId=-1|Location.X=379|Location.Y=347|Color=8388608|FontID=1|IsHidden=T|Text=0.063inch|Name=Width
|RECORD=41|OwnerIndex=1259|IndexInSheet=26|OwnerPartId=-1|Location.X=379|Location.Y=347|Color=8388608|FontID=1|IsHidden=T|Text=0.071inch|Name=Thickness
|RECORD=41|OwnerIndex=1259|IndexInSheet=27|OwnerPartId=-1|Location.X=379|Location.Y=347|Color=8388608|FontID=1|IsHidden=T|Text=2000|Name=Package Quantity
|RECORD=41|OwnerIndex=1259|IndexInSheet=28|OwnerPartId=-1|Location.X=379|Location.Y=347|Color=8388608|FontID=1|IsHidden=T|Text=-55°C|Name=Min Operating Temperature
|RECORD=41|OwnerIndex=1259|IndexInSheet=29|OwnerPartId=-1|Location.X=379|Location.Y=347|Color=8388608|FontID=1|IsHidden=T|Text=X7R|Name=Dielectric
|RECORD=34|OwnerIndex=1259|IndexInSheet=-1|OwnerPartId=-1|Location.X=380|Location.Y=325|Orientation=1|Color=8388608|FontID=2|Text=C76|Name=Designator|ReadOnlyState=1
|RECORD=41|OwnerIndex=1259|IndexInSheet=-1|OwnerPartId=1|Location.X=410|Location.Y=310|Orientation=1|Color=8388608|FontID=2|Text=4.7uF_50V_1206|Name=Comment
|RECORD=44|OwnerIndex=1259
|RECORD=45|OwnerIndex=1294|IndexInSheet=-1|UseComponentLibrary=T|ModelName=FP-GRM31C-0_2-e0_3_0_8-IPC_C|ModelType=PCBLIB|DatafileCount=1|ModelDatafileEntity0=FP-GRM31C-0_2-e0_3_0_8-IPC_C|ModelDatafileKind0=PCBLib|IsCurrent=T|DatalinksLocked=T|DatabaseDatalinksLocked=T
|RECORD=46|OwnerIndex=1295
|RECORD=48|OwnerIndex=1295
|RECORD=45|OwnerIndex=1294|IndexInSheet=-1|UseComponentLibrary=T|ModelName=FP-GRM31C-0_2-e0_3_0_8-IPC_B|ModelType=PCBLIB|DatafileCount=1|ModelDatafileEntity0=FP-GRM31C-0_2-e0_3_0_8-IPC_B|ModelDatafileKind0=PCBLib|DatalinksLocked=T|DatabaseDatalinksLocked=T
|RECORD=46|OwnerIndex=1298
|RECORD=48|OwnerIndex=1298
|RECORD=45|OwnerIndex=1294|IndexInSheet=-1|UseComponentLibrary=T|ModelName=FP-GRM31C-0_2-e0_3_0_8-IPC_A|ModelType=PCBLIB|DatafileCount=1|ModelDatafileEntity0=FP-GRM31C-0_2-e0_3_0_8-IPC_A|ModelDatafileKind0=PCBLib|DatalinksLocked=T|DatabaseDatalinksLocked=T
|RECORD=46|OwnerIndex=1301
|RECORD=48|OwnerIndex=1301
|RECORD=45|OwnerIndex=1294|IndexInSheet=-1|UseComponentLibrary=T|ModelName=FP-GRM31C-0_2-e0_3_0_8-MFG|ModelType=PCBLIB|DatafileCount=1|ModelDatafileEntity0=FP-GRM31C-0_2-e0_3_0_8-MFG|ModelDatafileKind0=PCBLib|DatalinksLocked=T|DatabaseDatalinksLocked=T
|RECORD=46|OwnerIndex=1304
|RECORD=48|OwnerIndex=1304
|RECORD=1|LibReference=02cd4be3c70576c341d710602a673aa|ComponentDescription=Chip Multilayer Ceramic Capacitors for General Purpose, 1206, 4.7uF, X7R, 15%, 10%, 50V|PartCount=2|DisplayModeCount=1|IndexInSheet=91|OwnerPartId=-1|Location.X=430|Location.Y=345|CurrentPartId=1|LibraryPath=*|SourceLibraryName=Altium Content Vault|TargetFileName=*|AreaColor=11599871|Color=128|PartIDLocked=T|DesignItemId=CMP-1037-04923-3|AllPinCount=2
|RECORD=2|OwnerIndex=1307|OwnerPartId=1|Electrical=4|PinConglomerate=49|PinLength=7|Location.X=430|Location.Y=338|Name=1|Designator=1|PinPropagationDelay=0.000000E+000
|RECORD=2|OwnerIndex=1307|OwnerPartId=1|Electrical=4|PinConglomerate=51|PinLength=6|Location.X=430|Location.Y=331|Name=2|Designator=2|PinPropagationDelay=0.000000E+000
|RECORD=13|OwnerIndex=1307|IsNotAccesible=T|IndexInSheet=2|OwnerPartId=1|Location.X=440|Location.Y=338|Corner.X=420|Corner.Y=338|LineWidth=1|Color=16711680
|RECORD=13|OwnerIndex=1307|IsNotAccesible=T|IndexInSheet=3|OwnerPartId=1|Location.X=440|Location.Y=332|Corner.X=420|Corner.Y=332|LineWidth=1|Color=16711680
|RECORD=13|OwnerIndex=1307|IsNotAccesible=T|IndexInSheet=4|OwnerPartId=1|Location.X=430|Location.Y=338|Corner.X=430|Corner.Y=341|LineWidth=1|Color=16711680
|RECORD=13|OwnerIndex=1307|IsNotAccesible=T|IndexInSheet=5|OwnerPartId=1|Location.X=430|Location.Y=331|Corner.X=430|Corner.Y=330|LineWidth=1|Color=16711680
|RECORD=41|OwnerIndex=1307|IndexInSheet=6|OwnerPartId=-1|Location.X=419|Location.Y=347|Color=8388608|FontID=1|IsHidden=T|Text=1.6mm|Name=Height
|RECORD=41|OwnerIndex=1307|IndexInSheet=7|OwnerPartId=-1|Location.X=419|Location.Y=347|Color=8388608|FontID=1|IsHidden=T|Text=50V|Name=Voltage
|RECORD=41|OwnerIndex=1307|IndexInSheet=8|OwnerPartId=-1|Location.X=419|Location.Y=347|Color=8388608|FontID=1|IsHidden=T|Text=4.7uF|Name=Capacitance
|RECORD=41|OwnerIndex=1307|IndexInSheet=9|OwnerPartId=-1|Location.X=419|Location.Y=347|Color=8388608|FontID=1|IsHidden=T|Text=Lead Free|Name=Lead Free
|RECORD=41|OwnerIndex=1307|IndexInSheet=10|OwnerPartId=-1|Location.X=419|Location.Y=347|Color=8388608|FontID=1|IsHidden=T|Text=125°C|Name=Max Operating Temperature
|RECORD=41|OwnerIndex=1307|IndexInSheet=11|OwnerPartId=-1|Location.X=419|Location.Y=347|Color=8388608|FontID=1|IsHidden=T|Text=Tape and Reel|Name=Packaging
|RECORD=41|OwnerIndex=1307|IndexInSheet=12|OwnerPartId=-1|Location.X=419|Location.Y=347|Color=8388608|FontID=1|IsHidden=T|Text=No SVHC|Name=REACH SVHC
|RECORD=41|OwnerIndex=1307|IndexInSheet=13|OwnerPartId=-1|Location.X=419|Location.Y=347|Color=8388608|FontID=1|IsHidden=T|Text=50V|Name=Voltage Rating
|RECORD=41|OwnerIndex=1307|IndexInSheet=14|OwnerPartId=-1|Location.X=419|Location.Y=347|Color=8388608|FontID=1|IsHidden=T|Text=Surface Mount|Name=Mount
|RECORD=41|OwnerIndex=1307|IndexInSheet=15|OwnerPartId=-1|Location.X=419|Location.Y=347|Color=8388608|FontID=1|IsHidden=T|Text=SMD/SMT|Name=Termination
|RECORD=41|OwnerIndex=1307|IndexInSheet=16|OwnerPartId=-1|Location.X=419|Location.Y=347|Color=8388608|FontID=1|IsHidden=T|Text=10%|Name=Tolerance
|RECORD=41|OwnerIndex=1307|IndexInSheet=17|OwnerPartId=-1|Location.X=419|Location.Y=347|Color=8388608|FontID=1|IsHidden=T|Text=1206|Name=Case/Package
|RECORD=41|OwnerIndex=1307|IndexInSheet=18|OwnerPartId=-1|Location.X=419|Location.Y=347|Color=8388608|FontID=1|IsHidden=T|Text=Ceramic|Name=Material
|RECORD=41|OwnerIndex=1307|IndexInSheet=19|OwnerPartId=-1|Location.X=419|Location.Y=347|Color=8388608|FontID=1|IsHidden=T|Text=1.6mm|Name=Depth
|RECORD=41|OwnerIndex=1307|IndexInSheet=20|OwnerPartId=-1|Location.X=419|Location.Y=347|Color=8388608|FontID=1|IsHidden=T|Text=3.2mm|Name=Length
|RECORD=41|OwnerIndex=1307|IndexInSheet=21|OwnerPartId=-1|Location.X=419|Location.Y=347|Color=8388608|FontID=1|IsHidden=T|Text=3216|Name=Case Code (Metric)
|RECORD=41|OwnerIndex=1307|IndexInSheet=22|OwnerPartId=-1|Location.X=419|Location.Y=347|Color=8388608|FontID=1|IsHidden=T|Text=50V|Name=Voltage Rating (DC)
|RECORD=41|OwnerIndex=1307|IndexInSheet=23|OwnerPartId=-1|Location.X=419|Location.Y=347|Color=8388608|FontID=1|IsHidden=T|Text=1206|Name=Case Code (Imperial)
|RECORD=41|OwnerIndex=1307|IndexInSheet=24|OwnerPartId=-1|Location.X=419|Location.Y=347|Color=8388608|FontID=1|IsHidden=T|Text=No|Name=Radiation Hardening
|RECORD=41|OwnerIndex=1307|IndexInSheet=25|OwnerPartId=-1|Location.X=419|Location.Y=347|Color=8388608|FontID=1|IsHidden=T|Text=0.063inch|Name=Width
|RECORD=41|OwnerIndex=1307|IndexInSheet=26|OwnerPartId=-1|Location.X=419|Location.Y=347|Color=8388608|FontID=1|IsHidden=T|Text=0.071inch|Name=Thickness
|RECORD=41|OwnerIndex=1307|IndexInSheet=27|OwnerPartId=-1|Location.X=419|Location.Y=347|Color=8388608|FontID=1|IsHidden=T|Text=2000|Name=Package Quantity
|RECORD=41|OwnerIndex=1307|IndexInSheet=28|OwnerPartId=-1|Location.X=419|Location.Y=347|Color=8388608|FontID=1|IsHidden=T|Text=-55°C|Name=Min Operating Temperature
|RECORD=41|OwnerIndex=1307|IndexInSheet=29|OwnerPartId=-1|Location.X=419|Location.Y=347|Color=8388608|FontID=1|IsHidden=T|Text=X7R|Name=Dielectric
|RECORD=34|OwnerIndex=1307|IndexInSheet=-1|OwnerPartId=-1|Location.X=420|Location.Y=325|Orientation=1|Color=8388608|FontID=2|Text=C77|Name=Designator|ReadOnlyState=1
|RECORD=41|OwnerIndex=1307|IndexInSheet=-1|OwnerPartId=1|Location.X=450|Location.Y=310|Orientation=1|Color=8388608|FontID=2|Text=4.7uF_50V_1206|Name=Comment
|RECORD=44|OwnerIndex=1307
|RECORD=45|OwnerIndex=1342|IndexInSheet=-1|UseComponentLibrary=T|ModelName=FP-GRM31C-0_2-e0_3_0_8-IPC_C|ModelType=PCBLIB|DatafileCount=1|ModelDatafileEntity0=FP-GRM31C-0_2-e0_3_0_8-IPC_C|ModelDatafileKind0=PCBLib|IsCurrent=T|DatalinksLocked=T|DatabaseDatalinksLocked=T
|RECORD=46|OwnerIndex=1343
|RECORD=48|OwnerIndex=1343
|RECORD=45|OwnerIndex=1342|IndexInSheet=-1|UseComponentLibrary=T|ModelName=FP-GRM31C-0_2-e0_3_0_8-IPC_B|ModelType=PCBLIB|DatafileCount=1|ModelDatafileEntity0=FP-GRM31C-0_2-e0_3_0_8-IPC_B|ModelDatafileKind0=PCBLib|DatalinksLocked=T|DatabaseDatalinksLocked=T
|RECORD=46|OwnerIndex=1346
|RECORD=48|OwnerIndex=1346
|RECORD=45|OwnerIndex=1342|IndexInSheet=-1|UseComponentLibrary=T|ModelName=FP-GRM31C-0_2-e0_3_0_8-IPC_A|ModelType=PCBLIB|DatafileCount=1|ModelDatafileEntity0=FP-GRM31C-0_2-e0_3_0_8-IPC_A|ModelDatafileKind0=PCBLib|DatalinksLocked=T|DatabaseDatalinksLocked=T
|RECORD=46|OwnerIndex=1349
|RECORD=48|OwnerIndex=1349
|RECORD=45|OwnerIndex=1342|IndexInSheet=-1|UseComponentLibrary=T|ModelName=FP-GRM31C-0_2-e0_3_0_8-MFG|ModelType=PCBLIB|DatafileCount=1|ModelDatafileEntity0=FP-GRM31C-0_2-e0_3_0_8-MFG|ModelDatafileKind0=PCBLib|DatalinksLocked=T|DatabaseDatalinksLocked=T
|RECORD=46|OwnerIndex=1352
|RECORD=48|OwnerIndex=1352
|RECORD=1|LibReference=a00bbbee19879c290e62620ae7e47b1|ComponentDescription=CAP TANT 100UF 10% 16V 2917|PartCount=2|DisplayModeCount=1|IndexInSheet=92|OwnerPartId=-1|Location.X=340|Location.Y=345|CurrentPartId=1|LibraryPath=*|SourceLibraryName=Altium Content Vault|TargetFileName=*|AreaColor=11599871|Color=128|PartIDLocked=T|DesignItemId=CMP-2000-07207-2|AllPinCount=2
|RECORD=2|OwnerIndex=1355|OwnerPartId=1|Electrical=4|PinConglomerate=51|PinLength=8|Location.X=340|Location.Y=333|Name=C|Designator=1|PinPropagationDelay=0.000000E+000
|RECORD=2|OwnerIndex=1355|OwnerPartId=1|Electrical=4|PinConglomerate=49|PinLength=8|Location.X=340|Location.Y=337|Name=A|Designator=2|PinPropagationDelay=0.000000E+000
|RECORD=5|OwnerIndex=1355|IsNotAccesible=T|IndexInSheet=2|OwnerPartId=1|LineWidth=1|Color=16711680|LocationCount=4|X1=330|Y1=329|X2=335|Y2=335|X3=345|Y3=335|X4=350|Y4=329
|RECORD=13|OwnerIndex=1355|IsNotAccesible=T|IndexInSheet=3|OwnerPartId=1|Location.X=330|Location.Y=337|Corner.X=350|Corner.Y=337|LineWidth=1|Color=16711680
|RECORD=13|OwnerIndex=1355|IsNotAccesible=T|IndexInSheet=4|OwnerPartId=1|Location.X=340|Location.Y=333|Corner.X=340|Corner.Y=331|LineWidth=1|Color=16711680
|RECORD=13|OwnerIndex=1355|IsNotAccesible=T|IndexInSheet=5|OwnerPartId=1|Location.X=340|Location.Y=337|Corner.X=340|Corner.Y=340|LineWidth=1|Color=16711680
|RECORD=4|OwnerIndex=1355|IsNotAccesible=T|IndexInSheet=6|OwnerPartId=1|Location.X=329|Location.Y=347|Justification=6|Color=8388608|FontID=1|Text=+
|RECORD=41|OwnerIndex=1355|IndexInSheet=7|OwnerPartId=-1|Location.X=329|Location.Y=347|Color=8388608|FontID=1|IsHidden=T|Text=100uF|Name=Capacitance
|RECORD=41|OwnerIndex=1355|IndexInSheet=8|OwnerPartId=-1|Location.X=329|Location.Y=347|Color=8388608|FontID=1|IsHidden=T|Text=No|Name=Radiation Hardening
|RECORD=41|OwnerIndex=1355|IndexInSheet=9|OwnerPartId=-1|Location.X=329|Location.Y=347|Color=8388608|FontID=1|IsHidden=T|Text=Yes|Name=RoHS Compliant
|RECORD=41|OwnerIndex=1355|IndexInSheet=10|OwnerPartId=-1|Location.X=329|Location.Y=347|Color=8388608|FontID=1|IsHidden=T|Text=7.3mm|Name=Length
|RECORD=41|OwnerIndex=1355|IndexInSheet=11|OwnerPartId=-1|Location.X=329|Location.Y=347|Color=8388608|FontID=1|IsHidden=T|Text=General Purpose|Name=Features
|RECORD=41|OwnerIndex=1355|IndexInSheet=12|OwnerPartId=-1|Location.X=329|Location.Y=347|Color=8388608|FontID=1|IsHidden=T|Text=Tape and Reel|Name=Packaging
|RECORD=41|OwnerIndex=1355|IndexInSheet=13|OwnerPartId=-1|Location.X=329|Location.Y=347|Color=8388608|FontID=1|IsHidden=T|Text=1|Name=Package Quantity
|RECORD=41|OwnerIndex=1355|IndexInSheet=14|OwnerPartId=-1|Location.X=329|Location.Y=347|Color=8388608|FontID=1|IsHidden=T|Text=0.023634oz|Name=Weight
|RECORD=41|OwnerIndex=1355|IndexInSheet=15|OwnerPartId=-1|Location.X=329|Location.Y=347|Color=8388608|FontID=1|IsHidden=T|Text=2000Hour|Name=Life (Hours)
|RECORD=41|OwnerIndex=1355|IndexInSheet=16|OwnerPartId=-1|Location.X=329|Location.Y=347|Color=8388608|FontID=1|IsHidden=T|Text=16V|Name=Voltage Rating
|RECORD=41|OwnerIndex=1355|IndexInSheet=17|OwnerPartId=-1|Location.X=329|Location.Y=347|Color=8388608|FontID=1|IsHidden=T|Text=0.169inch|Name=Width
|RECORD=41|OwnerIndex=1355|IndexInSheet=18|OwnerPartId=-1|Location.X=329|Location.Y=347|Color=8388608|FontID=1|IsHidden=T|Text=2917|Name=Case/Package
|RECORD=41|OwnerIndex=1355|IndexInSheet=19|OwnerPartId=-1|Location.X=329|Location.Y=347|Color=8388608|FontID=1|IsHidden=T|Text=125mR|Name=ESR (Equivalent Series Resistance)
|RECORD=41|OwnerIndex=1355|IndexInSheet=20|OwnerPartId=-1|Location.X=329|Location.Y=347|Color=8388608|FontID=1|IsHidden=T|Text=Surface Mount|Name=Mount
|RECORD=41|OwnerIndex=1355|IndexInSheet=21|OwnerPartId=-1|Location.X=329|Location.Y=347|Color=8388608|FontID=1|IsHidden=T|Text=16V|Name=Voltage
|RECORD=41|OwnerIndex=1355|IndexInSheet=22|OwnerPartId=-1|Location.X=329|Location.Y=347|Color=8388608|FontID=1|IsHidden=T|Text=-55°C|Name=Min Operating Temperature
|RECORD=41|OwnerIndex=1355|IndexInSheet=23|OwnerPartId=-1|Location.X=329|Location.Y=347|Color=8388608|FontID=1|IsHidden=T|Text=10%|Name=Tolerance
|RECORD=41|OwnerIndex=1355|IndexInSheet=24|OwnerPartId=-1|Location.X=329|Location.Y=347|Color=8388608|FontID=1|IsHidden=T|Text=No SVHC|Name=REACH SVHC
|RECORD=41|OwnerIndex=1355|IndexInSheet=25|OwnerPartId=-1|Location.X=329|Location.Y=347|Color=8388608|FontID=1|IsHidden=T|Text=0.122inch|Name=Height - Seated (Max)
|RECORD=41|OwnerIndex=1355|IndexInSheet=26|OwnerPartId=-1|Location.X=329|Location.Y=347|Color=8388608|FontID=1|IsHidden=T|Text=2|Name=Number of Pins
|RECORD=41|OwnerIndex=1355|IndexInSheet=27|OwnerPartId=-1|Location.X=329|Location.Y=347|Color=8388608|FontID=1|IsHidden=T|Text=Flat|Name=Construction
|RECORD=41|OwnerIndex=1355|IndexInSheet=28|OwnerPartId=-1|Location.X=329|Location.Y=347|Color=8388608|FontID=1|IsHidden=T|Text=4.3mm|Name=Depth
|RECORD=41|OwnerIndex=1355|IndexInSheet=29|OwnerPartId=-1|Location.X=329|Location.Y=347|Color=8388608|FontID=1|IsHidden=T|Text=T495|Name=Series
|RECORD=41|OwnerIndex=1355|IndexInSheet=30|OwnerPartId=-1|Location.X=329|Location.Y=347|Color=8388608|FontID=1|IsHidden=T|Text=125°C|Name=Max Operating Temperature
|RECORD=41|OwnerIndex=1355|IndexInSheet=31|OwnerPartId=-1|Location.X=329|Location.Y=347|Color=8388608|FontID=1|IsHidden=T|Text=0.001%|Name=Failure Rate
|RECORD=41|OwnerIndex=1355|IndexInSheet=32|OwnerPartId=-1|Location.X=329|Location.Y=347|Color=8388608|FontID=1|IsHidden=T|Text=SMD/SMT|Name=Termination
|RECORD=41|OwnerIndex=1355|IndexInSheet=33|OwnerPartId=-1|Location.X=329|Location.Y=347|Color=8388608|FontID=1|IsHidden=T|Text=Polar|Name=Polarity
|RECORD=41|OwnerIndex=1355|IndexInSheet=34|OwnerPartId=-1|Location.X=329|Location.Y=347|Color=8388608|FontID=1|IsHidden=T|Text=16V|Name=Voltage Rating (DC)
|RECORD=41|OwnerIndex=1355|IndexInSheet=35|OwnerPartId=-1|Location.X=329|Location.Y=347|Color=8388608|FontID=1|IsHidden=T|Text=Tantalum|Name=Dielectric Material
|RECORD=41|OwnerIndex=1355|IndexInSheet=36|OwnerPartId=-1|Location.X=329|Location.Y=347|Color=8388608|FontID=1|IsHidden=T|Text=2917|Name=Case Code (Imperial)
|RECORD=41|OwnerIndex=1355|IndexInSheet=37|OwnerPartId=-1|Location.X=329|Location.Y=347|Color=8388608|FontID=1|IsHidden=T|Text=7343|Name=Case Code (Metric)
|RECORD=41|OwnerIndex=1355|IndexInSheet=38|OwnerPartId=-1|Location.X=329|Location.Y=347|Color=8388608|FontID=1|IsHidden=T|Text=2.8mm|Name=Height
|RECORD=41|OwnerIndex=1355|IndexInSheet=39|OwnerPartId=-1|Location.X=329|Location.Y=347|Color=8388608|FontID=1|IsHidden=T|Text=8%|Name=Dissipation Factor
|RECORD=34|OwnerIndex=1355|IndexInSheet=-1|OwnerPartId=-1|Location.X=325|Location.Y=325|Orientation=1|Color=8388608|FontID=2|Text=C75|Name=Designator|ReadOnlyState=1
|RECORD=41|OwnerIndex=1355|IndexInSheet=-1|OwnerPartId=1|Location.X=365|Location.Y=305|Orientation=1|Color=8388608|FontID=2|Text=100uF_16V_2917|Name=Comment
|RECORD=44|OwnerIndex=1355
|RECORD=45|OwnerIndex=1400|IndexInSheet=-1|UseComponentLibrary=T|ModelName=FP-T495D107K016ATE125-MFG|ModelType=PCBLIB|DatafileCount=1|ModelDatafileEntity0=FP-T495D107K016ATE125-MFG|ModelDatafileKind0=PCBLib|IsCurrent=T|DatalinksLocked=T|DatabaseDatalinksLocked=T
|RECORD=46|OwnerIndex=1401
|RECORD=48|OwnerIndex=1401
|RECORD=17|IndexInSheet=93|OwnerPartId=-1|ShowNetName=T|Location.X=905|Location.Y=420|Orientation=1|Color=128|FontID=1|Text=P3V3_SENSE
|RECORD=1|LibReference=RES|PartCount=2|DisplayModeCount=2|IndexInSheet=94|OwnerPartId=-1|Location.X=915|Location.Y=415|CurrentPartId=1|SourceLibraryName=Altium Content Vault|TargetFileName=*|AreaColor=11599871|Color=128|PartIDLocked=F|DesignItemId=CMP-2003-04334-1|AllPinCount=2
|RECORD=2|OwnerIndex=1405|OwnerPartId=1|OwnerPartDisplayMode=1|FormalType=1|Electrical=4|PinConglomerate=32|PinLength=10|Location.X=935|Location.Y=405|Name=2|Designator=2|PinPropagationDelay=0.000000E+000
|RECORD=2|OwnerIndex=1405|OwnerPartId=1|OwnerPartDisplayMode=1|FormalType=1|Electrical=4|PinConglomerate=34|PinLength=10|Location.X=915|Location.Y=405|Name=1|Designator=1|PinPropagationDelay=0.000000E+000
|RECORD=14|OwnerIndex=1405|IsNotAccesible=T|IndexInSheet=2|OwnerPartId=1|OwnerPartDisplayMode=1|Location.X=915|Location.Y=401|Corner.X=935|Corner.Y=409|LineWidth=1|Color=16711680|AreaColor=11599871
|RECORD=2|OwnerIndex=1405|OwnerPartId=1|FormalType=1|Electrical=4|PinConglomerate=32|PinLength=10|Location.X=935|Location.Y=405|Name=2|Designator=2|PinPropagationDelay=0.000000E+000
|RECORD=2|OwnerIndex=1405|OwnerPartId=1|FormalType=1|Electrical=4|PinConglomerate=34|PinLength=10|Location.X=915|Location.Y=405|Name=1|Designator=1|PinPropagationDelay=0.000000E+000
|RECORD=6|OwnerIndex=1405|IsNotAccesible=T|IndexInSheet=5|OwnerPartId=1|LineWidth=1|Color=16711680|LocationCount=10|X1=935|Y1=405|X2=931|Y2=405|X3=930|Y3=403|X4=928|Y4=407|X5=926|Y5=403|X6=924|Y6=407|X7=922|Y7=403|X8=920|Y8=407|X9=919|Y9=405|X10=915|Y10=405
|RECORD=41|OwnerIndex=1405|IndexInSheet=6|OwnerPartId=-1|Location.X=903|Location.Y=418|Color=8388608|FontID=1|IsHidden=T|Text=Vishay Dale|Name=Manufacturer
|RECORD=41|OwnerIndex=1405|IndexInSheet=7|OwnerPartId=-1|Location.X=903|Location.Y=418|Color=8388608|FontID=1|IsHidden=T|Text=WSL12062L000FEA18|Name=Part Number
|RECORD=34|OwnerIndex=1405|IndexInSheet=-1|OwnerPartId=-1|Location.X=914|Location.Y=408|Color=8388608|FontID=1|Text=R72|Name=Designator|ReadOnlyState=1
|RECORD=41|OwnerIndex=1405|IndexInSheet=-1|OwnerPartId=-1|Location.X=914|Location.Y=392|Color=8388608|FontID=1|Text=2mOhm_1%_1206|Name=Comment
|RECORD=44|OwnerIndex=1405
|RECORD=45|OwnerIndex=1420|IndexInSheet=-1|Description=Chip Resistor, 2-Leads, Body 3.20x1.60mm, IPC Medium Density|UseComponentLibrary=T|ModelName=RESC3216X89X64NL25T25|ModelType=PCBLIB|DatafileCount=1|ModelDatafileEntity0=RESC3216X89X64NL25T25|ModelDatafileKind0=PCBLib|IsCurrent=T|DatalinksLocked=T|DatabaseDatalinksLocked=T
|RECORD=46|OwnerIndex=1421
|RECORD=48|OwnerIndex=1421
|RECORD=41|OwnerIndex=1423|IndexInSheet=-1|OwnerPartId=-1|Color=8388608|FontID=1|IsHidden=T|Text=2D|Name=Available Preview Images
|RECORD=45|OwnerIndex=1420|IndexInSheet=-1|Description=Chip Resistor, 2-Leads, Body 3.20x1.60mm, IPC High Density|UseComponentLibrary=T|ModelName=RESC3216X89X64LL25T25|ModelType=PCBLIB|DatafileCount=1|ModelDatafileEntity0=RESC3216X89X64LL25T25|ModelDatafileKind0=PCBLib|DatalinksLocked=T|DatabaseDatalinksLocked=T
|RECORD=46|OwnerIndex=1425
|RECORD=48|OwnerIndex=1425
|RECORD=41|OwnerIndex=1427|IndexInSheet=-1|OwnerPartId=-1|Color=8388608|FontID=1|IsHidden=T|Text=2D|Name=Available Preview Images
|RECORD=45|OwnerIndex=1420|IndexInSheet=-1|Description=Chip Resistor, 2-Leads, Body 3.20x1.60mm, IPC Low Density|UseComponentLibrary=T|ModelName=RESC3216X89X64ML25T25|ModelType=PCBLIB|DatafileCount=1|ModelDatafileEntity0=RESC3216X89X64ML25T25|ModelDatafileKind0=PCBLib|DatalinksLocked=T|DatabaseDatalinksLocked=T
|RECORD=46|OwnerIndex=1429
|RECORD=48|OwnerIndex=1429
|RECORD=41|OwnerIndex=1431|IndexInSheet=-1|OwnerPartId=-1|Color=8388608|FontID=1|IsHidden=T|Text=2D|Name=Available Preview Images
|RECORD=1|LibReference=b4654b650e69147ec39a6b967a45e02|ComponentDescription=Multilayer Ceramic Capacitor 10uF 16V X5R 20% SMD 0603 T/R|PartCount=2|DisplayModeCount=1|IndexInSheet=95|OwnerPartId=-1|Location.X=1095|Location.Y=355|CurrentPartId=1|LibraryPath=*|SourceLibraryName=Altium Content Vault|TargetFileName=*|AreaColor=11599871|Color=128|PartIDLocked=T|DesignItemId=CMP-2000-06226-4|AllPinCount=2
|RECORD=2|OwnerIndex=1433|OwnerPartId=1|Electrical=4|PinConglomerate=49|PinLength=7|Location.X=1095|Location.Y=348|Name=1|Designator=1|PinPropagationDelay=0.000000E+000
|RECORD=2|OwnerIndex=1433|OwnerPartId=1|Electrical=4|PinConglomerate=51|PinLength=6|Location.X=1095|Location.Y=341|Name=2|Designator=2|PinPropagationDelay=0.000000E+000
|RECORD=13|OwnerIndex=1433|IsNotAccesible=T|IndexInSheet=2|OwnerPartId=1|Location.X=1105|Location.Y=348|Corner.X=1085|Corner.Y=348|LineWidth=1|Color=16711680
|RECORD=13|OwnerIndex=1433|IsNotAccesible=T|IndexInSheet=3|OwnerPartId=1|Location.X=1105|Location.Y=342|Corner.X=1085|Corner.Y=342|LineWidth=1|Color=16711680
|RECORD=13|OwnerIndex=1433|IsNotAccesible=T|IndexInSheet=4|OwnerPartId=1|Location.X=1095|Location.Y=348|Corner.X=1095|Corner.Y=351|LineWidth=1|Color=16711680
|RECORD=13|OwnerIndex=1433|IsNotAccesible=T|IndexInSheet=5|OwnerPartId=1|Location.X=1095|Location.Y=341|Corner.X=1095|Corner.Y=340|LineWidth=1|Color=16711680
|RECORD=41|OwnerIndex=1433|IndexInSheet=6|OwnerPartId=-1|Location.X=1084|Location.Y=357|Color=8388608|FontID=1|IsHidden=T|Text=Tape and Reel|Name=Packaging
|RECORD=41|OwnerIndex=1433|IndexInSheet=7|OwnerPartId=-1|Location.X=1084|Location.Y=357|Color=8388608|FontID=1|IsHidden=T|Text=Flat|Name=Construction
|RECORD=41|OwnerIndex=1433|IndexInSheet=8|OwnerPartId=-1|Location.X=1084|Location.Y=357|Color=8388608|FontID=1|IsHidden=T|Text=0.8mm|Name=Height
|RECORD=41|OwnerIndex=1433|IndexInSheet=9|OwnerPartId=-1|Location.X=1084|Location.Y=357|Color=8388608|FontID=1|IsHidden=T|Text=85°C|Name=Max Operating Temperature
|RECORD=41|OwnerIndex=1433|IndexInSheet=10|OwnerPartId=-1|Location.X=1084|Location.Y=357|Color=8388608|FontID=1|IsHidden=T|Text=X5R|Name=Dielectric
|RECORD=41|OwnerIndex=1433|IndexInSheet=11|OwnerPartId=-1|Location.X=1084|Location.Y=357|Color=8388608|FontID=1|IsHidden=T|Text=1608|Name=Case Code (Metric)
|RECORD=41|OwnerIndex=1433|IndexInSheet=12|OwnerPartId=-1|Location.X=1084|Location.Y=357|Color=8388608|FontID=1|IsHidden=T|Text=16V|Name=Voltage Rating (DC)
|RECORD=41|OwnerIndex=1433|IndexInSheet=13|OwnerPartId=-1|Location.X=1084|Location.Y=357|Color=8388608|FontID=1|IsHidden=T|Text=0.031inch|Name=Width
|RECORD=41|OwnerIndex=1433|IndexInSheet=14|OwnerPartId=-1|Location.X=1084|Location.Y=357|Color=8388608|FontID=1|IsHidden=T|Text=16V|Name=Voltage Rating
|RECORD=41|OwnerIndex=1433|IndexInSheet=15|OwnerPartId=-1|Location.X=1084|Location.Y=357|Color=8388608|FontID=1|IsHidden=T|Text=0.063inch|Name=Length
|RECORD=41|OwnerIndex=1433|IndexInSheet=16|OwnerPartId=-1|Location.X=1084|Location.Y=357|Color=8388608|FontID=1|IsHidden=T|Text=Yes|Name=RoHS Compliant
|RECORD=41|OwnerIndex=1433|IndexInSheet=17|OwnerPartId=-1|Location.X=1084|Location.Y=357|Color=8388608|FontID=1|IsHidden=T|Text=Halogen Free|Name=Halogen Free
|RECORD=41|OwnerIndex=1433|IndexInSheet=18|OwnerPartId=-1|Location.X=1084|Location.Y=357|Color=8388608|FontID=1|IsHidden=T|Text=0603|Name=Case Code (Imperial)
|RECORD=41|OwnerIndex=1433|IndexInSheet=19|OwnerPartId=-1|Location.X=1084|Location.Y=357|Color=8388608|FontID=1|IsHidden=T|Text=10uF|Name=Capacitance
|RECORD=41|OwnerIndex=1433|IndexInSheet=20|OwnerPartId=-1|Location.X=1084|Location.Y=357|Color=8388608|FontID=1|IsHidden=T|Text=Surface Mount|Name=Mount
|RECORD=41|OwnerIndex=1433|IndexInSheet=21|OwnerPartId=-1|Location.X=1084|Location.Y=357|Color=8388608|FontID=1|IsHidden=T|Text=0.031inch|Name=Thickness
|RECORD=41|OwnerIndex=1433|IndexInSheet=22|OwnerPartId=-1|Location.X=1084|Location.Y=357|Color=8388608|FontID=1|IsHidden=T|Text=20%|Name=Tolerance
|RECORD=41|OwnerIndex=1433|IndexInSheet=23|OwnerPartId=-1|Location.X=1084|Location.Y=357|Color=8388608|FontID=1|IsHidden=T|Text=-55°C|Name=Min Operating Temperature
|RECORD=41|OwnerIndex=1433|IndexInSheet=24|OwnerPartId=-1|Location.X=1084|Location.Y=357|Color=8388608|FontID=1|IsHidden=T|Text=M|Name=Series
|RECORD=41|OwnerIndex=1433|IndexInSheet=25|OwnerPartId=-1|Location.X=1084|Location.Y=357|Color=8388608|FontID=1|IsHidden=T|Text=SMD/SMT|Name=Termination
|RECORD=41|OwnerIndex=1433|IndexInSheet=26|OwnerPartId=-1|Location.X=1084|Location.Y=357|Color=8388608|FontID=1|IsHidden=T|Text=0603|Name=Case/Package
|RECORD=41|OwnerIndex=1433|IndexInSheet=27|OwnerPartId=-1|Location.X=1084|Location.Y=357|Color=8388608|FontID=1|IsHidden=T|Text=1|Name=Package Quantity
|RECORD=34|OwnerIndex=1433|IndexInSheet=-1|OwnerPartId=-1|Location.X=1085|Location.Y=335|Orientation=1|Color=8388608|FontID=2|Text=C80|Name=Designator|ReadOnlyState=1
|RECORD=41|OwnerIndex=1433|IndexInSheet=-1|OwnerPartId=1|Location.X=1115|Location.Y=320|Orientation=1|Color=8388608|FontID=2|Text=10uF_16V_0603|Name=Comment
|RECORD=44|OwnerIndex=1433
|RECORD=45|OwnerIndex=1466|IndexInSheet=-1|UseComponentLibrary=T|ModelName=FP-0603-L_1_6_0_2-W_0_8_0-MFG|ModelType=PCBLIB|DatafileCount=1|ModelDatafileEntity0=FP-0603-L_1_6_0_2-W_0_8_0-MFG|ModelDatafileKind0=PCBLib|IsCurrent=T|DatalinksLocked=T|DatabaseDatalinksLocked=T
|RECORD=46|OwnerIndex=1467
|RECORD=48|OwnerIndex=1467
|RECORD=45|OwnerIndex=1466|IndexInSheet=-1|UseComponentLibrary=T|ModelName=FP-0603-L_1_6_0_2-W_0_8_0-IPC_B|ModelType=PCBLIB|DatafileCount=1|ModelDatafileEntity0=FP-0603-L_1_6_0_2-W_0_8_0-IPC_B|ModelDatafileKind0=PCBLib|DatalinksLocked=T|DatabaseDatalinksLocked=T
|RECORD=46|OwnerIndex=1470
|RECORD=48|OwnerIndex=1470
|RECORD=45|OwnerIndex=1466|IndexInSheet=-1|UseComponentLibrary=T|ModelName=FP-0603-L_1_6_0_2-W_0_8_0-IPC_C|ModelType=PCBLIB|DatafileCount=1|ModelDatafileEntity0=FP-0603-L_1_6_0_2-W_0_8_0-IPC_C|ModelDatafileKind0=PCBLib|DatalinksLocked=T|DatabaseDatalinksLocked=T
|RECORD=46|OwnerIndex=1473
|RECORD=48|OwnerIndex=1473
|RECORD=45|OwnerIndex=1466|IndexInSheet=-1|UseComponentLibrary=T|ModelName=FP-0603-L_1_6_0_2-W_0_8_0-IPC_A|ModelType=PCBLIB|DatafileCount=1|ModelDatafileEntity0=FP-0603-L_1_6_0_2-W_0_8_0-IPC_A|ModelDatafileKind0=PCBLib|DatalinksLocked=T|DatabaseDatalinksLocked=T
|RECORD=46|OwnerIndex=1476
|RECORD=48|OwnerIndex=1476
|RECORD=1|LibReference=a00bbbee19879c290e62620ae7e47b1|ComponentDescription=CAP TANT 100UF 10% 16V 2917|PartCount=2|DisplayModeCount=1|IndexInSheet=96|OwnerPartId=-1|Location.X=1010|Location.Y=355|CurrentPartId=1|LibraryPath=*|SourceLibraryName=Altium Content Vault|TargetFileName=*|AreaColor=11599871|Color=128|PartIDLocked=T|DesignItemId=CMP-2000-07207-2|AllPinCount=2
|RECORD=2|OwnerIndex=1479|OwnerPartId=1|Electrical=4|PinConglomerate=51|PinLength=8|Location.X=1010|Location.Y=343|Name=C|Designator=1|PinPropagationDelay=0.000000E+000
|RECORD=2|OwnerIndex=1479|OwnerPartId=1|Electrical=4|PinConglomerate=49|PinLength=8|Location.X=1010|Location.Y=347|Name=A|Designator=2|PinPropagationDelay=0.000000E+000
|RECORD=5|OwnerIndex=1479|IsNotAccesible=T|IndexInSheet=2|OwnerPartId=1|LineWidth=1|Color=16711680|LocationCount=4|X1=1000|Y1=339|X2=1005|Y2=345|X3=1015|Y3=345|X4=1020|Y4=339
|RECORD=13|OwnerIndex=1479|IsNotAccesible=T|IndexInSheet=3|OwnerPartId=1|Location.X=1000|Location.Y=347|Corner.X=1020|Corner.Y=347|LineWidth=1|Color=16711680
|RECORD=13|OwnerIndex=1479|IsNotAccesible=T|IndexInSheet=4|OwnerPartId=1|Location.X=1010|Location.Y=343|Corner.X=1010|Corner.Y=341|LineWidth=1|Color=16711680
|RECORD=13|OwnerIndex=1479|IsNotAccesible=T|IndexInSheet=5|OwnerPartId=1|Location.X=1010|Location.Y=347|Corner.X=1010|Corner.Y=350|LineWidth=1|Color=16711680
|RECORD=4|OwnerIndex=1479|IsNotAccesible=T|IndexInSheet=6|OwnerPartId=1|Location.X=999|Location.Y=357|Justification=6|Color=8388608|FontID=1|Text=+
|RECORD=41|OwnerIndex=1479|IndexInSheet=7|OwnerPartId=-1|Location.X=999|Location.Y=357|Color=8388608|FontID=1|IsHidden=T|Text=100uF|Name=Capacitance
|RECORD=41|OwnerIndex=1479|IndexInSheet=8|OwnerPartId=-1|Location.X=999|Location.Y=357|Color=8388608|FontID=1|IsHidden=T|Text=No|Name=Radiation Hardening
|RECORD=41|OwnerIndex=1479|IndexInSheet=9|OwnerPartId=-1|Location.X=999|Location.Y=357|Color=8388608|FontID=1|IsHidden=T|Text=Yes|Name=RoHS Compliant
|RECORD=41|OwnerIndex=1479|IndexInSheet=10|OwnerPartId=-1|Location.X=999|Location.Y=357|Color=8388608|FontID=1|IsHidden=T|Text=7.3mm|Name=Length
|RECORD=41|OwnerIndex=1479|IndexInSheet=11|OwnerPartId=-1|Location.X=999|Location.Y=357|Color=8388608|FontID=1|IsHidden=T|Text=General Purpose|Name=Features
|RECORD=41|OwnerIndex=1479|IndexInSheet=12|OwnerPartId=-1|Location.X=999|Location.Y=357|Color=8388608|FontID=1|IsHidden=T|Text=Tape and Reel|Name=Packaging
|RECORD=41|OwnerIndex=1479|IndexInSheet=13|OwnerPartId=-1|Location.X=999|Location.Y=357|Color=8388608|FontID=1|IsHidden=T|Text=1|Name=Package Quantity
|RECORD=41|OwnerIndex=1479|IndexInSheet=14|OwnerPartId=-1|Location.X=999|Location.Y=357|Color=8388608|FontID=1|IsHidden=T|Text=0.023634oz|Name=Weight
|RECORD=41|OwnerIndex=1479|IndexInSheet=15|OwnerPartId=-1|Location.X=999|Location.Y=357|Color=8388608|FontID=1|IsHidden=T|Text=2000Hour|Name=Life (Hours)
|RECORD=41|OwnerIndex=1479|IndexInSheet=16|OwnerPartId=-1|Location.X=999|Location.Y=357|Color=8388608|FontID=1|IsHidden=T|Text=16V|Name=Voltage Rating
|RECORD=41|OwnerIndex=1479|IndexInSheet=17|OwnerPartId=-1|Location.X=999|Location.Y=357|Color=8388608|FontID=1|IsHidden=T|Text=0.169inch|Name=Width
|RECORD=41|OwnerIndex=1479|IndexInSheet=18|OwnerPartId=-1|Location.X=999|Location.Y=357|Color=8388608|FontID=1|IsHidden=T|Text=2917|Name=Case/Package
|RECORD=41|OwnerIndex=1479|IndexInSheet=19|OwnerPartId=-1|Location.X=999|Location.Y=357|Color=8388608|FontID=1|IsHidden=T|Text=125mR|Name=ESR (Equivalent Series Resistance)
|RECORD=41|OwnerIndex=1479|IndexInSheet=20|OwnerPartId=-1|Location.X=999|Location.Y=357|Color=8388608|FontID=1|IsHidden=T|Text=Surface Mount|Name=Mount
|RECORD=41|OwnerIndex=1479|IndexInSheet=21|OwnerPartId=-1|Location.X=999|Location.Y=357|Color=8388608|FontID=1|IsHidden=T|Text=16V|Name=Voltage
|RECORD=41|OwnerIndex=1479|IndexInSheet=22|OwnerPartId=-1|Location.X=999|Location.Y=357|Color=8388608|FontID=1|IsHidden=T|Text=-55°C|Name=Min Operating Temperature
|RECORD=41|OwnerIndex=1479|IndexInSheet=23|OwnerPartId=-1|Location.X=999|Location.Y=357|Color=8388608|FontID=1|IsHidden=T|Text=10%|Name=Tolerance
|RECORD=41|OwnerIndex=1479|IndexInSheet=24|OwnerPartId=-1|Location.X=999|Location.Y=357|Color=8388608|FontID=1|IsHidden=T|Text=No SVHC|Name=REACH SVHC
|RECORD=41|OwnerIndex=1479|IndexInSheet=25|OwnerPartId=-1|Location.X=999|Location.Y=357|Color=8388608|FontID=1|IsHidden=T|Text=0.122inch|Name=Height - Seated (Max)
|RECORD=41|OwnerIndex=1479|IndexInSheet=26|OwnerPartId=-1|Location.X=999|Location.Y=357|Color=8388608|FontID=1|IsHidden=T|Text=2|Name=Number of Pins
|RECORD=41|OwnerIndex=1479|IndexInSheet=27|OwnerPartId=-1|Location.X=999|Location.Y=357|Color=8388608|FontID=1|IsHidden=T|Text=Flat|Name=Construction
|RECORD=41|OwnerIndex=1479|IndexInSheet=28|OwnerPartId=-1|Location.X=999|Location.Y=357|Color=8388608|FontID=1|IsHidden=T|Text=4.3mm|Name=Depth
|RECORD=41|OwnerIndex=1479|IndexInSheet=29|OwnerPartId=-1|Location.X=999|Location.Y=357|Color=8388608|FontID=1|IsHidden=T|Text=T495|Name=Series
|RECORD=41|OwnerIndex=1479|IndexInSheet=30|OwnerPartId=-1|Location.X=999|Location.Y=357|Color=8388608|FontID=1|IsHidden=T|Text=125°C|Name=Max Operating Temperature
|RECORD=41|OwnerIndex=1479|IndexInSheet=31|OwnerPartId=-1|Location.X=999|Location.Y=357|Color=8388608|FontID=1|IsHidden=T|Text=0.001%|Name=Failure Rate
|RECORD=41|OwnerIndex=1479|IndexInSheet=32|OwnerPartId=-1|Location.X=999|Location.Y=357|Color=8388608|FontID=1|IsHidden=T|Text=SMD/SMT|Name=Termination
|RECORD=41|OwnerIndex=1479|IndexInSheet=33|OwnerPartId=-1|Location.X=999|Location.Y=357|Color=8388608|FontID=1|IsHidden=T|Text=Polar|Name=Polarity
|RECORD=41|OwnerIndex=1479|IndexInSheet=34|OwnerPartId=-1|Location.X=999|Location.Y=357|Color=8388608|FontID=1|IsHidden=T|Text=16V|Name=Voltage Rating (DC)
|RECORD=41|OwnerIndex=1479|IndexInSheet=35|OwnerPartId=-1|Location.X=999|Location.Y=357|Color=8388608|FontID=1|IsHidden=T|Text=Tantalum|Name=Dielectric Material
|RECORD=41|OwnerIndex=1479|IndexInSheet=36|OwnerPartId=-1|Location.X=999|Location.Y=357|Color=8388608|FontID=1|IsHidden=T|Text=2917|Name=Case Code (Imperial)
|RECORD=41|OwnerIndex=1479|IndexInSheet=37|OwnerPartId=-1|Location.X=999|Location.Y=357|Color=8388608|FontID=1|IsHidden=T|Text=7343|Name=Case Code (Metric)
|RECORD=41|OwnerIndex=1479|IndexInSheet=38|OwnerPartId=-1|Location.X=999|Location.Y=357|Color=8388608|FontID=1|IsHidden=T|Text=2.8mm|Name=Height
|RECORD=41|OwnerIndex=1479|IndexInSheet=39|OwnerPartId=-1|Location.X=999|Location.Y=357|Color=8388608|FontID=1|IsHidden=T|Text=8%|Name=Dissipation Factor
|RECORD=34|OwnerIndex=1479|IndexInSheet=-1|OwnerPartId=-1|Location.X=995|Location.Y=335|Orientation=1|Color=8388608|FontID=2|Text=C79|Name=Designator|ReadOnlyState=1
|RECORD=41|OwnerIndex=1479|IndexInSheet=-1|OwnerPartId=1|Location.X=1035|Location.Y=315|Orientation=1|Color=8388608|FontID=2|Text=100uF_16V_2917|Name=Comment
|RECORD=44|OwnerIndex=1479
|RECORD=45|OwnerIndex=1524|IndexInSheet=-1|UseComponentLibrary=T|ModelName=FP-T495D107K016ATE125-MFG|ModelType=PCBLIB|DatafileCount=1|ModelDatafileEntity0=FP-T495D107K016ATE125-MFG|ModelDatafileKind0=PCBLib|IsCurrent=T|DatalinksLocked=T|DatabaseDatalinksLocked=T
|RECORD=46|OwnerIndex=1525
|RECORD=48|OwnerIndex=1525
|RECORD=1|LibReference=b4654b650e69147ec39a6b967a45e02|ComponentDescription=Multilayer Ceramic Capacitors 2.2µF ±10% 16V X5R SMD 0402|PartCount=2|DisplayModeCount=1|IndexInSheet=97|OwnerPartId=-1|Location.X=1140|Location.Y=355|CurrentPartId=1|LibraryPath=*|SourceLibraryName=Altium Content Vault|TargetFileName=*|AreaColor=11599871|Color=128|PartIDLocked=T|DesignItemId=CMP-2000-05998-2|AllPinCount=2
|RECORD=2|OwnerIndex=1528|OwnerPartId=1|Electrical=4|PinConglomerate=49|PinLength=7|Location.X=1140|Location.Y=348|Name=1|Designator=1|PinPropagationDelay=0.000000E+000
|RECORD=2|OwnerIndex=1528|OwnerPartId=1|Electrical=4|PinConglomerate=51|PinLength=6|Location.X=1140|Location.Y=341|Name=2|Designator=2|PinPropagationDelay=0.000000E+000
|RECORD=13|OwnerIndex=1528|IsNotAccesible=T|IndexInSheet=2|OwnerPartId=1|Location.X=1150|Location.Y=348|Corner.X=1130|Corner.Y=348|LineWidth=1|Color=16711680
|RECORD=13|OwnerIndex=1528|IsNotAccesible=T|IndexInSheet=3|OwnerPartId=1|Location.X=1150|Location.Y=342|Corner.X=1130|Corner.Y=342|LineWidth=1|Color=16711680
|RECORD=13|OwnerIndex=1528|IsNotAccesible=T|IndexInSheet=4|OwnerPartId=1|Location.X=1140|Location.Y=348|Corner.X=1140|Corner.Y=351|LineWidth=1|Color=16711680
|RECORD=13|OwnerIndex=1528|IsNotAccesible=T|IndexInSheet=5|OwnerPartId=1|Location.X=1140|Location.Y=341|Corner.X=1140|Corner.Y=340|LineWidth=1|Color=16711680
|RECORD=41|OwnerIndex=1528|IndexInSheet=6|OwnerPartId=-1|Location.X=1129|Location.Y=357|Color=8388608|FontID=1|IsHidden=T|Text=No SVHC|Name=REACH SVHC
|RECORD=41|OwnerIndex=1528|IndexInSheet=7|OwnerPartId=-1|Location.X=1129|Location.Y=357|Color=8388608|FontID=1|IsHidden=T|Text=C|Name=Series
|RECORD=41|OwnerIndex=1528|IndexInSheet=8|OwnerPartId=-1|Location.X=1129|Location.Y=357|Color=8388608|FontID=1|IsHidden=T|Text=SMD/SMT|Name=Termination
|RECORD=41|OwnerIndex=1528|IndexInSheet=9|OwnerPartId=-1|Location.X=1129|Location.Y=357|Color=8388608|FontID=1|IsHidden=T|Text=0402|Name=Case Code (Imperial)
|RECORD=41|OwnerIndex=1528|IndexInSheet=10|OwnerPartId=-1|Location.X=1129|Location.Y=357|Color=8388608|FontID=1|IsHidden=T|Text=0.5mm|Name=Depth
|RECORD=41|OwnerIndex=1528|IndexInSheet=11|OwnerPartId=-1|Location.X=1129|Location.Y=357|Color=8388608|FontID=1|IsHidden=T|Text=Surface Mount|Name=Mount
|RECORD=41|OwnerIndex=1528|IndexInSheet=12|OwnerPartId=-1|Location.X=1129|Location.Y=357|Color=8388608|FontID=1|IsHidden=T|Text=0.02inch|Name=Width
|RECORD=41|OwnerIndex=1528|IndexInSheet=13|OwnerPartId=-1|Location.X=1129|Location.Y=357|Color=8388608|FontID=1|IsHidden=T|Text=1|Name=Package Quantity
|RECORD=41|OwnerIndex=1528|IndexInSheet=14|OwnerPartId=-1|Location.X=1129|Location.Y=357|Color=8388608|FontID=1|IsHidden=T|Text=Ceramic|Name=Dielectric Material
|RECORD=41|OwnerIndex=1528|IndexInSheet=15|OwnerPartId=-1|Location.X=1129|Location.Y=357|Color=8388608|FontID=1|IsHidden=T|Text=1mm|Name=Length
|RECORD=41|OwnerIndex=1528|IndexInSheet=16|OwnerPartId=-1|Location.X=1129|Location.Y=357|Color=8388608|FontID=1|IsHidden=T|Text=Tape and Reel|Name=Packaging
|RECORD=41|OwnerIndex=1528|IndexInSheet=17|OwnerPartId=-1|Location.X=1129|Location.Y=357|Color=8388608|FontID=1|IsHidden=T|Text=1005|Name=Case Code (Metric)
|RECORD=41|OwnerIndex=1528|IndexInSheet=18|OwnerPartId=-1|Location.X=1129|Location.Y=357|Color=8388608|FontID=1|IsHidden=T|Text=Yes|Name=RoHS Compliant
|RECORD=41|OwnerIndex=1528|IndexInSheet=19|OwnerPartId=-1|Location.X=1129|Location.Y=357|Color=8388608|FontID=1|IsHidden=T|Text=X5R|Name=Dielectric
|RECORD=41|OwnerIndex=1528|IndexInSheet=20|OwnerPartId=-1|Location.X=1129|Location.Y=357|Color=8388608|FontID=1|IsHidden=T|Text=85°C|Name=Max Operating Temperature
|RECORD=41|OwnerIndex=1528|IndexInSheet=21|OwnerPartId=-1|Location.X=1129|Location.Y=357|Color=8388608|FontID=1|IsHidden=T|Text=Lead Free|Name=Lead Free
|RECORD=41|OwnerIndex=1528|IndexInSheet=22|OwnerPartId=-1|Location.X=1129|Location.Y=357|Color=8388608|FontID=1|IsHidden=T|Text=2.3E-05oz|Name=Weight
|RECORD=41|OwnerIndex=1528|IndexInSheet=23|OwnerPartId=-1|Location.X=1129|Location.Y=357|Color=8388608|FontID=1|IsHidden=T|Text=0.022inch|Name=Thickness
|RECORD=41|OwnerIndex=1528|IndexInSheet=24|OwnerPartId=-1|Location.X=1129|Location.Y=357|Color=8388608|FontID=1|IsHidden=T|Text=2.2uF|Name=Capacitance
|RECORD=41|OwnerIndex=1528|IndexInSheet=25|OwnerPartId=-1|Location.X=1129|Location.Y=357|Color=8388608|FontID=1|IsHidden=T|Text=16V|Name=Voltage Rating (DC)
|RECORD=41|OwnerIndex=1528|IndexInSheet=26|OwnerPartId=-1|Location.X=1129|Location.Y=357|Color=8388608|FontID=1|IsHidden=T|Text=10%|Name=Tolerance
|RECORD=41|OwnerIndex=1528|IndexInSheet=27|OwnerPartId=-1|Location.X=1129|Location.Y=357|Color=8388608|FontID=1|IsHidden=T|Text=16V|Name=Voltage Rating
|RECORD=41|OwnerIndex=1528|IndexInSheet=28|OwnerPartId=-1|Location.X=1129|Location.Y=357|Color=8388608|FontID=1|IsHidden=T|Text=Ceramic|Name=Resistor Type
|RECORD=41|OwnerIndex=1528|IndexInSheet=29|OwnerPartId=-1|Location.X=1129|Location.Y=357|Color=8388608|FontID=1|IsHidden=T|Text=0.5mm|Name=Height
|RECORD=41|OwnerIndex=1528|IndexInSheet=30|OwnerPartId=-1|Location.X=1129|Location.Y=357|Color=8388608|FontID=1|IsHidden=T|Text=0402|Name=Case/Package
|RECORD=41|OwnerIndex=1528|IndexInSheet=31|OwnerPartId=-1|Location.X=1129|Location.Y=357|Color=8388608|FontID=1|IsHidden=T|Text=-55°C|Name=Min Operating Temperature
|RECORD=34|OwnerIndex=1528|IndexInSheet=-1|OwnerPartId=-1|Location.X=1130|Location.Y=335|Orientation=1|Color=8388608|FontID=2|Text=C81|Name=Designator|ReadOnlyState=1
|RECORD=41|OwnerIndex=1528|IndexInSheet=-1|OwnerPartId=1|Location.X=1160|Location.Y=310|Orientation=1|Color=8388608|FontID=2|Text=2.2uF_16V_0402|Name=Comment
|RECORD=44|OwnerIndex=1528
|RECORD=45|OwnerIndex=1565|IndexInSheet=-1|UseComponentLibrary=T|ModelName=FP-C1005-050-0_05-IPC_A|ModelType=PCBLIB|DatafileCount=1|ModelDatafileEntity0=FP-C1005-050-0_05-IPC_A|ModelDatafileKind0=PCBLib|IsCurrent=T|DatalinksLocked=T|DatabaseDatalinksLocked=T
|RECORD=46|OwnerIndex=1566
|RECORD=48|OwnerIndex=1566
|RECORD=45|OwnerIndex=1565|IndexInSheet=-1|UseComponentLibrary=T|ModelName=FP-C1005-050-0_05-MFG|ModelType=PCBLIB|DatafileCount=1|ModelDatafileEntity0=FP-C1005-050-0_05-MFG|ModelDatafileKind0=PCBLib|DatalinksLocked=T|DatabaseDatalinksLocked=T
|RECORD=46|OwnerIndex=1569
|RECORD=48|OwnerIndex=1569
|RECORD=45|OwnerIndex=1565|IndexInSheet=-1|UseComponentLibrary=T|ModelName=FP-C1005-050-0_05-IPC_C|ModelType=PCBLIB|DatafileCount=1|ModelDatafileEntity0=FP-C1005-050-0_05-IPC_C|ModelDatafileKind0=PCBLib|DatalinksLocked=T|DatabaseDatalinksLocked=T
|RECORD=46|OwnerIndex=1572
|RECORD=48|OwnerIndex=1572
|RECORD=45|OwnerIndex=1565|IndexInSheet=-1|UseComponentLibrary=T|ModelName=FP-C1005-050-0_05-IPC_B|ModelType=PCBLIB|DatafileCount=1|ModelDatafileEntity0=FP-C1005-050-0_05-IPC_B|ModelDatafileKind0=PCBLib|DatalinksLocked=T|DatabaseDatalinksLocked=T
|RECORD=46|OwnerIndex=1575
|RECORD=48|OwnerIndex=1575
|RECORD=1|LibReference=b4654b650e69147ec39a6b967a45e02|ComponentDescription=None|PartCount=2|DisplayModeCount=1|IndexInSheet=98|OwnerPartId=-1|Location.X=1185|Location.Y=355|CurrentPartId=1|LibraryPath=*|SourceLibraryName=Altium Content Vault|TargetFileName=*|AreaColor=11599871|Color=128|PartIDLocked=T|DesignItemId=CMP-14477-000104-2|AllPinCount=2
|RECORD=2|OwnerIndex=1578|OwnerPartId=1|Electrical=4|PinConglomerate=49|PinLength=7|Location.X=1185|Location.Y=348|Name=1|Designator=1|PinPropagationDelay=0.000000E+000
|RECORD=2|OwnerIndex=1578|OwnerPartId=1|Electrical=4|PinConglomerate=51|PinLength=6|Location.X=1185|Location.Y=341|Name=2|Designator=2|PinPropagationDelay=0.000000E+000
|RECORD=13|OwnerIndex=1578|IsNotAccesible=T|IndexInSheet=2|OwnerPartId=1|Location.X=1195|Location.Y=348|Corner.X=1175|Corner.Y=348|LineWidth=1|Color=16711680
|RECORD=13|OwnerIndex=1578|IsNotAccesible=T|IndexInSheet=3|OwnerPartId=1|Location.X=1195|Location.Y=342|Corner.X=1175|Corner.Y=342|LineWidth=1|Color=16711680
|RECORD=13|OwnerIndex=1578|IsNotAccesible=T|IndexInSheet=4|OwnerPartId=1|Location.X=1185|Location.Y=348|Corner.X=1185|Corner.Y=351|LineWidth=1|Color=16711680
|RECORD=13|OwnerIndex=1578|IsNotAccesible=T|IndexInSheet=5|OwnerPartId=1|Location.X=1185|Location.Y=341|Corner.X=1185|Corner.Y=340|LineWidth=1|Color=16711680
|RECORD=41|OwnerIndex=1578|IndexInSheet=6|OwnerPartId=-1|Location.X=1174|Location.Y=357|Color=8388608|FontID=1|IsHidden=T|Text=Tape and Reel|Name=Packaging
|RECORD=41|OwnerIndex=1578|IndexInSheet=7|OwnerPartId=-1|Location.X=1174|Location.Y=357|Color=8388608|FontID=1|IsHidden=T|Text=0.5mm|Name=Depth
|RECORD=41|OwnerIndex=1578|IndexInSheet=8|OwnerPartId=-1|Location.X=1174|Location.Y=357|Color=8388608|FontID=1|IsHidden=T|Text=10%|Name=Tolerance
|RECORD=41|OwnerIndex=1578|IndexInSheet=9|OwnerPartId=-1|Location.X=1174|Location.Y=357|Color=8388608|FontID=1|IsHidden=T|Text=Surface Mount|Name=Mount
|RECORD=41|OwnerIndex=1578|IndexInSheet=10|OwnerPartId=-1|Location.X=1174|Location.Y=357|Color=8388608|FontID=1|IsHidden=T|Text=16V|Name=Voltage Rating
|RECORD=41|OwnerIndex=1578|IndexInSheet=11|OwnerPartId=-1|Location.X=1174|Location.Y=357|Color=8388608|FontID=1|IsHidden=T|Text=0.022inch|Name=Thickness
|RECORD=41|OwnerIndex=1578|IndexInSheet=12|OwnerPartId=-1|Location.X=1174|Location.Y=357|Color=8388608|FontID=1|IsHidden=T|Text=1|Name=Package Quantity
|RECORD=41|OwnerIndex=1578|IndexInSheet=13|OwnerPartId=-1|Location.X=1174|Location.Y=357|Color=8388608|FontID=1|IsHidden=T|Text=-55°C|Name=Min Operating Temperature
|RECORD=41|OwnerIndex=1578|IndexInSheet=14|OwnerPartId=-1|Location.X=1174|Location.Y=357|Color=8388608|FontID=1|IsHidden=T|Text=M|Name=Series
|RECORD=41|OwnerIndex=1578|IndexInSheet=15|OwnerPartId=-1|Location.X=1174|Location.Y=357|Color=8388608|FontID=1|IsHidden=T|Text=16V|Name=Voltage Rating (DC)
|RECORD=41|OwnerIndex=1578|IndexInSheet=16|OwnerPartId=-1|Location.X=1174|Location.Y=357|Color=8388608|FontID=1|IsHidden=T|Text=SMD/SMT|Name=Termination
|RECORD=41|OwnerIndex=1578|IndexInSheet=17|OwnerPartId=-1|Location.X=1174|Location.Y=357|Color=8388608|FontID=1|IsHidden=T|Text=0402|Name=Case/Package
|RECORD=41|OwnerIndex=1578|IndexInSheet=18|OwnerPartId=-1|Location.X=1174|Location.Y=357|Color=8388608|FontID=1|IsHidden=T|Text=X5R|Name=Dielectric
|RECORD=41|OwnerIndex=1578|IndexInSheet=19|OwnerPartId=-1|Location.X=1174|Location.Y=357|Color=8388608|FontID=1|IsHidden=T|Text=2|Name=Number of Pins
|RECORD=41|OwnerIndex=1578|IndexInSheet=20|OwnerPartId=-1|Location.X=1174|Location.Y=357|Color=8388608|FontID=1|IsHidden=T|Text=0402|Name=Case Code (Imperial)
|RECORD=41|OwnerIndex=1578|IndexInSheet=21|OwnerPartId=-1|Location.X=1174|Location.Y=357|Color=8388608|FontID=1|IsHidden=T|Text=1uF|Name=Capacitance
|RECORD=41|OwnerIndex=1578|IndexInSheet=22|OwnerPartId=-1|Location.X=1174|Location.Y=357|Color=8388608|FontID=1|IsHidden=T|Text=1mm|Name=Length
|RECORD=41|OwnerIndex=1578|IndexInSheet=23|OwnerPartId=-1|Location.X=1174|Location.Y=357|Color=8388608|FontID=1|IsHidden=T|Text=Halogen Free|Name=Halogen Free
|RECORD=41|OwnerIndex=1578|IndexInSheet=24|OwnerPartId=-1|Location.X=1174|Location.Y=357|Color=8388608|FontID=1|IsHidden=T|Text=1005|Name=Case Code (Metric)
|RECORD=41|OwnerIndex=1578|IndexInSheet=25|OwnerPartId=-1|Location.X=1174|Location.Y=357|Color=8388608|FontID=1|IsHidden=T|Text=0.02inch|Name=Width
|RECORD=41|OwnerIndex=1578|IndexInSheet=26|OwnerPartId=-1|Location.X=1174|Location.Y=357|Color=8388608|FontID=1|IsHidden=T|Text=Yes|Name=RoHS Compliant
|RECORD=41|OwnerIndex=1578|IndexInSheet=27|OwnerPartId=-1|Location.X=1174|Location.Y=357|Color=8388608|FontID=1|IsHidden=T|Text=No|Name=Radiation Hardening
|RECORD=41|OwnerIndex=1578|IndexInSheet=28|OwnerPartId=-1|Location.X=1174|Location.Y=357|Color=8388608|FontID=1|IsHidden=T|Text=85°C|Name=Max Operating Temperature
|RECORD=41|OwnerIndex=1578|IndexInSheet=29|OwnerPartId=-1|Location.X=1174|Location.Y=357|Color=8388608|FontID=1|IsHidden=T|Text=0.5mm|Name=Height
|RECORD=41|OwnerIndex=1578|IndexInSheet=30|OwnerPartId=-1|Location.X=1174|Location.Y=357|Color=8388608|FontID=1|IsHidden=T|Text=Flat|Name=Construction
|RECORD=34|OwnerIndex=1578|IndexInSheet=-1|OwnerPartId=-1|Location.X=1170|Location.Y=335|Orientation=1|Color=8388608|FontID=2|Text=C82|Name=Designator|ReadOnlyState=1
|RECORD=41|OwnerIndex=1578|IndexInSheet=-1|OwnerPartId=1|Location.X=1205|Location.Y=320|Orientation=1|Color=8388608|FontID=2|Text=1uF_16V_0402|Name=Comment
|RECORD=44|OwnerIndex=1578
|RECORD=45|OwnerIndex=1614|IndexInSheet=-1|UseComponentLibrary=T|ModelName=FP-0402-L_1_0_0_05-W_0_5-IPC_A|ModelType=PCBLIB|DatafileCount=1|ModelDatafileEntity0=FP-0402-L_1_0_0_05-W_0_5-IPC_A|ModelDatafileKind0=PCBLib|IsCurrent=T|DatalinksLocked=T|DatabaseDatalinksLocked=T
|RECORD=46|OwnerIndex=1615
|RECORD=48|OwnerIndex=1615
|RECORD=45|OwnerIndex=1614|IndexInSheet=-1|UseComponentLibrary=T|ModelName=EMK105BJ105_V-F|ModelType=SIM|IsCurrent=T|DatalinksLocked=T|DatabaseDatalinksLocked=T
|RECORD=46|OwnerIndex=1618
|RECORD=48|OwnerIndex=1618
|RECORD=41|OwnerIndex=1620|IndexInSheet=-1|OwnerPartId=-1|Color=8388608|FontID=1|IsHidden=T|Text=General|Name=Kind
|RECORD=41|OwnerIndex=1620|IndexInSheet=-1|OwnerPartId=-1|Color=8388608|FontID=1|IsHidden=T|Text=Spice Subcircuit|Name=SubKind
|RECORD=41|OwnerIndex=1620|IndexInSheet=-1|OwnerPartId=-1|Color=8388608|FontID=1|IsHidden=T|Name=Spice Prefix
|RECORD=41|OwnerIndex=1620|IndexInSheet=-1|OwnerPartId=-1|Color=8388608|FontID=1|IsHidden=T|Name=Excluded Parts
|RECORD=41|OwnerIndex=1620|IndexInSheet=-1|OwnerPartId=-1|Color=8388608|FontID=1|IsHidden=T|Name=Netlist
|RECORD=41|OwnerIndex=1620|IndexInSheet=-1|OwnerPartId=-1|Color=8388608|FontID=1|IsHidden=T|Text=document_sim_cache\GNEMVTBT\0|Name=SimulationCacheLocation|ReadOnlyState=3
|RECORD=45|OwnerIndex=1614|IndexInSheet=-1|UseComponentLibrary=T|ModelName=FP-0402-L_1_0_0_05-W_0_5-IPC_B|ModelType=PCBLIB|DatafileCount=1|ModelDatafileEntity0=FP-0402-L_1_0_0_05-W_0_5-IPC_B|ModelDatafileKind0=PCBLib|DatalinksLocked=T|DatabaseDatalinksLocked=T
|RECORD=46|OwnerIndex=1627
|RECORD=48|OwnerIndex=1627
|RECORD=45|OwnerIndex=1614|IndexInSheet=-1|UseComponentLibrary=T|ModelName=FP-0402-L_1_0_0_05-W_0_5-IPC_C|ModelType=PCBLIB|DatafileCount=1|ModelDatafileEntity0=FP-0402-L_1_0_0_05-W_0_5-IPC_C|ModelDatafileKind0=PCBLib|DatalinksLocked=T|DatabaseDatalinksLocked=T
|RECORD=46|OwnerIndex=1630
|RECORD=48|OwnerIndex=1630
|RECORD=45|OwnerIndex=1614|IndexInSheet=-1|UseComponentLibrary=T|ModelName=FP-0402-L_1_0_0_05-W_0_5-MFG|ModelType=PCBLIB|DatafileCount=1|ModelDatafileEntity0=FP-0402-L_1_0_0_05-W_0_5-MFG|ModelDatafileKind0=PCBLib|DatalinksLocked=T|DatabaseDatalinksLocked=T
|RECORD=46|OwnerIndex=1633
|RECORD=48|OwnerIndex=1633
|RECORD=1|LibReference=b4654b650e69147ec39a6b967a45e02|ComponentDescription=General Purpose Ceramic Capacitor, 0402, 100nF, 10%, X7R, 15%, 25V|PartCount=2|DisplayModeCount=1|IndexInSheet=99|OwnerPartId=-1|Location.X=1225|Location.Y=355|CurrentPartId=1|LibraryPath=*|SourceLibraryName=Altium Content Vault|TargetFileName=*|AreaColor=11599871|Color=128|PartIDLocked=T|DesignItemId=CMP-2008-02519-2|AllPinCount=2
|RECORD=2|OwnerIndex=1636|OwnerPartId=1|Electrical=4|PinConglomerate=49|PinLength=7|Location.X=1225|Location.Y=348|Name=1|Designator=1|PinPropagationDelay=0.000000E+000
|RECORD=2|OwnerIndex=1636|OwnerPartId=1|Electrical=4|PinConglomerate=51|PinLength=6|Location.X=1225|Location.Y=341|Name=2|Designator=2|PinPropagationDelay=0.000000E+000
|RECORD=13|OwnerIndex=1636|IsNotAccesible=T|IndexInSheet=2|OwnerPartId=1|Location.X=1235|Location.Y=348|Corner.X=1215|Corner.Y=348|LineWidth=1|Color=16711680
|RECORD=13|OwnerIndex=1636|IsNotAccesible=T|IndexInSheet=3|OwnerPartId=1|Location.X=1235|Location.Y=342|Corner.X=1215|Corner.Y=342|LineWidth=1|Color=16711680
|RECORD=13|OwnerIndex=1636|IsNotAccesible=T|IndexInSheet=4|OwnerPartId=1|Location.X=1225|Location.Y=348|Corner.X=1225|Corner.Y=351|LineWidth=1|Color=16711680
|RECORD=13|OwnerIndex=1636|IsNotAccesible=T|IndexInSheet=5|OwnerPartId=1|Location.X=1225|Location.Y=341|Corner.X=1225|Corner.Y=340|LineWidth=1|Color=16711680
|RECORD=41|OwnerIndex=1636|IndexInSheet=6|OwnerPartId=-1|Location.X=1214|Location.Y=357|Color=8388608|FontID=1|IsHidden=T|Text=1|Name=Package Quantity
|RECORD=41|OwnerIndex=1636|IndexInSheet=7|OwnerPartId=-1|Location.X=1214|Location.Y=357|Color=8388608|FontID=1|IsHidden=T|Text=100nF|Name=Capacitance
|RECORD=41|OwnerIndex=1636|IndexInSheet=8|OwnerPartId=-1|Location.X=1214|Location.Y=357|Color=8388608|FontID=1|IsHidden=T|Text=-55°C|Name=Min Operating Temperature
|RECORD=41|OwnerIndex=1636|IndexInSheet=9|OwnerPartId=-1|Location.X=1214|Location.Y=357|Color=8388608|FontID=1|IsHidden=T|Text=25V|Name=Voltage
|RECORD=41|OwnerIndex=1636|IndexInSheet=10|OwnerPartId=-1|Location.X=1214|Location.Y=357|Color=8388608|FontID=1|IsHidden=T|Text=25V|Name=Voltage Rating
|RECORD=41|OwnerIndex=1636|IndexInSheet=11|OwnerPartId=-1|Location.X=1214|Location.Y=357|Color=8388608|FontID=1|IsHidden=T|Text=Flat|Name=Construction
|RECORD=41|OwnerIndex=1636|IndexInSheet=12|OwnerPartId=-1|Location.X=1214|Location.Y=357|Color=8388608|FontID=1|IsHidden=T|Text=125°C|Name=Max Operating Temperature
|RECORD=41|OwnerIndex=1636|IndexInSheet=13|OwnerPartId=-1|Location.X=1214|Location.Y=357|Color=8388608|FontID=1|IsHidden=T|Text=No|Name=Radiation Hardening
|RECORD=41|OwnerIndex=1636|IndexInSheet=14|OwnerPartId=-1|Location.X=1214|Location.Y=357|Color=8388608|FontID=1|IsHidden=T|Text=0.5mm|Name=Depth
|RECORD=41|OwnerIndex=1636|IndexInSheet=15|OwnerPartId=-1|Location.X=1214|Location.Y=357|Color=8388608|FontID=1|IsHidden=T|Text=0.022inch|Name=Thickness
|RECORD=41|OwnerIndex=1636|IndexInSheet=16|OwnerPartId=-1|Location.X=1214|Location.Y=357|Color=8388608|FontID=1|IsHidden=T|Text=25V|Name=Voltage Rating (DC)
|RECORD=41|OwnerIndex=1636|IndexInSheet=17|OwnerPartId=-1|Location.X=1214|Location.Y=357|Color=8388608|FontID=1|IsHidden=T|Text=2|Name=Number of Pins
|RECORD=41|OwnerIndex=1636|IndexInSheet=18|OwnerPartId=-1|Location.X=1214|Location.Y=357|Color=8388608|FontID=1|IsHidden=T|Text=Lead Free|Name=Lead Free
|RECORD=41|OwnerIndex=1636|IndexInSheet=19|OwnerPartId=-1|Location.X=1214|Location.Y=357|Color=8388608|FontID=1|IsHidden=T|Text=-|Name=Series
|RECORD=41|OwnerIndex=1636|IndexInSheet=20|OwnerPartId=-1|Location.X=1214|Location.Y=357|Color=8388608|FontID=1|IsHidden=T|Text=No SVHC|Name=REACH SVHC
|RECORD=41|OwnerIndex=1636|IndexInSheet=21|OwnerPartId=-1|Location.X=1214|Location.Y=357|Color=8388608|FontID=1|IsHidden=T|Text=1mm|Name=Length
|RECORD=41|OwnerIndex=1636|IndexInSheet=22|OwnerPartId=-1|Location.X=1214|Location.Y=357|Color=8388608|FontID=1|IsHidden=T|Text=X7R|Name=Dielectric
|RECORD=41|OwnerIndex=1636|IndexInSheet=23|OwnerPartId=-1|Location.X=1214|Location.Y=357|Color=8388608|FontID=1|IsHidden=T|Text=Yes|Name=RoHS Compliant
|RECORD=41|OwnerIndex=1636|IndexInSheet=24|OwnerPartId=-1|Location.X=1214|Location.Y=357|Color=8388608|FontID=1|IsHidden=T|Text=Surface Mount|Name=Mount
|RECORD=41|OwnerIndex=1636|IndexInSheet=25|OwnerPartId=-1|Location.X=1214|Location.Y=357|Color=8388608|FontID=1|IsHidden=T|Text=Tape and Reel|Name=Packaging
|RECORD=41|OwnerIndex=1636|IndexInSheet=26|OwnerPartId=-1|Location.X=1214|Location.Y=357|Color=8388608|FontID=1|IsHidden=T|Text=0402|Name=Case/Package
|RECORD=41|OwnerIndex=1636|IndexInSheet=27|OwnerPartId=-1|Location.X=1214|Location.Y=357|Color=8388608|FontID=1|IsHidden=T|Text=0402|Name=Case Code (Imperial)
|RECORD=41|OwnerIndex=1636|IndexInSheet=28|OwnerPartId=-1|Location.X=1214|Location.Y=357|Color=8388608|FontID=1|IsHidden=T|Text=SMD/SMT|Name=Termination
|RECORD=41|OwnerIndex=1636|IndexInSheet=29|OwnerPartId=-1|Location.X=1214|Location.Y=357|Color=8388608|FontID=1|IsHidden=T|Text=0.02inch|Name=Width
|RECORD=41|OwnerIndex=1636|IndexInSheet=30|OwnerPartId=-1|Location.X=1214|Location.Y=357|Color=8388608|FontID=1|IsHidden=T|Text=1005|Name=Case Code (Metric)
|RECORD=41|OwnerIndex=1636|IndexInSheet=31|OwnerPartId=-1|Location.X=1214|Location.Y=357|Color=8388608|FontID=1|IsHidden=T|Text=10%|Name=Tolerance
|RECORD=34|OwnerIndex=1636|IndexInSheet=-1|OwnerPartId=-1|Location.X=1215|Location.Y=335|Orientation=1|Color=8388608|FontID=2|Text=C83|Name=Designator|ReadOnlyState=1
|RECORD=41|OwnerIndex=1636|IndexInSheet=-1|OwnerPartId=1|Location.X=1245|Location.Y=320|Orientation=1|Color=8388608|FontID=2|Text=0.1uF_25V_0402|Name=Comment
|RECORD=44|OwnerIndex=1636
|RECORD=45|OwnerIndex=1673|IndexInSheet=-1|UseComponentLibrary=T|ModelName=FP-0402-L_1_0_1-W_0_5_0_1-IPC_C|ModelType=PCBLIB|DatafileCount=1|ModelDatafileEntity0=FP-0402-L_1_0_1-W_0_5_0_1-IPC_C|ModelDatafileKind0=PCBLib|IsCurrent=T|DatalinksLocked=T|DatabaseDatalinksLocked=T
|RECORD=46|OwnerIndex=1674
|RECORD=48|OwnerIndex=1674
|RECORD=45|OwnerIndex=1673|IndexInSheet=-1|UseComponentLibrary=T|ModelName=FP-0402-L_1_0_1-W_0_5_0_1-IPC_B|ModelType=PCBLIB|DatafileCount=1|ModelDatafileEntity0=FP-0402-L_1_0_1-W_0_5_0_1-IPC_B|ModelDatafileKind0=PCBLib|DatalinksLocked=T|DatabaseDatalinksLocked=T
|RECORD=46|OwnerIndex=1677
|RECORD=48|OwnerIndex=1677
|RECORD=45|OwnerIndex=1673|IndexInSheet=-1|UseComponentLibrary=T|ModelName=FP-0402-L_1_0_1-W_0_5_0_1-MFG|ModelType=PCBLIB|DatafileCount=1|ModelDatafileEntity0=FP-0402-L_1_0_1-W_0_5_0_1-MFG|ModelDatafileKind0=PCBLib|DatalinksLocked=T|DatabaseDatalinksLocked=T
|RECORD=46|OwnerIndex=1680
|RECORD=48|OwnerIndex=1680
|RECORD=45|OwnerIndex=1673|IndexInSheet=-1|UseComponentLibrary=T|ModelName=FP-0402-L_1_0_1-W_0_5_0_1-IPC_A|ModelType=PCBLIB|DatafileCount=1|ModelDatafileEntity0=FP-0402-L_1_0_1-W_0_5_0_1-IPC_A|ModelDatafileKind0=PCBLib|DatalinksLocked=T|DatabaseDatalinksLocked=T
|RECORD=46|OwnerIndex=1683
|RECORD=48|OwnerIndex=1683
|RECORD=1|LibReference=11868f565c42a9108669ba33697ecf6|ComponentDescription=Multilayer Ceramic Capacitors 47uF ±20% 16V X5R SMD 1206|PartCount=2|DisplayModeCount=1|IndexInSheet=100|OwnerPartId=-1|Location.X=1055|Location.Y=355|CurrentPartId=1|LibraryPath=*|SourceLibraryName=Altium Content Vault|TargetFileName=*|AreaColor=11599871|Color=128|PartIDLocked=T|DesignItemId=CMP-2000-07442-2|AllPinCount=2
|RECORD=2|OwnerIndex=1686|OwnerPartId=1|Electrical=4|PinConglomerate=49|PinLength=7|Location.X=1055|Location.Y=348|Name=1|Designator=1|PinPropagationDelay=0.000000E+000
|RECORD=2|OwnerIndex=1686|OwnerPartId=1|Electrical=4|PinConglomerate=51|PinLength=6|Location.X=1055|Location.Y=341|Name=2|Designator=2|PinPropagationDelay=0.000000E+000
|RECORD=13|OwnerIndex=1686|IsNotAccesible=T|IndexInSheet=2|OwnerPartId=1|Location.X=1065|Location.Y=348|Corner.X=1045|Corner.Y=348|LineWidth=1|Color=16711680
|RECORD=13|OwnerIndex=1686|IsNotAccesible=T|IndexInSheet=3|OwnerPartId=1|Location.X=1065|Location.Y=342|Corner.X=1045|Corner.Y=342|LineWidth=1|Color=16711680
|RECORD=13|OwnerIndex=1686|IsNotAccesible=T|IndexInSheet=4|OwnerPartId=1|Location.X=1055|Location.Y=348|Corner.X=1055|Corner.Y=351|LineWidth=1|Color=16711680
|RECORD=13|OwnerIndex=1686|IsNotAccesible=T|IndexInSheet=5|OwnerPartId=1|Location.X=1055|Location.Y=341|Corner.X=1055|Corner.Y=340|LineWidth=1|Color=16711680
|RECORD=41|OwnerIndex=1686|IndexInSheet=6|OwnerPartId=-1|Location.X=1044|Location.Y=357|Color=8388608|FontID=1|IsHidden=T|Text=Ceramic|Name=Resistor Type
|RECORD=41|OwnerIndex=1686|IndexInSheet=7|OwnerPartId=-1|Location.X=1044|Location.Y=357|Color=8388608|FontID=1|IsHidden=T|Text=0.063inch|Name=Width
|RECORD=41|OwnerIndex=1686|IndexInSheet=8|OwnerPartId=-1|Location.X=1044|Location.Y=357|Color=8388608|FontID=1|IsHidden=T|Text=1206|Name=Case Code (Imperial)
|RECORD=41|OwnerIndex=1686|IndexInSheet=9|OwnerPartId=-1|Location.X=1044|Location.Y=357|Color=8388608|FontID=1|IsHidden=T|Text=No|Name=Radiation Hardening
|RECORD=41|OwnerIndex=1686|IndexInSheet=10|OwnerPartId=-1|Location.X=1044|Location.Y=357|Color=8388608|FontID=1|IsHidden=T|Text=0.071inch|Name=Thickness
|RECORD=41|OwnerIndex=1686|IndexInSheet=11|OwnerPartId=-1|Location.X=1044|Location.Y=357|Color=8388608|FontID=1|IsHidden=T|Text=X5R|Name=Dielectric
|RECORD=41|OwnerIndex=1686|IndexInSheet=12|OwnerPartId=-1|Location.X=1044|Location.Y=357|Color=8388608|FontID=1|IsHidden=T|Text=0.000571oz|Name=Weight
|RECORD=41|OwnerIndex=1686|IndexInSheet=13|OwnerPartId=-1|Location.X=1044|Location.Y=357|Color=8388608|FontID=1|IsHidden=T|Text=SMD/SMT|Name=Termination
|RECORD=41|OwnerIndex=1686|IndexInSheet=14|OwnerPartId=-1|Location.X=1044|Location.Y=357|Color=8388608|FontID=1|IsHidden=T|Text=Ceramic|Name=Dielectric Material
|RECORD=41|OwnerIndex=1686|IndexInSheet=15|OwnerPartId=-1|Location.X=1044|Location.Y=357|Color=8388608|FontID=1|IsHidden=T|Text=-55°C|Name=Min Operating Temperature
|RECORD=41|OwnerIndex=1686|IndexInSheet=16|OwnerPartId=-1|Location.X=1044|Location.Y=357|Color=8388608|FontID=1|IsHidden=T|Text=1.6mm|Name=Depth
|RECORD=41|OwnerIndex=1686|IndexInSheet=17|OwnerPartId=-1|Location.X=1044|Location.Y=357|Color=8388608|FontID=1|IsHidden=T|Text=3216|Name=Case Code (Metric)
|RECORD=41|OwnerIndex=1686|IndexInSheet=18|OwnerPartId=-1|Location.X=1044|Location.Y=357|Color=8388608|FontID=1|IsHidden=T|Text=85°C|Name=Max Operating Temperature
|RECORD=41|OwnerIndex=1686|IndexInSheet=19|OwnerPartId=-1|Location.X=1044|Location.Y=357|Color=8388608|FontID=1|IsHidden=T|Text=Yes|Name=RoHS Compliant
|RECORD=41|OwnerIndex=1686|IndexInSheet=20|OwnerPartId=-1|Location.X=1044|Location.Y=357|Color=8388608|FontID=1|IsHidden=T|Text=No SVHC|Name=REACH SVHC
|RECORD=41|OwnerIndex=1686|IndexInSheet=21|OwnerPartId=-1|Location.X=1044|Location.Y=357|Color=8388608|FontID=1|IsHidden=T|Text=Surface Mount|Name=Mount
|RECORD=41|OwnerIndex=1686|IndexInSheet=22|OwnerPartId=-1|Location.X=1044|Location.Y=357|Color=8388608|FontID=1|IsHidden=T|Text=Lead Free|Name=Lead Free
|RECORD=41|OwnerIndex=1686|IndexInSheet=23|OwnerPartId=-1|Location.X=1044|Location.Y=357|Color=8388608|FontID=1|IsHidden=T|Text=1.6mm|Name=Height
|RECORD=41|OwnerIndex=1686|IndexInSheet=24|OwnerPartId=-1|Location.X=1044|Location.Y=357|Color=8388608|FontID=1|IsHidden=T|Text=3.2mm|Name=Length
|RECORD=41|OwnerIndex=1686|IndexInSheet=25|OwnerPartId=-1|Location.X=1044|Location.Y=357|Color=8388608|FontID=1|IsHidden=T|Text=20%|Name=Tolerance
|RECORD=41|OwnerIndex=1686|IndexInSheet=26|OwnerPartId=-1|Location.X=1044|Location.Y=357|Color=8388608|FontID=1|IsHidden=T|Text=16V|Name=Voltage Rating (DC)
|RECORD=41|OwnerIndex=1686|IndexInSheet=27|OwnerPartId=-1|Location.X=1044|Location.Y=357|Color=8388608|FontID=1|IsHidden=T|Text=47uF|Name=Capacitance
|RECORD=41|OwnerIndex=1686|IndexInSheet=28|OwnerPartId=-1|Location.X=1044|Location.Y=357|Color=8388608|FontID=1|IsHidden=T|Text=1|Name=Package Quantity
|RECORD=41|OwnerIndex=1686|IndexInSheet=29|OwnerPartId=-1|Location.X=1044|Location.Y=357|Color=8388608|FontID=1|IsHidden=T|Text=Flat|Name=Construction
|RECORD=41|OwnerIndex=1686|IndexInSheet=30|OwnerPartId=-1|Location.X=1044|Location.Y=357|Color=8388608|FontID=1|IsHidden=T|Text=Tape and Reel|Name=Packaging
|RECORD=41|OwnerIndex=1686|IndexInSheet=31|OwnerPartId=-1|Location.X=1044|Location.Y=357|Color=8388608|FontID=1|IsHidden=T|Text=C|Name=Series
|RECORD=41|OwnerIndex=1686|IndexInSheet=32|OwnerPartId=-1|Location.X=1044|Location.Y=357|Color=8388608|FontID=1|IsHidden=T|Text=1206|Name=Case/Package
|RECORD=41|OwnerIndex=1686|IndexInSheet=33|OwnerPartId=-1|Location.X=1044|Location.Y=357|Color=8388608|FontID=1|IsHidden=T|Text=16V|Name=Voltage Rating
|RECORD=34|OwnerIndex=1686|IndexInSheet=-1|OwnerPartId=-1|Location.X=1045|Location.Y=340|Orientation=1|Color=8388608|FontID=2|Text=C78|Name=Designator|ReadOnlyState=1
|RECORD=41|OwnerIndex=1686|IndexInSheet=-1|OwnerPartId=1|Location.X=1075|Location.Y=315|Orientation=1|Color=8388608|FontID=2|Text=47uF_16V_1206|Name=Comment
|RECORD=44|OwnerIndex=1686
|RECORD=45|OwnerIndex=1725|IndexInSheet=-1|UseComponentLibrary=T|ModelName=FP-C3216-160-0_2-MFG|ModelType=PCBLIB|DatafileCount=1|ModelDatafileEntity0=FP-C3216-160-0_2-MFG|ModelDatafileKind0=PCBLib|IsCurrent=T|DatalinksLocked=T|DatabaseDatalinksLocked=T
|RECORD=46|OwnerIndex=1726
|RECORD=48|OwnerIndex=1726
|RECORD=45|OwnerIndex=1725|IndexInSheet=-1|UseComponentLibrary=T|ModelName=FP-C3216-160-0_2-IPC_B|ModelType=PCBLIB|DatafileCount=1|ModelDatafileEntity0=FP-C3216-160-0_2-IPC_B|ModelDatafileKind0=PCBLib|DatalinksLocked=T|DatabaseDatalinksLocked=T
|RECORD=46|OwnerIndex=1729
|RECORD=48|OwnerIndex=1729
|RECORD=45|OwnerIndex=1725|IndexInSheet=-1|UseComponentLibrary=T|ModelName=FP-C3216-160-0_2-IPC_C|ModelType=PCBLIB|DatafileCount=1|ModelDatafileEntity0=FP-C3216-160-0_2-IPC_C|ModelDatafileKind0=PCBLib|DatalinksLocked=T|DatabaseDatalinksLocked=T
|RECORD=46|OwnerIndex=1732
|RECORD=48|OwnerIndex=1732
|RECORD=45|OwnerIndex=1725|IndexInSheet=-1|UseComponentLibrary=T|ModelName=FP-C3216-160-0_2-IPC_A|ModelType=PCBLIB|DatafileCount=1|ModelDatafileEntity0=FP-C3216-160-0_2-IPC_A|ModelDatafileKind0=PCBLib|DatalinksLocked=T|DatabaseDatalinksLocked=T
|RECORD=46|OwnerIndex=1735
|RECORD=48|OwnerIndex=1735
|RECORD=17|IndexInSheet=101|OwnerPartId=-1|Style=4|ShowNetName=T|Location.X=960|Location.Y=295|Orientation=3|Color=128|FontID=1|Text=GND
|RECORD=1|LibReference=41cc1aee4cbc9fa2660a15773fa0e79|ComponentDescription=IC MONITOR PWR/CURR BIDIR 8-SOIC|PartCount=2|DisplayModeCount=1|IndexInSheet=102|OwnerPartId=-1|Location.X=1380|Location.Y=635|CurrentPartId=1|LibraryPath=*|SourceLibraryName=Altium Content Vault|TargetFileName=*|AreaColor=11599871|Color=128|PartIDLocked=T|DesignItemId=CMP-0704-00005-3|AllPinCount=8
|RECORD=14|OwnerIndex=1739|IsNotAccesible=T|OwnerPartId=1|Location.X=1400|Location.Y=555|Corner.X=1490|Corner.Y=645|LineWidth=1|Color=128|AreaColor=11599871|IsSolid=T
|RECORD=2|OwnerIndex=1739|OwnerPartId=1|PinConglomerate=58|PinLength=20|Location.X=1400|Location.Y=575|Name=VIN+|Designator=8|PinName_PositionConglomerate=16|Name_CustomFontID=1|PinDesignator_PositionConglomerate=16|Designator_CustomFontID=1|PinPropagationDelay=0.000000E+000
|RECORD=2|OwnerIndex=1739|OwnerPartId=1|PinConglomerate=58|PinLength=20|Location.X=1400|Location.Y=565|Name=VIN-|Designator=7|PinName_PositionConglomerate=16|Name_CustomFontID=1|PinDesignator_PositionConglomerate=16|Designator_CustomFontID=1|PinPropagationDelay=0.000000E+000
|RECORD=2|OwnerIndex=1739|OwnerPartId=1|PinConglomerate=56|PinLength=20|Location.X=1490|Location.Y=595|Name=A0|Designator=2|PinName_PositionConglomerate=16|Name_CustomFontID=1|PinDesignator_PositionConglomerate=16|Designator_CustomFontID=1|PinPropagationDelay=0.000000E+000
|RECORD=2|OwnerIndex=1739|OwnerPartId=1|PinConglomerate=56|PinLength=20|Location.X=1490|Location.Y=585|Name=A1|Designator=1|PinName_PositionConglomerate=16|Name_CustomFontID=1|PinDesignator_PositionConglomerate=16|Designator_CustomFontID=1|PinPropagationDelay=0.000000E+000
|RECORD=2|OwnerIndex=1739|OwnerPartId=1|SymBol_InnerEdge=3|Electrical=1|PinConglomerate=56|PinLength=20|Location.X=1490|Location.Y=615|Name=SCL|Designator=4|PinName_PositionConglomerate=16|Name_CustomFontID=1|PinDesignator_PositionConglomerate=16|Designator_CustomFontID=1|PinPropagationDelay=0.000000E+000
|RECORD=2|OwnerIndex=1739|OwnerPartId=1|Electrical=1|PinConglomerate=56|PinLength=20|Location.X=1490|Location.Y=635|Name=SDA|Designator=3|PinName_PositionConglomerate=16|Name_CustomFontID=1|PinDesignator_PositionConglomerate=16|Designator_CustomFontID=1|PinPropagationDelay=0.000000E+000
|RECORD=2|OwnerIndex=1739|OwnerPartId=1|Electrical=7|PinConglomerate=58|PinLength=20|Location.X=1400|Location.Y=635|Name=VS|Designator=5|PinName_PositionConglomerate=16|Name_CustomFontID=1|PinDesignator_PositionConglomerate=16|Designator_CustomFontID=1|PinPropagationDelay=0.000000E+000
|RECORD=2|OwnerIndex=1739|OwnerPartId=1|Electrical=7|PinConglomerate=56|PinLength=20|Location.X=1490|Location.Y=565|Name=GND|Designator=6|PinName_PositionConglomerate=16|Name_CustomFontID=1|PinDesignator_PositionConglomerate=16|Designator_CustomFontID=1|PinPropagationDelay=0.000000E+000
|RECORD=41|OwnerIndex=1739|IndexInSheet=9|OwnerPartId=-1|Location.X=1378|Location.Y=645|Color=8388608|FontID=1|IsHidden=T|Text=3V|Name=Min Supply Voltage
|RECORD=41|OwnerIndex=1739|IndexInSheet=10|OwnerPartId=-1|Location.X=1378|Location.Y=645|Color=8388608|FontID=1|IsHidden=T|Text=100dB|Name=Common Mode Rejection Ratio
|RECORD=41|OwnerIndex=1739|IndexInSheet=11|OwnerPartId=-1|Location.X=1378|Location.Y=645|Color=8388608|FontID=1|IsHidden=T|Text=Tape and Reel|Name=Packaging
|RECORD=41|OwnerIndex=1739|IndexInSheet=12|OwnerPartId=-1|Location.X=1378|Location.Y=645|Color=8388608|FontID=1|IsHidden=T|Text=No SVHC|Name=REACH SVHC
|RECORD=41|OwnerIndex=1739|IndexInSheet=13|OwnerPartId=-1|Location.X=1378|Location.Y=645|Color=8388608|FontID=1|IsHidden=T|Text=125°C|Name=Max Operating Temperature
|RECORD=41|OwnerIndex=1739|IndexInSheet=14|OwnerPartId=-1|Location.X=1378|Location.Y=645|Color=8388608|FontID=1|IsHidden=T|Text=8|Name=Number of Pins
|RECORD=41|OwnerIndex=1739|IndexInSheet=15|OwnerPartId=-1|Location.X=1378|Location.Y=645|Color=8388608|FontID=1|IsHidden=T|Text=10mA|Name=Output Current
|RECORD=41|OwnerIndex=1739|IndexInSheet=16|OwnerPartId=-1|Location.X=1378|Location.Y=645|Color=8388608|FontID=1|IsHidden=T|Text=Lead Free|Name=Lead Free
|RECORD=41|OwnerIndex=1739|IndexInSheet=17|OwnerPartId=-1|Location.X=1378|Location.Y=645|Color=8388608|FontID=1|IsHidden=T|Text=1|Name=Package Quantity
|RECORD=41|OwnerIndex=1739|IndexInSheet=18|OwnerPartId=-1|Location.X=1378|Location.Y=645|Color=8388608|FontID=1|IsHidden=T|Text=No|Name=Radiation Hardening
|RECORD=41|OwnerIndex=1739|IndexInSheet=19|OwnerPartId=-1|Location.X=1378|Location.Y=645|Color=8388608|FontID=1|IsHidden=T|Text=SOIC|Name=Case/Package
|RECORD=41|OwnerIndex=1739|IndexInSheet=20|OwnerPartId=-1|Location.X=1378|Location.Y=645|Color=8388608|FontID=1|IsHidden=T|Text=1|Name=Number of Amplifiers
|RECORD=41|OwnerIndex=1739|IndexInSheet=21|OwnerPartId=-1|Location.X=1378|Location.Y=645|Color=8388608|FontID=1|IsHidden=T|Text=-40°C|Name=Min Operating Temperature
|RECORD=41|OwnerIndex=1739|IndexInSheet=22|OwnerPartId=-1|Location.X=1378|Location.Y=645|Color=8388608|FontID=1|IsHidden=T|Text=0.5%|Name=Accuracy
|RECORD=41|OwnerIndex=1739|IndexInSheet=23|OwnerPartId=-1|Location.X=1378|Location.Y=645|Color=8388608|FontID=1|IsHidden=T|Text=1mA|Name=Supply Current
|RECORD=41|OwnerIndex=1739|IndexInSheet=24|OwnerPartId=-1|Location.X=1378|Location.Y=645|Color=8388608|FontID=1|IsHidden=T|Text=Gold|Name=Contact Plating
|RECORD=41|OwnerIndex=1739|IndexInSheet=25|OwnerPartId=-1|Location.X=1378|Location.Y=645|Color=8388608|FontID=1|IsHidden=T|Text=700uA|Name=Quiescent Current
|RECORD=41|OwnerIndex=1739|IndexInSheet=26|OwnerPartId=-1|Location.X=1378|Location.Y=645|Color=8388608|FontID=1|IsHidden=T|Text=Zero-Drift|Name=Series
|RECORD=41|OwnerIndex=1739|IndexInSheet=27|OwnerPartId=-1|Location.X=1378|Location.Y=645|Color=8388608|FontID=1|IsHidden=T|Text=1mA|Name=Nominal Supply Current
|RECORD=41|OwnerIndex=1739|IndexInSheet=28|OwnerPartId=-1|Location.X=1378|Location.Y=645|Color=8388608|FontID=1|IsHidden=T|Text=11kHz|Name=Bandwidth
|RECORD=41|OwnerIndex=1739|IndexInSheet=29|OwnerPartId=-1|Location.X=1378|Location.Y=645|Color=8388608|FontID=1|IsHidden=T|Text=40uV|Name=Input Offset Voltage (Vos)
|RECORD=41|OwnerIndex=1739|IndexInSheet=30|OwnerPartId=-1|Location.X=1378|Location.Y=645|Color=8388608|FontID=1|IsHidden=T|Text=5.5V|Name=Max Supply Voltage
|RECORD=41|OwnerIndex=1739|IndexInSheet=31|OwnerPartId=-1|Location.X=1378|Location.Y=645|Color=8388608|FontID=1|IsHidden=T|Text=Yes|Name=RoHS Compliant
|RECORD=34|OwnerIndex=1739|IndexInSheet=-1|OwnerPartId=-1|Location.X=1400|Location.Y=645|Color=8388608|FontID=1|Text=U19|Name=Designator|ReadOnlyState=1
|RECORD=41|OwnerIndex=1739|IndexInSheet=-1|OwnerPartId=1|Location.X=1400|Location.Y=545|Color=8388608|FontID=1|Text=INA219BIDR|Name=Comment
|RECORD=44|OwnerIndex=1739
|RECORD=45|OwnerIndex=1782|IndexInSheet=-1|UseComponentLibrary=T|ModelName=FP-D0008A-MFG|ModelType=PCBLIB|DatafileCount=1|ModelDatafileEntity0=FP-D0008A-MFG|ModelDatafileKind0=PCBLib|IsCurrent=T|DatalinksLocked=T|DatabaseDatalinksLocked=T
|RECORD=46|OwnerIndex=1783
|RECORD=48|OwnerIndex=1783
|RECORD=45|OwnerIndex=1782|IndexInSheet=-1|UseComponentLibrary=T|ModelName=FP-D0008A-IPC_A|ModelType=PCBLIB|DatafileCount=1|ModelDatafileEntity0=FP-D0008A-IPC_A|ModelDatafileKind0=PCBLib|DatalinksLocked=T|DatabaseDatalinksLocked=T
|RECORD=46|OwnerIndex=1786
|RECORD=48|OwnerIndex=1786
|RECORD=45|OwnerIndex=1782|IndexInSheet=-1|UseComponentLibrary=T|ModelName=FP-D0008A-IPC_C|ModelType=PCBLIB|DatafileCount=1|ModelDatafileEntity0=FP-D0008A-IPC_C|ModelDatafileKind0=PCBLib|DatalinksLocked=T|DatabaseDatalinksLocked=T
|RECORD=46|OwnerIndex=1789
|RECORD=48|OwnerIndex=1789
|RECORD=45|OwnerIndex=1782|IndexInSheet=-1|UseComponentLibrary=T|ModelName=FP-D0008A-IPC_B|ModelType=PCBLIB|DatafileCount=1|ModelDatafileEntity0=FP-D0008A-IPC_B|ModelDatafileKind0=PCBLib|DatalinksLocked=T|DatabaseDatalinksLocked=T
|RECORD=46|OwnerIndex=1792
|RECORD=48|OwnerIndex=1792
|RECORD=1|LibReference=b4654b650e69147ec39a6b967a45e02|ComponentDescription=Multilayer Ceramic Capacitor 10uF 16V X5R 20% SMD 0603 T/R|PartCount=2|DisplayModeCount=1|IndexInSheet=103|OwnerPartId=-1|Location.X=1240|Location.Y=615|CurrentPartId=1|LibraryPath=*|SourceLibraryName=Altium Content Vault|TargetFileName=*|AreaColor=11599871|Color=128|PartIDLocked=T|DesignItemId=CMP-2000-06226-4|AllPinCount=2
|RECORD=2|OwnerIndex=1795|OwnerPartId=1|Electrical=4|PinConglomerate=49|PinLength=7|Location.X=1240|Location.Y=608|Name=1|Designator=1|PinPropagationDelay=0.000000E+000
|RECORD=2|OwnerIndex=1795|OwnerPartId=1|Electrical=4|PinConglomerate=51|PinLength=6|Location.X=1240|Location.Y=601|Name=2|Designator=2|PinPropagationDelay=0.000000E+000
|RECORD=13|OwnerIndex=1795|IsNotAccesible=T|IndexInSheet=2|OwnerPartId=1|Location.X=1250|Location.Y=608|Corner.X=1230|Corner.Y=608|LineWidth=1|Color=16711680
|RECORD=13|OwnerIndex=1795|IsNotAccesible=T|IndexInSheet=3|OwnerPartId=1|Location.X=1250|Location.Y=602|Corner.X=1230|Corner.Y=602|LineWidth=1|Color=16711680
|RECORD=13|OwnerIndex=1795|IsNotAccesible=T|IndexInSheet=4|OwnerPartId=1|Location.X=1240|Location.Y=608|Corner.X=1240|Corner.Y=611|LineWidth=1|Color=16711680
|RECORD=13|OwnerIndex=1795|IsNotAccesible=T|IndexInSheet=5|OwnerPartId=1|Location.X=1240|Location.Y=601|Corner.X=1240|Corner.Y=600|LineWidth=1|Color=16711680
|RECORD=41|OwnerIndex=1795|IndexInSheet=6|OwnerPartId=-1|Location.X=1229|Location.Y=617|Color=8388608|FontID=1|IsHidden=T|Text=Tape and Reel|Name=Packaging
|RECORD=41|OwnerIndex=1795|IndexInSheet=7|OwnerPartId=-1|Location.X=1229|Location.Y=617|Color=8388608|FontID=1|IsHidden=T|Text=Flat|Name=Construction
|RECORD=41|OwnerIndex=1795|IndexInSheet=8|OwnerPartId=-1|Location.X=1229|Location.Y=617|Color=8388608|FontID=1|IsHidden=T|Text=0.8mm|Name=Height
|RECORD=41|OwnerIndex=1795|IndexInSheet=9|OwnerPartId=-1|Location.X=1229|Location.Y=617|Color=8388608|FontID=1|IsHidden=T|Text=85°C|Name=Max Operating Temperature
|RECORD=41|OwnerIndex=1795|IndexInSheet=10|OwnerPartId=-1|Location.X=1229|Location.Y=617|Color=8388608|FontID=1|IsHidden=T|Text=X5R|Name=Dielectric
|RECORD=41|OwnerIndex=1795|IndexInSheet=11|OwnerPartId=-1|Location.X=1229|Location.Y=617|Color=8388608|FontID=1|IsHidden=T|Text=1608|Name=Case Code (Metric)
|RECORD=41|OwnerIndex=1795|IndexInSheet=12|OwnerPartId=-1|Location.X=1229|Location.Y=617|Color=8388608|FontID=1|IsHidden=T|Text=16V|Name=Voltage Rating (DC)
|RECORD=41|OwnerIndex=1795|IndexInSheet=13|OwnerPartId=-1|Location.X=1229|Location.Y=617|Color=8388608|FontID=1|IsHidden=T|Text=0.031inch|Name=Width
|RECORD=41|OwnerIndex=1795|IndexInSheet=14|OwnerPartId=-1|Location.X=1229|Location.Y=617|Color=8388608|FontID=1|IsHidden=T|Text=16V|Name=Voltage Rating
|RECORD=41|OwnerIndex=1795|IndexInSheet=15|OwnerPartId=-1|Location.X=1229|Location.Y=617|Color=8388608|FontID=1|IsHidden=T|Text=0.063inch|Name=Length
|RECORD=41|OwnerIndex=1795|IndexInSheet=16|OwnerPartId=-1|Location.X=1229|Location.Y=617|Color=8388608|FontID=1|IsHidden=T|Text=Yes|Name=RoHS Compliant
|RECORD=41|OwnerIndex=1795|IndexInSheet=17|OwnerPartId=-1|Location.X=1229|Location.Y=617|Color=8388608|FontID=1|IsHidden=T|Text=Halogen Free|Name=Halogen Free
|RECORD=41|OwnerIndex=1795|IndexInSheet=18|OwnerPartId=-1|Location.X=1229|Location.Y=617|Color=8388608|FontID=1|IsHidden=T|Text=0603|Name=Case Code (Imperial)
|RECORD=41|OwnerIndex=1795|IndexInSheet=19|OwnerPartId=-1|Location.X=1229|Location.Y=617|Color=8388608|FontID=1|IsHidden=T|Text=10uF|Name=Capacitance
|RECORD=41|OwnerIndex=1795|IndexInSheet=20|OwnerPartId=-1|Location.X=1229|Location.Y=617|Color=8388608|FontID=1|IsHidden=T|Text=Surface Mount|Name=Mount
|RECORD=41|OwnerIndex=1795|IndexInSheet=21|OwnerPartId=-1|Location.X=1229|Location.Y=617|Color=8388608|FontID=1|IsHidden=T|Text=0.031inch|Name=Thickness
|RECORD=41|OwnerIndex=1795|IndexInSheet=22|OwnerPartId=-1|Location.X=1229|Location.Y=617|Color=8388608|FontID=1|IsHidden=T|Text=20%|Name=Tolerance
|RECORD=41|OwnerIndex=1795|IndexInSheet=23|OwnerPartId=-1|Location.X=1229|Location.Y=617|Color=8388608|FontID=1|IsHidden=T|Text=-55°C|Name=Min Operating Temperature
|RECORD=41|OwnerIndex=1795|IndexInSheet=24|OwnerPartId=-1|Location.X=1229|Location.Y=617|Color=8388608|FontID=1|IsHidden=T|Text=M|Name=Series
|RECORD=41|OwnerIndex=1795|IndexInSheet=25|OwnerPartId=-1|Location.X=1229|Location.Y=617|Color=8388608|FontID=1|IsHidden=T|Text=SMD/SMT|Name=Termination
|RECORD=41|OwnerIndex=1795|IndexInSheet=26|OwnerPartId=-1|Location.X=1229|Location.Y=617|Color=8388608|FontID=1|IsHidden=T|Text=0603|Name=Case/Package
|RECORD=41|OwnerIndex=1795|IndexInSheet=27|OwnerPartId=-1|Location.X=1229|Location.Y=617|Color=8388608|FontID=1|IsHidden=T|Text=1|Name=Package Quantity
|RECORD=34|OwnerIndex=1795|IndexInSheet=-1|OwnerPartId=-1|Location.X=1230|Location.Y=595|Orientation=1|Color=8388608|FontID=2|Text=C85|Name=Designator|ReadOnlyState=1
|RECORD=41|OwnerIndex=1795|IndexInSheet=-1|OwnerPartId=1|Location.X=1260|Location.Y=580|Orientation=1|Color=8388608|FontID=2|Text=10uF_16V_0603|Name=Comment
|RECORD=44|OwnerIndex=1795
|RECORD=45|OwnerIndex=1828|IndexInSheet=-1|UseComponentLibrary=T|ModelName=FP-0603-L_1_6_0_2-W_0_8_0-MFG|ModelType=PCBLIB|DatafileCount=1|ModelDatafileEntity0=FP-0603-L_1_6_0_2-W_0_8_0-MFG|ModelDatafileKind0=PCBLib|IsCurrent=T|DatalinksLocked=T|DatabaseDatalinksLocked=T
|RECORD=46|OwnerIndex=1829
|RECORD=48|OwnerIndex=1829
|RECORD=45|OwnerIndex=1828|IndexInSheet=-1|UseComponentLibrary=T|ModelName=FP-0603-L_1_6_0_2-W_0_8_0-IPC_B|ModelType=PCBLIB|DatafileCount=1|ModelDatafileEntity0=FP-0603-L_1_6_0_2-W_0_8_0-IPC_B|ModelDatafileKind0=PCBLib|DatalinksLocked=T|DatabaseDatalinksLocked=T
|RECORD=46|OwnerIndex=1832
|RECORD=48|OwnerIndex=1832
|RECORD=45|OwnerIndex=1828|IndexInSheet=-1|UseComponentLibrary=T|ModelName=FP-0603-L_1_6_0_2-W_0_8_0-IPC_C|ModelType=PCBLIB|DatafileCount=1|ModelDatafileEntity0=FP-0603-L_1_6_0_2-W_0_8_0-IPC_C|ModelDatafileKind0=PCBLib|DatalinksLocked=T|DatabaseDatalinksLocked=T
|RECORD=46|OwnerIndex=1835
|RECORD=48|OwnerIndex=1835
|RECORD=45|OwnerIndex=1828|IndexInSheet=-1|UseComponentLibrary=T|ModelName=FP-0603-L_1_6_0_2-W_0_8_0-IPC_A|ModelType=PCBLIB|DatafileCount=1|ModelDatafileEntity0=FP-0603-L_1_6_0_2-W_0_8_0-IPC_A|ModelDatafileKind0=PCBLib|DatalinksLocked=T|DatabaseDatalinksLocked=T
|RECORD=46|OwnerIndex=1838
|RECORD=48|OwnerIndex=1838
|RECORD=17|IndexInSheet=104|OwnerPartId=-1|ShowNetName=T|Location.X=1240|Location.Y=660|Orientation=1|Color=128|FontID=1|Text=+3.3V
|RECORD=17|IndexInSheet=105|OwnerPartId=-1|Style=4|ShowNetName=T|Location.X=1240|Location.Y=585|Orientation=3|Color=128|FontID=1|Text=GND
|RECORD=17|IndexInSheet=106|OwnerPartId=-1|Style=4|ShowNetName=T|Location.X=1280|Location.Y=585|Orientation=3|Color=128|FontID=1|Text=GND
|RECORD=17|IndexInSheet=107|OwnerPartId=-1|ShowNetName=T|Location.X=1360|Location.Y=600|Orientation=1|Color=128|FontID=1|Text=P3V3_SENSE
|RECORD=17|IndexInSheet=108|OwnerPartId=-1|Style=4|ShowNetName=T|Location.X=1520|Location.Y=560|Orientation=3|Color=128|FontID=1|Text=GND
|RECORD=17|IndexInSheet=109|OwnerPartId=-1|ShowNetName=T|Location.X=1555|Location.Y=615|Color=255|FontID=1|Text=SENS_I2C_SCL|IsCrossSheetConnector=T
|RECORD=17|IndexInSheet=110|OwnerPartId=-1|ShowNetName=T|Location.X=1555|Location.Y=635|Color=255|FontID=1|Text=SENS_I2C_SDA|IsCrossSheetConnector=T
|RECORD=1|LibReference=RES-2|ComponentDescription=Chip Resistor, 0 Ohm, 0.1 W, -55 to 155 degC, 0402 (1005 Metric), RoHS, Tape and Reel|PartCount=2|DisplayModeCount=1|IndexInSheet=111|OwnerPartId=-1|Location.X=1540|Location.Y=595|CurrentPartId=1|LibraryPath=*|SourceLibraryName=Altium Content Vault|TargetFileName=*|AreaColor=11599871|Color=128|PartIDLocked=T|DesignItemId=CMP-2000-07451-1|AllPinCount=2
|RECORD=2|OwnerIndex=1848|OwnerPartId=1|FormalType=1|Electrical=4|PinConglomerate=32|PinLength=10|Location.X=1560|Location.Y=595|Name=2|Designator=2|PinPropagationDelay=0.000000E+000
|RECORD=2|OwnerIndex=1848|OwnerPartId=1|FormalType=1|Electrical=4|PinConglomerate=34|PinLength=10|Location.X=1540|Location.Y=595|Name=1|Designator=1|PinPropagationDelay=0.000000E+000
|RECORD=6|OwnerIndex=1848|IsNotAccesible=T|IndexInSheet=2|OwnerPartId=1|LineWidth=1|Color=16711680|LocationCount=10|X1=1560|Y1=595|X2=1556|Y2=595|X3=1555|Y3=593|X4=1553|Y4=597|X5=1551|Y5=593|X6=1549|Y6=597|X7=1547|Y7=593|X8=1545|Y8=597|X9=1544|Y9=595|X10=1540|Y10=595
|RECORD=41|OwnerIndex=1848|IndexInSheet=3|OwnerPartId=-1|Location.X=1528|Location.Y=610|Color=8388608|FontID=1|IsHidden=T|Text=50V|Name=Voltage Rating (DC)
|RECORD=41|OwnerIndex=1848|IndexInSheet=4|OwnerPartId=-1|Location.X=1528|Location.Y=610|Color=8388608|FontID=1|IsHidden=T|Text=2|Name=Number of Terminations
|RECORD=41|OwnerIndex=1848|IndexInSheet=5|OwnerPartId=-1|Location.X=1528|Location.Y=610|Color=8388608|FontID=1|IsHidden=T|Text=SurfaceMount|Name=Mount
|RECORD=41|OwnerIndex=1848|IndexInSheet=6|OwnerPartId=-1|Location.X=1528|Location.Y=610|Color=8388608|FontID=1|IsHidden=T|Text=0.35mm|Name=Height
|RECORD=41|OwnerIndex=1848|IndexInSheet=7|OwnerPartId=-1|Location.X=1528|Location.Y=610|Color=8388608|FontID=1|IsHidden=T|Text=TapeandReel|Name=Packaging
|RECORD=41|OwnerIndex=1848|IndexInSheet=8|OwnerPartId=-1|Location.X=1528|Location.Y=610|Color=8388608|FontID=1|IsHidden=T|Text=Tin|Name=Contact Plating
|RECORD=41|OwnerIndex=1848|IndexInSheet=9|OwnerPartId=-1|Location.X=1528|Location.Y=610|Color=8388608|FontID=3|IsHidden=T|Text=http://www.panasonic.com/|Name=Manufacturer URL
|RECORD=41|OwnerIndex=1848|IndexInSheet=10|OwnerPartId=-1|Location.X=1528|Location.Y=610|Color=8388608|FontID=1|IsHidden=T|Text=ThickFilm|Name=Composition
|RECORD=41|OwnerIndex=1848|IndexInSheet=11|OwnerPartId=-1|Location.X=1528|Location.Y=610|Color=8388608|FontID=1|IsHidden=T|Text=155degC|Name=Max Operating Temperature
|RECORD=41|OwnerIndex=1848|IndexInSheet=12|OwnerPartId=-1|Location.X=1528|Location.Y=610|Color=8388608|FontID=1|IsHidden=T|Text=600ppm/??C|Name=Temperature Coefficient
|RECORD=41|OwnerIndex=1848|IndexInSheet=13|OwnerPartId=-1|Location.X=1528|Location.Y=610|Color=8388608|FontID=1|IsHidden=T|Text=NoSVHC|Name=REACH SVHC
|RECORD=41|OwnerIndex=1848|IndexInSheet=14|OwnerPartId=-1|Location.X=1528|Location.Y=610|Color=8388608|FontID=1|IsHidden=T|Text=0402|Name=Case/Package
|RECORD=41|OwnerIndex=1848|IndexInSheet=15|OwnerPartId=-1|Location.X=1528|Location.Y=610|Color=8388608|FontID=1|IsHidden=T|Text=100mW|Name=Max Power Dissipation
|RECORD=41|OwnerIndex=1848|IndexInSheet=16|OwnerPartId=-1|Location.X=1528|Location.Y=610|Color=8388608|FontID=1|IsHidden=T|Text=402|Name=Package Reference
|RECORD=41|OwnerIndex=1848|IndexInSheet=17|OwnerPartId=-1|Location.X=1528|Location.Y=610|Color=8388608|FontID=1|IsHidden=T|Text=0.5mm|Name=Depth
|RECORD=41|OwnerIndex=1848|IndexInSheet=18|OwnerPartId=-1|Location.X=1528|Location.Y=610|Color=8388608|FontID=1|IsHidden=T|Text=Panasonic|Name=Manufacturer
|RECORD=41|OwnerIndex=1848|IndexInSheet=19|OwnerPartId=-1|Location.X=1528|Location.Y=610|Color=8388608|FontID=1|IsHidden=T|Text=2-Pin Surface Mount Device, Body 1 x 0.5 mm|Name=Package Description
|RECORD=41|OwnerIndex=1848|IndexInSheet=20|OwnerPartId=-1|Location.X=1528|Location.Y=610|Color=8388608|FontID=3|IsHidden=T|Text=https://industrial.panasonic.com/cdbs/www-data/pdf/RDA0000/AOA0000C301.pdf|Name=Datasheet URL
|RECORD=41|OwnerIndex=1848|IndexInSheet=21|OwnerPartId=-1|Location.X=1528|Location.Y=610|Color=8388608|FontID=1|IsHidden=T|Text=True|Name=RoHSCompliant
|RECORD=41|OwnerIndex=1848|IndexInSheet=22|OwnerPartId=-1|Location.X=1528|Location.Y=610|Color=8388608|FontID=1|IsHidden=T|Text=0402|Name=Case Code (Imperial)
|RECORD=41|OwnerIndex=1848|IndexInSheet=23|OwnerPartId=-1|Location.X=1528|Location.Y=610|Color=8388608|FontID=1|IsHidden=T|Text=0mOhm|Name=Resistance
|RECORD=41|OwnerIndex=1848|IndexInSheet=24|OwnerPartId=-1|Location.X=1528|Location.Y=610|Color=8388608|FontID=1|IsHidden=T|Text=Not|Name=Military Standard
|RECORD=41|OwnerIndex=1848|IndexInSheet=25|OwnerPartId=-1|Location.X=1528|Location.Y=610|Color=8388608|FontID=1|IsHidden=T|Text=5%|Name=Tolerance
|RECORD=41|OwnerIndex=1848|IndexInSheet=26|OwnerPartId=-1|Location.X=1528|Location.Y=610|Color=8388608|FontID=1|IsHidden=T|Text=-55degC|Name=Min Operating Temperature
|RECORD=41|OwnerIndex=1848|IndexInSheet=27|OwnerPartId=-1|Location.X=1528|Location.Y=610|Color=8388608|FontID=1|IsHidden=T|Text=100mW|Name=Power Rating
|RECORD=41|OwnerIndex=1848|IndexInSheet=28|OwnerPartId=-1|Location.X=1528|Location.Y=610|Color=8388608|FontID=1|IsHidden=T|Text=03/2015|Name=Datasheet Version
|RECORD=41|OwnerIndex=1848|IndexInSheet=29|OwnerPartId=-1|Location.X=1528|Location.Y=610|Color=8388608|FontID=1|IsHidden=T|Text=1mm|Name=Length
|RECORD=41|OwnerIndex=1848|IndexInSheet=30|OwnerPartId=-1|Location.X=1528|Location.Y=610|Color=8388608|FontID=1|IsHidden=T|Text=1005|Name=Case Code (Metric)
|RECORD=41|OwnerIndex=1848|IndexInSheet=31|OwnerPartId=-1|Location.X=1528|Location.Y=610|Color=8388608|FontID=1|IsHidden=T|Text=SMD/SMT|Name=Termination
|RECORD=41|OwnerIndex=1848|IndexInSheet=32|OwnerPartId=-1|Location.X=1528|Location.Y=610|Color=8388608|FontID=1|IsHidden=T|Text=SurfaceMount|Name=Mounting Technology
|RECORD=41|OwnerIndex=1848|IndexInSheet=33|OwnerPartId=-1|Location.X=1528|Location.Y=610|Color=8388608|FontID=1|IsHidden=T|Text=50V|Name=Voltage Rating
|RECORD=41|OwnerIndex=1848|IndexInSheet=34|OwnerPartId=-1|Location.X=1528|Location.Y=610|Color=8388608|FontID=1|IsHidden=T|Text=0.02inch|Name=Width
|RECORD=41|OwnerIndex=1848|IndexInSheet=35|OwnerPartId=-1|Location.X=1528|Location.Y=610|Color=8388608|FontID=1|IsHidden=T|Text=1|Name=Package Quantity
|RECORD=41|OwnerIndex=1848|IndexInSheet=36|OwnerPartId=-1|Location.X=1528|Location.Y=610|Color=8388608|FontID=1|IsHidden=T|Text=LeadFree|Name=Lead Free
|RECORD=41|OwnerIndex=1848|IndexInSheet=37|OwnerPartId=-1|Location.X=1528|Location.Y=610|Color=8388608|FontID=1|IsHidden=T|Text=No|Name=Radiation Hardening
|RECORD=34|OwnerIndex=1848|IndexInSheet=-1|OwnerPartId=-1|Location.X=1520|Location.Y=595|Color=8388608|FontID=1|Text=R79|Name=Designator|ReadOnlyState=1
|RECORD=41|OwnerIndex=1848|IndexInSheet=-1|OwnerPartId=-1|Location.X=1560|Location.Y=595|Color=8388608|FontID=1|Text=0_1%_0402|Name=Comment
|RECORD=44|OwnerIndex=1848
|RECORD=45|OwnerIndex=1891|IndexInSheet=-1|Description=Chip Resistor, 2-Leads, Body 1.05x0.55mm, IPC High Density|UseComponentLibrary=T|ModelName=RESC1005X40X25LL05T05|ModelType=PCBLIB|DatafileCount=1|ModelDatafileEntity0=RESC1005X40X25LL05T05|ModelDatafileKind0=PCBLib|IsCurrent=T|DatalinksLocked=T|DatabaseDatalinksLocked=T
|RECORD=46|OwnerIndex=1892
|RECORD=48|OwnerIndex=1892
|RECORD=41|OwnerIndex=1894|IndexInSheet=-1|OwnerPartId=-1|Color=8388608|FontID=1|IsHidden=T|Text=2D|Name=Available Preview Images
|RECORD=45|OwnerIndex=1891|IndexInSheet=-1|Description=Chip Resistor, 2-Leads, Body 1.05x0.55mm, IPC Low Density|UseComponentLibrary=T|ModelName=RESC1005X40X25ML05T05|ModelType=PCBLIB|DatafileCount=1|ModelDatafileEntity0=RESC1005X40X25ML05T05|ModelDatafileKind0=PCBLib|DatalinksLocked=T|DatabaseDatalinksLocked=T
|RECORD=46|OwnerIndex=1896
|RECORD=48|OwnerIndex=1896
|RECORD=41|OwnerIndex=1898|IndexInSheet=-1|OwnerPartId=-1|Color=8388608|FontID=1|IsHidden=T|Text=2D|Name=Available Preview Images
|RECORD=45|OwnerIndex=1891|IndexInSheet=-1|Description=Chip Resistor, 2-Leads, Body 1.05x0.55mm, IPC Medium Density|UseComponentLibrary=T|ModelName=RESC1005X40X25NL05T05|ModelType=PCBLIB|DatafileCount=1|ModelDatafileEntity0=RESC1005X40X25NL05T05|ModelDatafileKind0=PCBLib|DatalinksLocked=T|DatabaseDatalinksLocked=T
|RECORD=46|OwnerIndex=1900
|RECORD=48|OwnerIndex=1900
|RECORD=41|OwnerIndex=1902|IndexInSheet=-1|OwnerPartId=-1|Color=8388608|FontID=1|IsHidden=T|Text=2D|Name=Available Preview Images
|RECORD=1|LibReference=RES-2|ComponentDescription=Chip Resistor, 0 Ohm, 0.1 W, -55 to 155 degC, 0402 (1005 Metric), RoHS, Tape and Reel|PartCount=2|DisplayModeCount=1|IndexInSheet=112|OwnerPartId=-1|Location.X=1540|Location.Y=585|CurrentPartId=1|LibraryPath=*|SourceLibraryName=Altium Content Vault|TargetFileName=*|AreaColor=11599871|Color=128|PartIDLocked=T|DesignItemId=CMP-2000-07451-1|AllPinCount=2
|RECORD=2|OwnerIndex=1904|OwnerPartId=1|FormalType=1|Electrical=4|PinConglomerate=32|PinLength=10|Location.X=1560|Location.Y=585|Name=2|Designator=2|PinPropagationDelay=0.000000E+000
|RECORD=2|OwnerIndex=1904|OwnerPartId=1|FormalType=1|Electrical=4|PinConglomerate=34|PinLength=10|Location.X=1540|Location.Y=585|Name=1|Designator=1|PinPropagationDelay=0.000000E+000
|RECORD=6|OwnerIndex=1904|IsNotAccesible=T|IndexInSheet=2|OwnerPartId=1|LineWidth=1|Color=16711680|LocationCount=10|X1=1560|Y1=585|X2=1556|Y2=585|X3=1555|Y3=583|X4=1553|Y4=587|X5=1551|Y5=583|X6=1549|Y6=587|X7=1547|Y7=583|X8=1545|Y8=587|X9=1544|Y9=585|X10=1540|Y10=585
|RECORD=41|OwnerIndex=1904|IndexInSheet=3|OwnerPartId=-1|Location.X=1528|Location.Y=600|Color=8388608|FontID=1|IsHidden=T|Text=50V|Name=Voltage Rating (DC)
|RECORD=41|OwnerIndex=1904|IndexInSheet=4|OwnerPartId=-1|Location.X=1528|Location.Y=600|Color=8388608|FontID=1|IsHidden=T|Text=2|Name=Number of Terminations
|RECORD=41|OwnerIndex=1904|IndexInSheet=5|OwnerPartId=-1|Location.X=1528|Location.Y=600|Color=8388608|FontID=1|IsHidden=T|Text=SurfaceMount|Name=Mount
|RECORD=41|OwnerIndex=1904|IndexInSheet=6|OwnerPartId=-1|Location.X=1528|Location.Y=600|Color=8388608|FontID=1|IsHidden=T|Text=0.35mm|Name=Height
|RECORD=41|OwnerIndex=1904|IndexInSheet=7|OwnerPartId=-1|Location.X=1528|Location.Y=600|Color=8388608|FontID=1|IsHidden=T|Text=TapeandReel|Name=Packaging
|RECORD=41|OwnerIndex=1904|IndexInSheet=8|OwnerPartId=-1|Location.X=1528|Location.Y=600|Color=8388608|FontID=1|IsHidden=T|Text=Tin|Name=Contact Plating
|RECORD=41|OwnerIndex=1904|IndexInSheet=9|OwnerPartId=-1|Location.X=1528|Location.Y=600|Color=8388608|FontID=3|IsHidden=T|Text=http://www.panasonic.com/|Name=Manufacturer URL
|RECORD=41|OwnerIndex=1904|IndexInSheet=10|OwnerPartId=-1|Location.X=1528|Location.Y=600|Color=8388608|FontID=1|IsHidden=T|Text=ThickFilm|Name=Composition
|RECORD=41|OwnerIndex=1904|IndexInSheet=11|OwnerPartId=-1|Location.X=1528|Location.Y=600|Color=8388608|FontID=1|IsHidden=T|Text=155degC|Name=Max Operating Temperature
|RECORD=41|OwnerIndex=1904|IndexInSheet=12|OwnerPartId=-1|Location.X=1528|Location.Y=600|Color=8388608|FontID=1|IsHidden=T|Text=600ppm/??C|Name=Temperature Coefficient
|RECORD=41|OwnerIndex=1904|IndexInSheet=13|OwnerPartId=-1|Location.X=1528|Location.Y=600|Color=8388608|FontID=1|IsHidden=T|Text=NoSVHC|Name=REACH SVHC
|RECORD=41|OwnerIndex=1904|IndexInSheet=14|OwnerPartId=-1|Location.X=1528|Location.Y=600|Color=8388608|FontID=1|IsHidden=T|Text=0402|Name=Case/Package
|RECORD=41|OwnerIndex=1904|IndexInSheet=15|OwnerPartId=-1|Location.X=1528|Location.Y=600|Color=8388608|FontID=1|IsHidden=T|Text=100mW|Name=Max Power Dissipation
|RECORD=41|OwnerIndex=1904|IndexInSheet=16|OwnerPartId=-1|Location.X=1528|Location.Y=600|Color=8388608|FontID=1|IsHidden=T|Text=402|Name=Package Reference
|RECORD=41|OwnerIndex=1904|IndexInSheet=17|OwnerPartId=-1|Location.X=1528|Location.Y=600|Color=8388608|FontID=1|IsHidden=T|Text=0.5mm|Name=Depth
|RECORD=41|OwnerIndex=1904|IndexInSheet=18|OwnerPartId=-1|Location.X=1528|Location.Y=600|Color=8388608|FontID=1|IsHidden=T|Text=Panasonic|Name=Manufacturer
|RECORD=41|OwnerIndex=1904|IndexInSheet=19|OwnerPartId=-1|Location.X=1528|Location.Y=600|Color=8388608|FontID=1|IsHidden=T|Text=2-Pin Surface Mount Device, Body 1 x 0.5 mm|Name=Package Description
|RECORD=41|OwnerIndex=1904|IndexInSheet=20|OwnerPartId=-1|Location.X=1528|Location.Y=600|Color=8388608|FontID=3|IsHidden=T|Text=https://industrial.panasonic.com/cdbs/www-data/pdf/RDA0000/AOA0000C301.pdf|Name=Datasheet URL
|RECORD=41|OwnerIndex=1904|IndexInSheet=21|OwnerPartId=-1|Location.X=1528|Location.Y=600|Color=8388608|FontID=1|IsHidden=T|Text=True|Name=RoHSCompliant
|RECORD=41|OwnerIndex=1904|IndexInSheet=22|OwnerPartId=-1|Location.X=1528|Location.Y=600|Color=8388608|FontID=1|IsHidden=T|Text=0402|Name=Case Code (Imperial)
|RECORD=41|OwnerIndex=1904|IndexInSheet=23|OwnerPartId=-1|Location.X=1528|Location.Y=600|Color=8388608|FontID=1|IsHidden=T|Text=0mOhm|Name=Resistance
|RECORD=41|OwnerIndex=1904|IndexInSheet=24|OwnerPartId=-1|Location.X=1528|Location.Y=600|Color=8388608|FontID=1|IsHidden=T|Text=Not|Name=Military Standard
|RECORD=41|OwnerIndex=1904|IndexInSheet=25|OwnerPartId=-1|Location.X=1528|Location.Y=600|Color=8388608|FontID=1|IsHidden=T|Text=5%|Name=Tolerance
|RECORD=41|OwnerIndex=1904|IndexInSheet=26|OwnerPartId=-1|Location.X=1528|Location.Y=600|Color=8388608|FontID=1|IsHidden=T|Text=-55degC|Name=Min Operating Temperature
|RECORD=41|OwnerIndex=1904|IndexInSheet=27|OwnerPartId=-1|Location.X=1528|Location.Y=600|Color=8388608|FontID=1|IsHidden=T|Text=100mW|Name=Power Rating
|RECORD=41|OwnerIndex=1904|IndexInSheet=28|OwnerPartId=-1|Location.X=1528|Location.Y=600|Color=8388608|FontID=1|IsHidden=T|Text=03/2015|Name=Datasheet Version
|RECORD=41|OwnerIndex=1904|IndexInSheet=29|OwnerPartId=-1|Location.X=1528|Location.Y=600|Color=8388608|FontID=1|IsHidden=T|Text=1mm|Name=Length
|RECORD=41|OwnerIndex=1904|IndexInSheet=30|OwnerPartId=-1|Location.X=1528|Location.Y=600|Color=8388608|FontID=1|IsHidden=T|Text=1005|Name=Case Code (Metric)
|RECORD=41|OwnerIndex=1904|IndexInSheet=31|OwnerPartId=-1|Location.X=1528|Location.Y=600|Color=8388608|FontID=1|IsHidden=T|Text=SMD/SMT|Name=Termination
|RECORD=41|OwnerIndex=1904|IndexInSheet=32|OwnerPartId=-1|Location.X=1528|Location.Y=600|Color=8388608|FontID=1|IsHidden=T|Text=SurfaceMount|Name=Mounting Technology
|RECORD=41|OwnerIndex=1904|IndexInSheet=33|OwnerPartId=-1|Location.X=1528|Location.Y=600|Color=8388608|FontID=1|IsHidden=T|Text=50V|Name=Voltage Rating
|RECORD=41|OwnerIndex=1904|IndexInSheet=34|OwnerPartId=-1|Location.X=1528|Location.Y=600|Color=8388608|FontID=1|IsHidden=T|Text=0.02inch|Name=Width
|RECORD=41|OwnerIndex=1904|IndexInSheet=35|OwnerPartId=-1|Location.X=1528|Location.Y=600|Color=8388608|FontID=1|IsHidden=T|Text=1|Name=Package Quantity
|RECORD=41|OwnerIndex=1904|IndexInSheet=36|OwnerPartId=-1|Location.X=1528|Location.Y=600|Color=8388608|FontID=1|IsHidden=T|Text=LeadFree|Name=Lead Free
|RECORD=41|OwnerIndex=1904|IndexInSheet=37|OwnerPartId=-1|Location.X=1528|Location.Y=600|Color=8388608|FontID=1|IsHidden=T|Text=No|Name=Radiation Hardening
|RECORD=34|OwnerIndex=1904|IndexInSheet=-1|OwnerPartId=-1|Location.X=1520|Location.Y=585|Color=8388608|FontID=1|Text=R80|Name=Designator|ReadOnlyState=1
|RECORD=41|OwnerIndex=1904|IndexInSheet=-1|OwnerPartId=-1|Location.X=1560|Location.Y=585|Color=8388608|FontID=1|Text=0_1%_0402|Name=Comment
|RECORD=44|OwnerIndex=1904
|RECORD=45|OwnerIndex=1947|IndexInSheet=-1|Description=Chip Resistor, 2-Leads, Body 1.05x0.55mm, IPC High Density|UseComponentLibrary=T|ModelName=RESC1005X40X25LL05T05|ModelType=PCBLIB|DatafileCount=1|ModelDatafileEntity0=RESC1005X40X25LL05T05|ModelDatafileKind0=PCBLib|IsCurrent=T|DatalinksLocked=T|DatabaseDatalinksLocked=T
|RECORD=46|OwnerIndex=1948
|RECORD=48|OwnerIndex=1948
|RECORD=41|OwnerIndex=1950|IndexInSheet=-1|OwnerPartId=-1|Color=8388608|FontID=1|IsHidden=T|Text=2D|Name=Available Preview Images
|RECORD=45|OwnerIndex=1947|IndexInSheet=-1|Description=Chip Resistor, 2-Leads, Body 1.05x0.55mm, IPC Low Density|UseComponentLibrary=T|ModelName=RESC1005X40X25ML05T05|ModelType=PCBLIB|DatafileCount=1|ModelDatafileEntity0=RESC1005X40X25ML05T05|ModelDatafileKind0=PCBLib|DatalinksLocked=T|DatabaseDatalinksLocked=T
|RECORD=46|OwnerIndex=1952
|RECORD=48|OwnerIndex=1952
|RECORD=41|OwnerIndex=1954|IndexInSheet=-1|OwnerPartId=-1|Color=8388608|FontID=1|IsHidden=T|Text=2D|Name=Available Preview Images
|RECORD=45|OwnerIndex=1947|IndexInSheet=-1|Description=Chip Resistor, 2-Leads, Body 1.05x0.55mm, IPC Medium Density|UseComponentLibrary=T|ModelName=RESC1005X40X25NL05T05|ModelType=PCBLIB|DatafileCount=1|ModelDatafileEntity0=RESC1005X40X25NL05T05|ModelDatafileKind0=PCBLib|DatalinksLocked=T|DatabaseDatalinksLocked=T
|RECORD=46|OwnerIndex=1956
|RECORD=48|OwnerIndex=1956
|RECORD=41|OwnerIndex=1958|IndexInSheet=-1|OwnerPartId=-1|Color=8388608|FontID=1|IsHidden=T|Text=2D|Name=Available Preview Images
|RECORD=4|IndexInSheet=113|OwnerPartId=-1|Location.X=1420|Location.Y=665|Color=8388608|FontID=1|Text=Address 0x44
|RECORD=17|IndexInSheet=114|OwnerPartId=-1|ShowNetName=T|Location.X=1620|Location.Y=650|Orientation=1|Color=128|FontID=1|Text=+3.3V
|RECORD=17|IndexInSheet=115|OwnerPartId=-1|ShowNetName=T|Location.X=960|Location.Y=420|Orientation=1|Color=128|FontID=1|Text=+3.3V
|RECORD=17|IndexInSheet=116|OwnerPartId=-1|Style=4|ShowNetName=T|Location.X=200|Location.Y=455|Orientation=3|Color=128|FontID=1|Text=GND
|RECORD=17|IndexInSheet=117|OwnerPartId=-1|ShowNetName=T|Location.X=1325|Location.Y=745|Orientation=1|Color=128|FontID=1|Text=+5.0V
|RECORD=17|IndexInSheet=118|OwnerPartId=-1|ShowNetName=T|Location.X=1430|Location.Y=1005|Orientation=1|Color=128|FontID=1|Text=+5.0V
|RECORD=17|IndexInSheet=119|OwnerPartId=-1|ShowNetName=T|Location.X=200|Location.Y=635|Orientation=1|Color=128|FontID=1|Text=+5.0V
|RECORD=17|IndexInSheet=120|OwnerPartId=-1|ShowNetName=T|Location.X=1320|Location.Y=600|Orientation=1|Color=128|FontID=1|Text=+3.3V
|RECORD=1|LibReference=1029c3af85768c4190bb7ad29bc67b5|ComponentDescription=RES SMD 200 OHM 1% 1/10W 0402|PartCount=2|DisplayModeCount=1|IndexInSheet=121|OwnerPartId=-1|Location.X=85|Location.Y=470|Orientation=1|CurrentPartId=1|LibraryPath=*|SourceLibraryName=Altium Content Vault|TargetFileName=*|AreaColor=11599871|Color=128|PartIDLocked=T|DesignItemId=CMP-2002-00757-2|AllPinCount=2
|RECORD=2|OwnerIndex=1968|OwnerPartId=1|Electrical=4|PinConglomerate=51|PinLength=20|Location.X=85|Location.Y=490|Name=1|Designator=1|PinPropagationDelay=0.000000E+000
|RECORD=2|OwnerIndex=1968|OwnerPartId=1|Electrical=4|PinConglomerate=49|PinLength=20|Location.X=85|Location.Y=520|Name=2|Designator=2|PinPropagationDelay=0.000000E+000
|RECORD=13|OwnerIndex=1968|IsNotAccesible=T|IndexInSheet=2|OwnerPartId=1|Location.X=85|Location.Y=490|Corner.X=80|Corner.Y=493|LineWidth=1|Color=16711680
|RECORD=13|OwnerIndex=1968|IsNotAccesible=T|IndexInSheet=3|OwnerPartId=1|Location.X=80|Location.Y=493|Corner.X=90|Corner.Y=498|LineWidth=1|Color=16711680
|RECORD=13|OwnerIndex=1968|IsNotAccesible=T|IndexInSheet=4|OwnerPartId=1|Location.X=90|Location.Y=498|Corner.X=80|Corner.Y=503|LineWidth=1|Color=16711680
|RECORD=13|OwnerIndex=1968|IsNotAccesible=T|IndexInSheet=5|OwnerPartId=1|Location.X=80|Location.Y=503|Corner.X=90|Corner.Y=508|LineWidth=1|Color=16711680
|RECORD=13|OwnerIndex=1968|IsNotAccesible=T|IndexInSheet=6|OwnerPartId=1|Location.X=90|Location.Y=508|Corner.X=80|Corner.Y=513|LineWidth=1|Color=16711680
|RECORD=13|OwnerIndex=1968|IsNotAccesible=T|IndexInSheet=7|OwnerPartId=1|Location.X=80|Location.Y=513|Corner.X=90|Corner.Y=518|LineWidth=1|Color=16711680
|RECORD=13|OwnerIndex=1968|IsNotAccesible=T|IndexInSheet=8|OwnerPartId=1|Location.X=90|Location.Y=518|Corner.X=85|Corner.Y=520|LineWidth=1|Color=16711680
|RECORD=13|OwnerIndex=1968|IsNotAccesible=T|IndexInSheet=9|OwnerPartId=1|Location.X=85|Location.Y=490|Corner.X=85|Corner.Y=487|LineWidth=1|Color=16711680
|RECORD=13|OwnerIndex=1968|IsNotAccesible=T|IndexInSheet=10|OwnerPartId=1|Location.X=85|Location.Y=520|Corner.X=85|Corner.Y=523|LineWidth=1|Color=16711680
|RECORD=41|OwnerIndex=1968|IndexInSheet=11|OwnerPartId=-1|Location.X=79|Location.Y=542|Color=8388608|FontID=1|IsHidden=T|Text=Yes|Name=RoHS Compliant
|RECORD=41|OwnerIndex=1968|IndexInSheet=12|OwnerPartId=-1|Location.X=79|Location.Y=542|Color=8388608|FontID=1|IsHidden=T|Text=Tape and Reel|Name=Packaging
|RECORD=41|OwnerIndex=1968|IndexInSheet=13|OwnerPartId=-1|Location.X=79|Location.Y=542|Color=8388608|FontID=1|IsHidden=T|Text=1005|Name=Case Code (Metric)
|RECORD=41|OwnerIndex=1968|IndexInSheet=14|OwnerPartId=-1|Location.X=79|Location.Y=542|Color=8388608|FontID=1|IsHidden=T|Text=1|Name=Package Quantity
|RECORD=41|OwnerIndex=1968|IndexInSheet=15|OwnerPartId=-1|Location.X=79|Location.Y=542|Color=8388608|FontID=1|IsHidden=T|Text=Tin|Name=Contact Plating
|RECORD=41|OwnerIndex=1968|IndexInSheet=16|OwnerPartId=-1|Location.X=79|Location.Y=542|Color=8388608|FontID=1|IsHidden=T|Text=100mW|Name=Power Rating
|RECORD=41|OwnerIndex=1968|IndexInSheet=17|OwnerPartId=-1|Location.X=79|Location.Y=542|Color=8388608|FontID=1|IsHidden=T|Text=ERJ|Name=Series
|RECORD=41|OwnerIndex=1968|IndexInSheet=18|OwnerPartId=-1|Location.X=79|Location.Y=542|Color=8388608|FontID=1|IsHidden=T|Text=Surface Mount|Name=Mount
|RECORD=41|OwnerIndex=1968|IndexInSheet=19|OwnerPartId=-1|Location.X=79|Location.Y=542|Color=8388608|FontID=1|IsHidden=T|Text=Lead Free|Name=Lead Free
|RECORD=41|OwnerIndex=1968|IndexInSheet=20|OwnerPartId=-1|Location.X=79|Location.Y=542|Color=8388608|FontID=1|IsHidden=T|Text=-55°C|Name=Min Operating Temperature
|RECORD=41|OwnerIndex=1968|IndexInSheet=21|OwnerPartId=-1|Location.X=79|Location.Y=542|Color=8388608|FontID=1|IsHidden=T|Text=2|Name=Number of Terminations
|RECORD=41|OwnerIndex=1968|IndexInSheet=22|OwnerPartId=-1|Location.X=79|Location.Y=542|Color=8388608|FontID=1|IsHidden=T|Text=50V|Name=Voltage Rating (DC)
|RECORD=41|OwnerIndex=1968|IndexInSheet=23|OwnerPartId=-1|Location.X=79|Location.Y=542|Color=8388608|FontID=1|IsHidden=T|Text=100mW|Name=Max Power Dissipation
|RECORD=41|OwnerIndex=1968|IndexInSheet=24|OwnerPartId=-1|Location.X=79|Location.Y=542|Color=8388608|FontID=1|IsHidden=T|Text=THICK FILM|Name=Technology
|RECORD=41|OwnerIndex=1968|IndexInSheet=25|OwnerPartId=-1|Location.X=79|Location.Y=542|Color=8388608|FontID=1|IsHidden=T|Text=200R|Name=Resistance
|RECORD=41|OwnerIndex=1968|IndexInSheet=26|OwnerPartId=-1|Location.X=79|Location.Y=542|Color=8388608|FontID=1|IsHidden=T|Text=50V|Name=Voltage Rating
|RECORD=41|OwnerIndex=1968|IndexInSheet=27|OwnerPartId=-1|Location.X=79|Location.Y=542|Color=8388608|FontID=1|IsHidden=T|Text=0402|Name=Case/Package
|RECORD=41|OwnerIndex=1968|IndexInSheet=28|OwnerPartId=-1|Location.X=79|Location.Y=542|Color=8388608|FontID=1|IsHidden=T|Text=0.02inch|Name=Width
|RECORD=41|OwnerIndex=1968|IndexInSheet=29|OwnerPartId=-1|Location.X=79|Location.Y=542|Color=8388608|FontID=1|IsHidden=T|Text=SMD/SMT|Name=Termination
|RECORD=41|OwnerIndex=1968|IndexInSheet=30|OwnerPartId=-1|Location.X=79|Location.Y=542|Color=8388608|FontID=1|IsHidden=T|Text=Not|Name=Military Standard
|RECORD=41|OwnerIndex=1968|IndexInSheet=31|OwnerPartId=-1|Location.X=79|Location.Y=542|Color=8388608|FontID=1|IsHidden=T|Text=100ppm/°C|Name=Temperature Coefficient
|RECORD=41|OwnerIndex=1968|IndexInSheet=32|OwnerPartId=-1|Location.X=79|Location.Y=542|Color=8388608|FontID=1|IsHidden=T|Text=0.35mm|Name=Height
|RECORD=41|OwnerIndex=1968|IndexInSheet=33|OwnerPartId=-1|Location.X=79|Location.Y=542|Color=8388608|FontID=1|IsHidden=T|Text=No|Name=Radiation Hardening
|RECORD=41|OwnerIndex=1968|IndexInSheet=34|OwnerPartId=-1|Location.X=79|Location.Y=542|Color=8388608|FontID=1|IsHidden=T|Text=1%|Name=Resistance Tolerance
|RECORD=41|OwnerIndex=1968|IndexInSheet=35|OwnerPartId=-1|Location.X=79|Location.Y=542|Color=8388608|FontID=1|IsHidden=T|Text=1mm|Name=Length
|RECORD=41|OwnerIndex=1968|IndexInSheet=36|OwnerPartId=-1|Location.X=79|Location.Y=542|Color=8388608|FontID=1|IsHidden=T|Text=No SVHC|Name=REACH SVHC
|RECORD=41|OwnerIndex=1968|IndexInSheet=37|OwnerPartId=-1|Location.X=79|Location.Y=542|Color=8388608|FontID=1|IsHidden=T|Text=Rectangular|Name=Construction
|RECORD=41|OwnerIndex=1968|IndexInSheet=38|OwnerPartId=-1|Location.X=79|Location.Y=542|Color=8388608|FontID=1|IsHidden=T|Text=0.5mm|Name=Depth
|RECORD=41|OwnerIndex=1968|IndexInSheet=39|OwnerPartId=-1|Location.X=79|Location.Y=542|Color=8388608|FontID=1|IsHidden=T|Text=Automotive AEC-Q200|Name=Features
|RECORD=41|OwnerIndex=1968|IndexInSheet=40|OwnerPartId=-1|Location.X=79|Location.Y=542|Color=8388608|FontID=1|IsHidden=T|Text=Thick Film|Name=Resistor Type
|RECORD=41|OwnerIndex=1968|IndexInSheet=41|OwnerPartId=-1|Location.X=79|Location.Y=542|Color=8388608|FontID=1|IsHidden=T|Text=0402|Name=Case Code (Imperial)
|RECORD=41|OwnerIndex=1968|IndexInSheet=42|OwnerPartId=-1|Location.X=79|Location.Y=542|Color=8388608|FontID=1|IsHidden=T|Text=1%|Name=Tolerance
|RECORD=41|OwnerIndex=1968|IndexInSheet=43|OwnerPartId=-1|Location.X=79|Location.Y=542|Color=8388608|FontID=1|IsHidden=T|Text=0402|Name=Size Code
|RECORD=41|OwnerIndex=1968|IndexInSheet=44|OwnerPartId=-1|Location.X=79|Location.Y=542|Color=8388608|FontID=1|IsHidden=T|Text=155°C|Name=Max Operating Temperature
|RECORD=34|OwnerIndex=1968|IndexInSheet=-1|OwnerPartId=-1|Location.X=91|Location.Y=514|Color=8388608|FontID=1|Text=R77|Name=Designator|ReadOnlyState=1
|RECORD=41|OwnerIndex=1968|IndexInSheet=-1|OwnerPartId=1|Location.X=91|Location.Y=504|Color=8388608|FontID=1|Text=200_1%_0402|Name=Comment
|RECORD=44|OwnerIndex=1968
|RECORD=45|OwnerIndex=2018|IndexInSheet=-1|UseComponentLibrary=T|ModelName=FP-ERJ2RK-IPC_A|ModelType=PCBLIB|DatafileCount=1|ModelDatafileEntity0=FP-ERJ2RK-IPC_A|ModelDatafileKind0=PCBLib|IsCurrent=T|DatalinksLocked=T|DatabaseDatalinksLocked=T
|RECORD=46|OwnerIndex=2019
|RECORD=48|OwnerIndex=2019
|RECORD=45|OwnerIndex=2018|IndexInSheet=-1|UseComponentLibrary=T|ModelName=FP-ERJ2RK-IPC_C|ModelType=PCBLIB|DatafileCount=1|ModelDatafileEntity0=FP-ERJ2RK-IPC_C|ModelDatafileKind0=PCBLib|DatalinksLocked=T|DatabaseDatalinksLocked=T
|RECORD=46|OwnerIndex=2022
|RECORD=48|OwnerIndex=2022
|RECORD=45|OwnerIndex=2018|IndexInSheet=-1|UseComponentLibrary=T|ModelName=FP-ERJ2RK-MFG|ModelType=PCBLIB|DatafileCount=1|ModelDatafileEntity0=FP-ERJ2RK-MFG|ModelDatafileKind0=PCBLib|DatalinksLocked=T|DatabaseDatalinksLocked=T
|RECORD=46|OwnerIndex=2025
|RECORD=48|OwnerIndex=2025
|RECORD=45|OwnerIndex=2018|IndexInSheet=-1|UseComponentLibrary=T|ModelName=FP-ERJ2RK-IPC_B|ModelType=PCBLIB|DatafileCount=1|ModelDatafileEntity0=FP-ERJ2RK-IPC_B|ModelDatafileKind0=PCBLib|DatalinksLocked=T|DatabaseDatalinksLocked=T
|RECORD=46|OwnerIndex=2028
|RECORD=48|OwnerIndex=2028
|RECORD=1|LibReference=1029c3af85768c4190bb7ad29bc67b5|ComponentDescription=RES SMD 200 OHM 1% 1/10W 0402|PartCount=2|DisplayModeCount=1|IndexInSheet=122|OwnerPartId=-1|Location.X=200|Location.Y=475|Orientation=1|CurrentPartId=1|LibraryPath=*|SourceLibraryName=Altium Content Vault|TargetFileName=*|AreaColor=11599871|Color=128|PartIDLocked=T|DesignItemId=CMP-2002-00757-2|AllPinCount=2
|RECORD=2|OwnerIndex=2031|OwnerPartId=1|Electrical=4|PinConglomerate=51|PinLength=20|Location.X=200|Location.Y=495|Name=1|Designator=1|PinPropagationDelay=0.000000E+000
|RECORD=2|OwnerIndex=2031|OwnerPartId=1|Electrical=4|PinConglomerate=49|PinLength=20|Location.X=200|Location.Y=525|Name=2|Designator=2|PinPropagationDelay=0.000000E+000
|RECORD=13|OwnerIndex=2031|IsNotAccesible=T|IndexInSheet=2|OwnerPartId=1|Location.X=200|Location.Y=495|Corner.X=195|Corner.Y=498|LineWidth=1|Color=16711680
|RECORD=13|OwnerIndex=2031|IsNotAccesible=T|IndexInSheet=3|OwnerPartId=1|Location.X=195|Location.Y=498|Corner.X=205|Corner.Y=503|LineWidth=1|Color=16711680
|RECORD=13|OwnerIndex=2031|IsNotAccesible=T|IndexInSheet=4|OwnerPartId=1|Location.X=205|Location.Y=503|Corner.X=195|Corner.Y=508|LineWidth=1|Color=16711680
|RECORD=13|OwnerIndex=2031|IsNotAccesible=T|IndexInSheet=5|OwnerPartId=1|Location.X=195|Location.Y=508|Corner.X=205|Corner.Y=513|LineWidth=1|Color=16711680
|RECORD=13|OwnerIndex=2031|IsNotAccesible=T|IndexInSheet=6|OwnerPartId=1|Location.X=205|Location.Y=513|Corner.X=195|Corner.Y=518|LineWidth=1|Color=16711680
|RECORD=13|OwnerIndex=2031|IsNotAccesible=T|IndexInSheet=7|OwnerPartId=1|Location.X=195|Location.Y=518|Corner.X=205|Corner.Y=523|LineWidth=1|Color=16711680
|RECORD=13|OwnerIndex=2031|IsNotAccesible=T|IndexInSheet=8|OwnerPartId=1|Location.X=205|Location.Y=523|Corner.X=200|Corner.Y=525|LineWidth=1|Color=16711680
|RECORD=13|OwnerIndex=2031|IsNotAccesible=T|IndexInSheet=9|OwnerPartId=1|Location.X=200|Location.Y=495|Corner.X=200|Corner.Y=492|LineWidth=1|Color=16711680
|RECORD=13|OwnerIndex=2031|IsNotAccesible=T|IndexInSheet=10|OwnerPartId=1|Location.X=200|Location.Y=525|Corner.X=200|Corner.Y=528|LineWidth=1|Color=16711680
|RECORD=41|OwnerIndex=2031|IndexInSheet=11|OwnerPartId=-1|Location.X=194|Location.Y=547|Color=8388608|FontID=1|IsHidden=T|Text=Yes|Name=RoHS Compliant
|RECORD=41|OwnerIndex=2031|IndexInSheet=12|OwnerPartId=-1|Location.X=194|Location.Y=547|Color=8388608|FontID=1|IsHidden=T|Text=Tape and Reel|Name=Packaging
|RECORD=41|OwnerIndex=2031|IndexInSheet=13|OwnerPartId=-1|Location.X=194|Location.Y=547|Color=8388608|FontID=1|IsHidden=T|Text=1005|Name=Case Code (Metric)
|RECORD=41|OwnerIndex=2031|IndexInSheet=14|OwnerPartId=-1|Location.X=194|Location.Y=547|Color=8388608|FontID=1|IsHidden=T|Text=1|Name=Package Quantity
|RECORD=41|OwnerIndex=2031|IndexInSheet=15|OwnerPartId=-1|Location.X=194|Location.Y=547|Color=8388608|FontID=1|IsHidden=T|Text=Tin|Name=Contact Plating
|RECORD=41|OwnerIndex=2031|IndexInSheet=16|OwnerPartId=-1|Location.X=194|Location.Y=547|Color=8388608|FontID=1|IsHidden=T|Text=100mW|Name=Power Rating
|RECORD=41|OwnerIndex=2031|IndexInSheet=17|OwnerPartId=-1|Location.X=194|Location.Y=547|Color=8388608|FontID=1|IsHidden=T|Text=ERJ|Name=Series
|RECORD=41|OwnerIndex=2031|IndexInSheet=18|OwnerPartId=-1|Location.X=194|Location.Y=547|Color=8388608|FontID=1|IsHidden=T|Text=Surface Mount|Name=Mount
|RECORD=41|OwnerIndex=2031|IndexInSheet=19|OwnerPartId=-1|Location.X=194|Location.Y=547|Color=8388608|FontID=1|IsHidden=T|Text=Lead Free|Name=Lead Free
|RECORD=41|OwnerIndex=2031|IndexInSheet=20|OwnerPartId=-1|Location.X=194|Location.Y=547|Color=8388608|FontID=1|IsHidden=T|Text=-55°C|Name=Min Operating Temperature
|RECORD=41|OwnerIndex=2031|IndexInSheet=21|OwnerPartId=-1|Location.X=194|Location.Y=547|Color=8388608|FontID=1|IsHidden=T|Text=2|Name=Number of Terminations
|RECORD=41|OwnerIndex=2031|IndexInSheet=22|OwnerPartId=-1|Location.X=194|Location.Y=547|Color=8388608|FontID=1|IsHidden=T|Text=50V|Name=Voltage Rating (DC)
|RECORD=41|OwnerIndex=2031|IndexInSheet=23|OwnerPartId=-1|Location.X=194|Location.Y=547|Color=8388608|FontID=1|IsHidden=T|Text=100mW|Name=Max Power Dissipation
|RECORD=41|OwnerIndex=2031|IndexInSheet=24|OwnerPartId=-1|Location.X=194|Location.Y=547|Color=8388608|FontID=1|IsHidden=T|Text=THICK FILM|Name=Technology
|RECORD=41|OwnerIndex=2031|IndexInSheet=25|OwnerPartId=-1|Location.X=194|Location.Y=547|Color=8388608|FontID=1|IsHidden=T|Text=200R|Name=Resistance
|RECORD=41|OwnerIndex=2031|IndexInSheet=26|OwnerPartId=-1|Location.X=194|Location.Y=547|Color=8388608|FontID=1|IsHidden=T|Text=50V|Name=Voltage Rating
|RECORD=41|OwnerIndex=2031|IndexInSheet=27|OwnerPartId=-1|Location.X=194|Location.Y=547|Color=8388608|FontID=1|IsHidden=T|Text=0402|Name=Case/Package
|RECORD=41|OwnerIndex=2031|IndexInSheet=28|OwnerPartId=-1|Location.X=194|Location.Y=547|Color=8388608|FontID=1|IsHidden=T|Text=0.02inch|Name=Width
|RECORD=41|OwnerIndex=2031|IndexInSheet=29|OwnerPartId=-1|Location.X=194|Location.Y=547|Color=8388608|FontID=1|IsHidden=T|Text=SMD/SMT|Name=Termination
|RECORD=41|OwnerIndex=2031|IndexInSheet=30|OwnerPartId=-1|Location.X=194|Location.Y=547|Color=8388608|FontID=1|IsHidden=T|Text=Not|Name=Military Standard
|RECORD=41|OwnerIndex=2031|IndexInSheet=31|OwnerPartId=-1|Location.X=194|Location.Y=547|Color=8388608|FontID=1|IsHidden=T|Text=100ppm/°C|Name=Temperature Coefficient
|RECORD=41|OwnerIndex=2031|IndexInSheet=32|OwnerPartId=-1|Location.X=194|Location.Y=547|Color=8388608|FontID=1|IsHidden=T|Text=0.35mm|Name=Height
|RECORD=41|OwnerIndex=2031|IndexInSheet=33|OwnerPartId=-1|Location.X=194|Location.Y=547|Color=8388608|FontID=1|IsHidden=T|Text=No|Name=Radiation Hardening
|RECORD=41|OwnerIndex=2031|IndexInSheet=34|OwnerPartId=-1|Location.X=194|Location.Y=547|Color=8388608|FontID=1|IsHidden=T|Text=1%|Name=Resistance Tolerance
|RECORD=41|OwnerIndex=2031|IndexInSheet=35|OwnerPartId=-1|Location.X=194|Location.Y=547|Color=8388608|FontID=1|IsHidden=T|Text=1mm|Name=Length
|RECORD=41|OwnerIndex=2031|IndexInSheet=36|OwnerPartId=-1|Location.X=194|Location.Y=547|Color=8388608|FontID=1|IsHidden=T|Text=No SVHC|Name=REACH SVHC
|RECORD=41|OwnerIndex=2031|IndexInSheet=37|OwnerPartId=-1|Location.X=194|Location.Y=547|Color=8388608|FontID=1|IsHidden=T|Text=Rectangular|Name=Construction
|RECORD=41|OwnerIndex=2031|IndexInSheet=38|OwnerPartId=-1|Location.X=194|Location.Y=547|Color=8388608|FontID=1|IsHidden=T|Text=0.5mm|Name=Depth
|RECORD=41|OwnerIndex=2031|IndexInSheet=39|OwnerPartId=-1|Location.X=194|Location.Y=547|Color=8388608|FontID=1|IsHidden=T|Text=Automotive AEC-Q200|Name=Features
|RECORD=41|OwnerIndex=2031|IndexInSheet=40|OwnerPartId=-1|Location.X=194|Location.Y=547|Color=8388608|FontID=1|IsHidden=T|Text=Thick Film|Name=Resistor Type
|RECORD=41|OwnerIndex=2031|IndexInSheet=41|OwnerPartId=-1|Location.X=194|Location.Y=547|Color=8388608|FontID=1|IsHidden=T|Text=0402|Name=Case Code (Imperial)
|RECORD=41|OwnerIndex=2031|IndexInSheet=42|OwnerPartId=-1|Location.X=194|Location.Y=547|Color=8388608|FontID=1|IsHidden=T|Text=1%|Name=Tolerance
|RECORD=41|OwnerIndex=2031|IndexInSheet=43|OwnerPartId=-1|Location.X=194|Location.Y=547|Color=8388608|FontID=1|IsHidden=T|Text=0402|Name=Size Code
|RECORD=41|OwnerIndex=2031|IndexInSheet=44|OwnerPartId=-1|Location.X=194|Location.Y=547|Color=8388608|FontID=1|IsHidden=T|Text=155°C|Name=Max Operating Temperature
|RECORD=34|OwnerIndex=2031|IndexInSheet=-1|OwnerPartId=-1|Location.X=206|Location.Y=519|Color=8388608|FontID=1|Text=R1|Name=Designator|ReadOnlyState=1
|RECORD=41|OwnerIndex=2031|IndexInSheet=-1|OwnerPartId=1|Location.X=206|Location.Y=509|Color=8388608|FontID=1|Text=200_1%_0402|Name=Comment
|RECORD=44|OwnerIndex=2031
|RECORD=45|OwnerIndex=2081|IndexInSheet=-1|UseComponentLibrary=T|ModelName=FP-ERJ2RK-IPC_A|ModelType=PCBLIB|DatafileCount=1|ModelDatafileEntity0=FP-ERJ2RK-IPC_A|ModelDatafileKind0=PCBLib|IsCurrent=T|DatalinksLocked=T|DatabaseDatalinksLocked=T
|RECORD=46|OwnerIndex=2082
|RECORD=48|OwnerIndex=2082
|RECORD=45|OwnerIndex=2081|IndexInSheet=-1|UseComponentLibrary=T|ModelName=FP-ERJ2RK-IPC_C|ModelType=PCBLIB|DatafileCount=1|ModelDatafileEntity0=FP-ERJ2RK-IPC_C|ModelDatafileKind0=PCBLib|DatalinksLocked=T|DatabaseDatalinksLocked=T
|RECORD=46|OwnerIndex=2085
|RECORD=48|OwnerIndex=2085
|RECORD=45|OwnerIndex=2081|IndexInSheet=-1|UseComponentLibrary=T|ModelName=FP-ERJ2RK-MFG|ModelType=PCBLIB|DatafileCount=1|ModelDatafileEntity0=FP-ERJ2RK-MFG|ModelDatafileKind0=PCBLib|DatalinksLocked=T|DatabaseDatalinksLocked=T
|RECORD=46|OwnerIndex=2088
|RECORD=48|OwnerIndex=2088
|RECORD=45|OwnerIndex=2081|IndexInSheet=-1|UseComponentLibrary=T|ModelName=FP-ERJ2RK-IPC_B|ModelType=PCBLIB|DatafileCount=1|ModelDatafileEntity0=FP-ERJ2RK-IPC_B|ModelDatafileKind0=PCBLib|DatalinksLocked=T|DatabaseDatalinksLocked=T
|RECORD=46|OwnerIndex=2091
|RECORD=48|OwnerIndex=2091
|RECORD=1|LibReference=673ecd2ea4d7fb87b4005b0cb348b7d|ComponentDescription=TVS DIODE 12V 19.9V DO214AB|PartCount=2|DisplayModeCount=1|IndexInSheet=123|OwnerPartId=-1|Location.X=425|Location.Y=840|Orientation=1|CurrentPartId=1|LibraryPath=*|SourceLibraryName=Altium Content Vault|TargetFileName=*|AreaColor=11599871|Color=128|PartIDLocked=T|DesignItemId=CMP-08607-000111-1|AllPinCount=2
|RECORD=13|OwnerIndex=2094|IsNotAccesible=T|OwnerPartId=1|Location.X=415|Location.Y=860|Corner.X=435|Corner.Y=860|LineWidth=1|Color=16711680
|RECORD=13|OwnerIndex=2094|IsNotAccesible=T|IndexInSheet=1|OwnerPartId=1|Location.X=420|Location.Y=880|Corner.X=430|Corner.Y=880|LineWidth=1|Color=16711680
|RECORD=13|OwnerIndex=2094|IsNotAccesible=T|IndexInSheet=2|OwnerPartId=1|Location.X=415|Location.Y=860|Corner.X=425|Corner.Y=880|LineWidth=1|Color=16711680
|RECORD=13|OwnerIndex=2094|IsNotAccesible=T|IndexInSheet=3|OwnerPartId=1|Location.X=435|Location.Y=860|Corner.X=425|Corner.Y=880|LineWidth=1|Color=16711680
|RECORD=13|OwnerIndex=2094|IsNotAccesible=T|IndexInSheet=4|OwnerPartId=1|Location.X=420|Location.Y=880|Corner.X=415|Corner.Y=875|LineWidth=1|Color=16711680
|RECORD=13|OwnerIndex=2094|IsNotAccesible=T|IndexInSheet=5|OwnerPartId=1|Location.X=430|Location.Y=880|Corner.X=435|Corner.Y=885|LineWidth=1|Color=16711680
|RECORD=2|OwnerIndex=2094|OwnerPartId=1|Electrical=4|PinConglomerate=51|PinLength=20|Location.X=425|Location.Y=860|Name=A|Designator=2|PinPropagationDelay=0.000000E+000
|RECORD=2|OwnerIndex=2094|OwnerPartId=1|Electrical=4|PinConglomerate=49|PinLength=20|Location.X=425|Location.Y=880|Name=C|Designator=1|PinPropagationDelay=0.000000E+000
|RECORD=41|OwnerIndex=2094|IndexInSheet=8|OwnerPartId=-1|Location.X=414|Location.Y=902|Color=8388608|FontID=1|IsHidden=T|Text=Lead Free|Name=Lead Free
|RECORD=41|OwnerIndex=2094|IndexInSheet=9|OwnerPartId=-1|Location.X=414|Location.Y=902|Color=8388608|FontID=1|IsHidden=T|Text=Tape and Reel|Name=Packaging
|RECORD=41|OwnerIndex=2094|IndexInSheet=10|OwnerPartId=-1|Location.X=414|Location.Y=902|Color=8388608|FontID=1|IsHidden=T|Text=SMDJ|Name=Series
|RECORD=41|OwnerIndex=2094|IndexInSheet=11|OwnerPartId=-1|Location.X=414|Location.Y=902|Color=8388608|FontID=1|IsHidden=T|Text=2|Name=Number of Pins
|RECORD=41|OwnerIndex=2094|IndexInSheet=12|OwnerPartId=-1|Location.X=414|Location.Y=902|Color=8388608|FontID=1|IsHidden=T|Text=1|Name=Number of Channels
|RECORD=41|OwnerIndex=2094|IndexInSheet=13|OwnerPartId=-1|Location.X=414|Location.Y=902|Color=8388608|FontID=1|IsHidden=T|Text=Zener|Name=Resistor Type
|RECORD=41|OwnerIndex=2094|IndexInSheet=14|OwnerPartId=-1|Location.X=414|Location.Y=902|Color=8388608|FontID=1|IsHidden=T|Text=SMD/SMT|Name=Termination
|RECORD=41|OwnerIndex=2094|IndexInSheet=15|OwnerPartId=-1|Location.X=414|Location.Y=902|Color=8388608|FontID=1|IsHidden=T|Text=No|Name=Power Line Protection
|RECORD=41|OwnerIndex=2094|IndexInSheet=16|OwnerPartId=-1|Location.X=414|Location.Y=902|Color=8388608|FontID=1|IsHidden=T|Text=13.3V|Name=Reverse Breakdown Voltage
|RECORD=41|OwnerIndex=2094|IndexInSheet=17|OwnerPartId=-1|Location.X=414|Location.Y=902|Color=8388608|FontID=1|IsHidden=T|Text=6.5W|Name=Max Power Dissipation
|RECORD=41|OwnerIndex=2094|IndexInSheet=18|OwnerPartId=-1|Location.X=414|Location.Y=902|Color=8388608|FontID=1|IsHidden=T|Text=150.8A|Name=Peak Pulse Current
|RECORD=41|OwnerIndex=2094|IndexInSheet=19|OwnerPartId=-1|Location.X=414|Location.Y=902|Color=8388608|FontID=1|IsHidden=T|Text=Yes|Name=RoHS Compliant
|RECORD=41|OwnerIndex=2094|IndexInSheet=20|OwnerPartId=-1|Location.X=414|Location.Y=902|Color=8388608|FontID=1|IsHidden=T|Text=2uA|Name=Leakage Current
|RECORD=41|OwnerIndex=2094|IndexInSheet=21|OwnerPartId=-1|Location.X=414|Location.Y=902|Color=8388608|FontID=1|IsHidden=T|Text=ZENER|Name=Diode Type
|RECORD=41|OwnerIndex=2094|IndexInSheet=22|OwnerPartId=-1|Location.X=414|Location.Y=902|Color=8388608|FontID=1|IsHidden=T|Text=3kW|Name=Power Dissipation
|RECORD=41|OwnerIndex=2094|IndexInSheet=23|OwnerPartId=-1|Location.X=414|Location.Y=902|Color=8388608|FontID=1|IsHidden=T|Text=1|Name=Number of Elements
|RECORD=41|OwnerIndex=2094|IndexInSheet=24|OwnerPartId=-1|Location.X=414|Location.Y=902|Color=8388608|FontID=1|IsHidden=T|Text=1mA|Name=Test Current
|RECORD=41|OwnerIndex=2094|IndexInSheet=25|OwnerPartId=-1|Location.X=414|Location.Y=902|Color=8388608|FontID=1|IsHidden=T|Text=No SVHC|Name=REACH SVHC
|RECORD=41|OwnerIndex=2094|IndexInSheet=26|OwnerPartId=-1|Location.X=414|Location.Y=902|Color=8388608|FontID=1|IsHidden=T|Text=13.3V|Name=Min Breakdown Voltage
|RECORD=41|OwnerIndex=2094|IndexInSheet=27|OwnerPartId=-1|Location.X=414|Location.Y=902|Color=8388608|FontID=1|IsHidden=T|Text=Unidirectional|Name=Direction
|RECORD=41|OwnerIndex=2094|IndexInSheet=28|OwnerPartId=-1|Location.X=414|Location.Y=902|Color=8388608|FontID=1|IsHidden=T|Text=14.7V|Name=Max Breakdown Voltage
|RECORD=41|OwnerIndex=2094|IndexInSheet=29|OwnerPartId=-1|Location.X=414|Location.Y=902|Color=8388608|FontID=1|IsHidden=T|Text=Surface Mount|Name=Mount
|RECORD=41|OwnerIndex=2094|IndexInSheet=30|OwnerPartId=-1|Location.X=414|Location.Y=902|Color=8388608|FontID=1|IsHidden=T|Text=12V|Name=Operating Supply Voltage
|RECORD=41|OwnerIndex=2094|IndexInSheet=31|OwnerPartId=-1|Location.X=414|Location.Y=902|Color=8388608|FontID=1|IsHidden=T|Text=Unidirectional|Name=Polarity
|RECORD=41|OwnerIndex=2094|IndexInSheet=32|OwnerPartId=-1|Location.X=414|Location.Y=902|Color=8388608|FontID=1|IsHidden=T|Text=13.3V|Name=Breakdown Voltage
|RECORD=41|OwnerIndex=2094|IndexInSheet=33|OwnerPartId=-1|Location.X=414|Location.Y=902|Color=8388608|FontID=1|IsHidden=T|Text=150.8A|Name=Max Surge Current
|RECORD=41|OwnerIndex=2094|IndexInSheet=34|OwnerPartId=-1|Location.X=414|Location.Y=902|Color=8388608|FontID=1|IsHidden=T|Text=19.9V|Name=Clamping Voltage-Max
|RECORD=41|OwnerIndex=2094|IndexInSheet=35|OwnerPartId=-1|Location.X=414|Location.Y=902|Color=8388608|FontID=1|IsHidden=T|Text=19.9V|Name=Clamping Voltage
|RECORD=41|OwnerIndex=2094|IndexInSheet=36|OwnerPartId=-1|Location.X=414|Location.Y=902|Color=8388608|FontID=1|IsHidden=T|Text=12V|Name=Reverse Standoff Voltage
|RECORD=41|OwnerIndex=2094|IndexInSheet=37|OwnerPartId=-1|Location.X=414|Location.Y=902|Color=8388608|FontID=1|IsHidden=T|Text=150°C|Name=Max Operating Temperature
|RECORD=41|OwnerIndex=2094|IndexInSheet=38|OwnerPartId=-1|Location.X=414|Location.Y=902|Color=8388608|FontID=1|IsHidden=T|Text=DO-214AB|Name=Case/Package
|RECORD=41|OwnerIndex=2094|IndexInSheet=39|OwnerPartId=-1|Location.X=414|Location.Y=902|Color=8388608|FontID=1|IsHidden=T|Text=3000|Name=Package Quantity
|RECORD=41|OwnerIndex=2094|IndexInSheet=40|OwnerPartId=-1|Location.X=414|Location.Y=902|Color=8388608|FontID=1|IsHidden=T|Text=3kW|Name=Peak Pulse Power
|RECORD=41|OwnerIndex=2094|IndexInSheet=41|OwnerPartId=-1|Location.X=414|Location.Y=902|Color=8388608|FontID=1|IsHidden=T|Text=-55°C|Name=Min Operating Temperature
|RECORD=41|OwnerIndex=2094|IndexInSheet=42|OwnerPartId=-1|Location.X=414|Location.Y=902|Color=8388608|FontID=1|IsHidden=T|Text=1|Name=Number of Unidirectional Channels
|RECORD=34|OwnerIndex=2094|IndexInSheet=-1|OwnerPartId=-1|Location.X=436|Location.Y=876|Color=8388608|FontID=1|Text=D23|Name=Designator|ReadOnlyState=1
|RECORD=41|OwnerIndex=2094|IndexInSheet=-1|OwnerPartId=1|Location.X=436|Location.Y=866|Color=8388608|FontID=1|Text=SMDJ12A|Name=Comment
|RECORD=44|OwnerIndex=2094
|RECORD=45|OwnerIndex=2142|IndexInSheet=-1|UseComponentLibrary=T|ModelName=FP-DO-214AB_SMC_J-Bend-MFG|ModelType=PCBLIB|DatafileCount=1|ModelDatafileEntity0=FP-DO-214AB_SMC_J-Bend-MFG|ModelDatafileKind0=PCBLib|IsCurrent=T|DatalinksLocked=T|DatabaseDatalinksLocked=T
|RECORD=46|OwnerIndex=2143
|RECORD=48|OwnerIndex=2143
|RECORD=17|IndexInSheet=124|OwnerPartId=-1|Style=4|ShowNetName=T|Location.X=425|Location.Y=830|Orientation=3|Color=128|FontID=1|Text=GND
|RECORD=1|LibReference=8706943c75ba83719d021d2fdc84c58|ComponentDescription=LED GREEN CLEAR SMD|PartCount=2|DisplayModeCount=1|IndexInSheet=125|OwnerPartId=-1|Location.X=85|Location.Y=620|Orientation=3|CurrentPartId=1|LibraryPath=*|SourceLibraryName=Altium Content Vault|TargetFileName=*|AreaColor=11599871|Color=128|PartIDLocked=T|DesignItemId=CMP-2000-05198-2|AllPinCount=2
|RECORD=2|OwnerIndex=2147|OwnerPartId=1|Electrical=4|PinConglomerate=49|PinLength=20|Location.X=85|Location.Y=600|Name=A|Designator=2|PinPropagationDelay=0.000000E+000
|RECORD=2|OwnerIndex=2147|OwnerPartId=1|Electrical=4|PinConglomerate=51|PinLength=20|Location.X=85|Location.Y=580|Name=C|Designator=1|PinPropagationDelay=0.000000E+000
|RECORD=13|OwnerIndex=2147|IsNotAccesible=T|IndexInSheet=2|OwnerPartId=1|Location.X=95|Location.Y=600|Corner.X=75|Corner.Y=600|LineWidth=1|Color=16711680
|RECORD=13|OwnerIndex=2147|IsNotAccesible=T|IndexInSheet=3|OwnerPartId=1|Location.X=95|Location.Y=580|Corner.X=75|Corner.Y=580|LineWidth=1|Color=16711680
|RECORD=13|OwnerIndex=2147|IsNotAccesible=T|IndexInSheet=4|OwnerPartId=1|Location.X=95|Location.Y=600|Corner.X=85|Corner.Y=580|LineWidth=1|Color=16711680
|RECORD=13|OwnerIndex=2147|IsNotAccesible=T|IndexInSheet=5|OwnerPartId=1|Location.X=75|Location.Y=600|Corner.X=85|Corner.Y=580|LineWidth=1|Color=16711680
|RECORD=13|OwnerIndex=2147|IsNotAccesible=T|IndexInSheet=6|OwnerPartId=1|Location.X=97|Location.Y=595|Corner.X=107|Corner.Y=585|LineWidth=1|Color=16711680
|RECORD=13|OwnerIndex=2147|IsNotAccesible=T|IndexInSheet=7|OwnerPartId=1|Location.X=107|Location.Y=585|Corner.X=107|Corner.Y=590|LineWidth=1|Color=16711680
|RECORD=13|OwnerIndex=2147|IsNotAccesible=T|IndexInSheet=8|OwnerPartId=1|Location.X=107|Location.Y=585|Corner.X=102|Corner.Y=585|LineWidth=1|Color=16711680
|RECORD=13|OwnerIndex=2147|IsNotAccesible=T|IndexInSheet=9|OwnerPartId=1|Location.X=93|Location.Y=588|Corner.X=103|Corner.Y=578|LineWidth=1|Color=16711680
|RECORD=13|OwnerIndex=2147|IsNotAccesible=T|IndexInSheet=10|OwnerPartId=1|Location.X=103|Location.Y=578|Corner.X=103|Corner.Y=583|LineWidth=1|Color=16711680
|RECORD=13|OwnerIndex=2147|IsNotAccesible=T|IndexInSheet=11|OwnerPartId=1|Location.X=103|Location.Y=578|Corner.X=98|Corner.Y=578|LineWidth=1|Color=16711680
|RECORD=13|OwnerIndex=2147|IsNotAccesible=T|IndexInSheet=12|OwnerPartId=1|Location.X=85|Location.Y=600|Corner.X=85|Corner.Y=603|LineWidth=1|Color=16711680
|RECORD=13|OwnerIndex=2147|IsNotAccesible=T|IndexInSheet=13|OwnerPartId=1|Location.X=85|Location.Y=580|Corner.X=85|Corner.Y=577|LineWidth=1|Color=16711680
|RECORD=41|OwnerIndex=2147|IndexInSheet=14|OwnerPartId=-1|Location.X=74|Location.Y=622|Color=8388608|FontID=1|IsHidden=T|Text=0.8mm|Name=Width
|RECORD=41|OwnerIndex=2147|IndexInSheet=15|OwnerPartId=-1|Location.X=74|Location.Y=622|Color=8388608|FontID=1|IsHidden=T|Text=0603|Name=Case Code (Imperial)
|RECORD=41|OwnerIndex=2147|IndexInSheet=16|OwnerPartId=-1|Location.X=74|Location.Y=622|Color=8388608|FontID=1|IsHidden=T|Text=2|Name=Number of Pins
|RECORD=41|OwnerIndex=2147|IndexInSheet=17|OwnerPartId=-1|Location.X=74|Location.Y=622|Color=8388608|FontID=1|IsHidden=T|Text=75mW|Name=Max Power Dissipation
|RECORD=41|OwnerIndex=2147|IndexInSheet=18|OwnerPartId=-1|Location.X=74|Location.Y=622|Color=8388608|FontID=1|IsHidden=T|Text=30mA|Name=Forward Current
|RECORD=41|OwnerIndex=2147|IndexInSheet=19|OwnerPartId=-1|Location.X=74|Location.Y=622|Color=8388608|FontID=1|IsHidden=T|Text=Lead Free|Name=Lead Free
|RECORD=41|OwnerIndex=2147|IndexInSheet=20|OwnerPartId=-1|Location.X=74|Location.Y=622|Color=8388608|FontID=1|IsHidden=T|Text=5V|Name=Reverse Voltage
|RECORD=41|OwnerIndex=2147|IndexInSheet=21|OwnerPartId=-1|Location.X=74|Location.Y=622|Color=8388608|FontID=1|IsHidden=T|Text=Colorless|Name=Lens Color
|RECORD=41|OwnerIndex=2147|IndexInSheet=22|OwnerPartId=-1|Location.X=74|Location.Y=622|Color=8388608|FontID=1|IsHidden=T|Text=2V|Name=Forward Voltage
|RECORD=41|OwnerIndex=2147|IndexInSheet=23|OwnerPartId=-1|Location.X=74|Location.Y=622|Color=8388608|FontID=1|IsHidden=T|Text=Tape and Reel|Name=Packaging
|RECORD=41|OwnerIndex=2147|IndexInSheet=24|OwnerPartId=-1|Location.X=74|Location.Y=622|Color=8388608|FontID=1|IsHidden=T|Text=1|Name=Package Quantity
|RECORD=41|OwnerIndex=2147|IndexInSheet=25|OwnerPartId=-1|Location.X=74|Location.Y=622|Color=8388608|FontID=1|IsHidden=T|Text=-55°C|Name=Min Operating Temperature
|RECORD=41|OwnerIndex=2147|IndexInSheet=26|OwnerPartId=-1|Location.X=74|Location.Y=622|Color=8388608|FontID=1|IsHidden=T|Text=0603|Name=Case/Package
|RECORD=41|OwnerIndex=2147|IndexInSheet=27|OwnerPartId=-1|Location.X=74|Location.Y=622|Color=8388608|FontID=1|IsHidden=T|Text=1.6mm|Name=Length
|RECORD=41|OwnerIndex=2147|IndexInSheet=28|OwnerPartId=-1|Location.X=74|Location.Y=622|Color=8388608|FontID=1|IsHidden=T|Text=75mW|Name=Power Dissipation
|RECORD=41|OwnerIndex=2147|IndexInSheet=29|OwnerPartId=-1|Location.X=74|Location.Y=622|Color=8388608|FontID=1|IsHidden=T|Text=571nm|Name=Dominant Wavelength
|RECORD=41|OwnerIndex=2147|IndexInSheet=30|OwnerPartId=-1|Location.X=74|Location.Y=622|Color=8388608|FontID=1|IsHidden=T|Text=0.8mm|Name=Depth
|RECORD=41|OwnerIndex=2147|IndexInSheet=31|OwnerPartId=-1|Location.X=74|Location.Y=622|Color=8388608|FontID=1|IsHidden=T|Text=No|Name=Radiation Hardening
|RECORD=41|OwnerIndex=2147|IndexInSheet=32|OwnerPartId=-1|Location.X=74|Location.Y=622|Color=8388608|FontID=1|IsHidden=T|Text=Surface Mount|Name=Mount
|RECORD=41|OwnerIndex=2147|IndexInSheet=33|OwnerPartId=-1|Location.X=74|Location.Y=622|Color=8388608|FontID=1|IsHidden=T|Text=85°C|Name=Max Operating Temperature
|RECORD=41|OwnerIndex=2147|IndexInSheet=34|OwnerPartId=-1|Location.X=74|Location.Y=622|Color=8388608|FontID=1|IsHidden=T|Text=Green|Name=Color
|RECORD=41|OwnerIndex=2147|IndexInSheet=35|OwnerPartId=-1|Location.X=74|Location.Y=622|Color=8388608|FontID=1|IsHidden=T|Text=75mW|Name=Power Rating
|RECORD=41|OwnerIndex=2147|IndexInSheet=36|OwnerPartId=-1|Location.X=74|Location.Y=622|Color=8388608|FontID=1|IsHidden=T|Text=0.55mm|Name=Height
|RECORD=41|OwnerIndex=2147|IndexInSheet=37|OwnerPartId=-1|Location.X=74|Location.Y=622|Color=8388608|FontID=1|IsHidden=T|Text=1|Name=Number of LEDs
|RECORD=41|OwnerIndex=2147|IndexInSheet=38|OwnerPartId=-1|Location.X=74|Location.Y=622|Color=8388608|FontID=1|IsHidden=T|Text=130°|Name=Viewing Angle
|RECORD=41|OwnerIndex=2147|IndexInSheet=39|OwnerPartId=-1|Location.X=74|Location.Y=622|Color=8388608|FontID=1|IsHidden=T|Text=Rectangular|Name=Lens Style
|RECORD=41|OwnerIndex=2147|IndexInSheet=40|OwnerPartId=-1|Location.X=74|Location.Y=622|Color=8388608|FontID=1|IsHidden=T|Text=Green|Name=Illumination Color
|RECORD=41|OwnerIndex=2147|IndexInSheet=41|OwnerPartId=-1|Location.X=74|Location.Y=622|Color=8388608|FontID=1|IsHidden=T|Text=20mA|Name=Test Current
|RECORD=41|OwnerIndex=2147|IndexInSheet=42|OwnerPartId=-1|Location.X=74|Location.Y=622|Color=8388608|FontID=1|IsHidden=T|Text=1608|Name=Case Code (Metric)
|RECORD=41|OwnerIndex=2147|IndexInSheet=43|OwnerPartId=-1|Location.X=74|Location.Y=622|Color=8388608|FontID=1|IsHidden=T|Text=Clear|Name=Lens Transparency
|RECORD=41|OwnerIndex=2147|IndexInSheet=44|OwnerPartId=-1|Location.X=74|Location.Y=622|Color=8388608|FontID=1|IsHidden=T|Text=35mcd|Name=Luminous Intensity
|RECORD=41|OwnerIndex=2147|IndexInSheet=45|OwnerPartId=-1|Location.X=74|Location.Y=622|Color=8388608|FontID=1|IsHidden=T|Text=1|Name=Number of Elements
|RECORD=41|OwnerIndex=2147|IndexInSheet=46|OwnerPartId=-1|Location.X=74|Location.Y=622|Color=8388608|FontID=1|IsHidden=T|Text=574nm|Name=Wavelength
|RECORD=34|OwnerIndex=2147|IndexInSheet=-1|OwnerPartId=-1|Location.X=70|Location.Y=580|Orientation=1|Color=8388608|FontID=2|Text=D20|Name=Designator|ReadOnlyState=1
|RECORD=41|OwnerIndex=2147|IndexInSheet=-1|OwnerPartId=1|Location.X=124|Location.Y=560|Orientation=1|Color=8388608|FontID=2|Text=LTST-C191KGKT|Name=Comment
|RECORD=44|OwnerIndex=2147
|RECORD=45|OwnerIndex=2199|IndexInSheet=-1|UseComponentLibrary=T|ModelName=FP-LTST-C191KGKT-MFG|ModelType=PCBLIB|DatafileCount=1|ModelDatafileEntity0=FP-LTST-C191KGKT-MFG|ModelDatafileKind0=PCBLib|IsCurrent=T|DatalinksLocked=T|DatabaseDatalinksLocked=T
|RECORD=46|OwnerIndex=2200
|RECORD=48|OwnerIndex=2200
|RECORD=1|LibReference=8706943c75ba83719d021d2fdc84c58|ComponentDescription=LED GREEN CLEAR SMD|PartCount=2|DisplayModeCount=1|IndexInSheet=126|OwnerPartId=-1|Location.X=200|Location.Y=625|Orientation=3|CurrentPartId=1|LibraryPath=*|SourceLibraryName=Altium Content Vault|TargetFileName=*|AreaColor=11599871|Color=128|PartIDLocked=T|DesignItemId=CMP-2000-05198-2|AllPinCount=2
|RECORD=2|OwnerIndex=2203|OwnerPartId=1|Electrical=4|PinConglomerate=49|PinLength=20|Location.X=200|Location.Y=605|Name=A|Designator=2|PinPropagationDelay=0.000000E+000
|RECORD=2|OwnerIndex=2203|OwnerPartId=1|Electrical=4|PinConglomerate=51|PinLength=20|Location.X=200|Location.Y=585|Name=C|Designator=1|PinPropagationDelay=0.000000E+000
|RECORD=13|OwnerIndex=2203|IsNotAccesible=T|IndexInSheet=2|OwnerPartId=1|Location.X=210|Location.Y=605|Corner.X=190|Corner.Y=605|LineWidth=1|Color=16711680
|RECORD=13|OwnerIndex=2203|IsNotAccesible=T|IndexInSheet=3|OwnerPartId=1|Location.X=210|Location.Y=585|Corner.X=190|Corner.Y=585|LineWidth=1|Color=16711680
|RECORD=13|OwnerIndex=2203|IsNotAccesible=T|IndexInSheet=4|OwnerPartId=1|Location.X=210|Location.Y=605|Corner.X=200|Corner.Y=585|LineWidth=1|Color=16711680
|RECORD=13|OwnerIndex=2203|IsNotAccesible=T|IndexInSheet=5|OwnerPartId=1|Location.X=190|Location.Y=605|Corner.X=200|Corner.Y=585|LineWidth=1|Color=16711680
|RECORD=13|OwnerIndex=2203|IsNotAccesible=T|IndexInSheet=6|OwnerPartId=1|Location.X=212|Location.Y=600|Corner.X=222|Corner.Y=590|LineWidth=1|Color=16711680
|RECORD=13|OwnerIndex=2203|IsNotAccesible=T|IndexInSheet=7|OwnerPartId=1|Location.X=222|Location.Y=590|Corner.X=222|Corner.Y=595|LineWidth=1|Color=16711680
|RECORD=13|OwnerIndex=2203|IsNotAccesible=T|IndexInSheet=8|OwnerPartId=1|Location.X=222|Location.Y=590|Corner.X=217|Corner.Y=590|LineWidth=1|Color=16711680
|RECORD=13|OwnerIndex=2203|IsNotAccesible=T|IndexInSheet=9|OwnerPartId=1|Location.X=208|Location.Y=593|Corner.X=218|Corner.Y=583|LineWidth=1|Color=16711680
|RECORD=13|OwnerIndex=2203|IsNotAccesible=T|IndexInSheet=10|OwnerPartId=1|Location.X=218|Location.Y=583|Corner.X=218|Corner.Y=588|LineWidth=1|Color=16711680
|RECORD=13|OwnerIndex=2203|IsNotAccesible=T|IndexInSheet=11|OwnerPartId=1|Location.X=218|Location.Y=583|Corner.X=213|Corner.Y=583|LineWidth=1|Color=16711680
|RECORD=13|OwnerIndex=2203|IsNotAccesible=T|IndexInSheet=12|OwnerPartId=1|Location.X=200|Location.Y=605|Corner.X=200|Corner.Y=608|LineWidth=1|Color=16711680
|RECORD=13|OwnerIndex=2203|IsNotAccesible=T|IndexInSheet=13|OwnerPartId=1|Location.X=200|Location.Y=585|Corner.X=200|Corner.Y=582|LineWidth=1|Color=16711680
|RECORD=41|OwnerIndex=2203|IndexInSheet=14|OwnerPartId=-1|Location.X=189|Location.Y=627|Color=8388608|FontID=1|IsHidden=T|Text=0.8mm|Name=Width
|RECORD=41|OwnerIndex=2203|IndexInSheet=15|OwnerPartId=-1|Location.X=189|Location.Y=627|Color=8388608|FontID=1|IsHidden=T|Text=0603|Name=Case Code (Imperial)
|RECORD=41|OwnerIndex=2203|IndexInSheet=16|OwnerPartId=-1|Location.X=189|Location.Y=627|Color=8388608|FontID=1|IsHidden=T|Text=2|Name=Number of Pins
|RECORD=41|OwnerIndex=2203|IndexInSheet=17|OwnerPartId=-1|Location.X=189|Location.Y=627|Color=8388608|FontID=1|IsHidden=T|Text=75mW|Name=Max Power Dissipation
|RECORD=41|OwnerIndex=2203|IndexInSheet=18|OwnerPartId=-1|Location.X=189|Location.Y=627|Color=8388608|FontID=1|IsHidden=T|Text=30mA|Name=Forward Current
|RECORD=41|OwnerIndex=2203|IndexInSheet=19|OwnerPartId=-1|Location.X=189|Location.Y=627|Color=8388608|FontID=1|IsHidden=T|Text=Lead Free|Name=Lead Free
|RECORD=41|OwnerIndex=2203|IndexInSheet=20|OwnerPartId=-1|Location.X=189|Location.Y=627|Color=8388608|FontID=1|IsHidden=T|Text=5V|Name=Reverse Voltage
|RECORD=41|OwnerIndex=2203|IndexInSheet=21|OwnerPartId=-1|Location.X=189|Location.Y=627|Color=8388608|FontID=1|IsHidden=T|Text=Colorless|Name=Lens Color
|RECORD=41|OwnerIndex=2203|IndexInSheet=22|OwnerPartId=-1|Location.X=189|Location.Y=627|Color=8388608|FontID=1|IsHidden=T|Text=2V|Name=Forward Voltage
|RECORD=41|OwnerIndex=2203|IndexInSheet=23|OwnerPartId=-1|Location.X=189|Location.Y=627|Color=8388608|FontID=1|IsHidden=T|Text=Tape and Reel|Name=Packaging
|RECORD=41|OwnerIndex=2203|IndexInSheet=24|OwnerPartId=-1|Location.X=189|Location.Y=627|Color=8388608|FontID=1|IsHidden=T|Text=1|Name=Package Quantity
|RECORD=41|OwnerIndex=2203|IndexInSheet=25|OwnerPartId=-1|Location.X=189|Location.Y=627|Color=8388608|FontID=1|IsHidden=T|Text=-55°C|Name=Min Operating Temperature
|RECORD=41|OwnerIndex=2203|IndexInSheet=26|OwnerPartId=-1|Location.X=189|Location.Y=627|Color=8388608|FontID=1|IsHidden=T|Text=0603|Name=Case/Package
|RECORD=41|OwnerIndex=2203|IndexInSheet=27|OwnerPartId=-1|Location.X=189|Location.Y=627|Color=8388608|FontID=1|IsHidden=T|Text=1.6mm|Name=Length
|RECORD=41|OwnerIndex=2203|IndexInSheet=28|OwnerPartId=-1|Location.X=189|Location.Y=627|Color=8388608|FontID=1|IsHidden=T|Text=75mW|Name=Power Dissipation
|RECORD=41|OwnerIndex=2203|IndexInSheet=29|OwnerPartId=-1|Location.X=189|Location.Y=627|Color=8388608|FontID=1|IsHidden=T|Text=571nm|Name=Dominant Wavelength
|RECORD=41|OwnerIndex=2203|IndexInSheet=30|OwnerPartId=-1|Location.X=189|Location.Y=627|Color=8388608|FontID=1|IsHidden=T|Text=0.8mm|Name=Depth
|RECORD=41|OwnerIndex=2203|IndexInSheet=31|OwnerPartId=-1|Location.X=189|Location.Y=627|Color=8388608|FontID=1|IsHidden=T|Text=No|Name=Radiation Hardening
|RECORD=41|OwnerIndex=2203|IndexInSheet=32|OwnerPartId=-1|Location.X=189|Location.Y=627|Color=8388608|FontID=1|IsHidden=T|Text=Surface Mount|Name=Mount
|RECORD=41|OwnerIndex=2203|IndexInSheet=33|OwnerPartId=-1|Location.X=189|Location.Y=627|Color=8388608|FontID=1|IsHidden=T|Text=85°C|Name=Max Operating Temperature
|RECORD=41|OwnerIndex=2203|IndexInSheet=34|OwnerPartId=-1|Location.X=189|Location.Y=627|Color=8388608|FontID=1|IsHidden=T|Text=Green|Name=Color
|RECORD=41|OwnerIndex=2203|IndexInSheet=35|OwnerPartId=-1|Location.X=189|Location.Y=627|Color=8388608|FontID=1|IsHidden=T|Text=75mW|Name=Power Rating
|RECORD=41|OwnerIndex=2203|IndexInSheet=36|OwnerPartId=-1|Location.X=189|Location.Y=627|Color=8388608|FontID=1|IsHidden=T|Text=0.55mm|Name=Height
|RECORD=41|OwnerIndex=2203|IndexInSheet=37|OwnerPartId=-1|Location.X=189|Location.Y=627|Color=8388608|FontID=1|IsHidden=T|Text=1|Name=Number of LEDs
|RECORD=41|OwnerIndex=2203|IndexInSheet=38|OwnerPartId=-1|Location.X=189|Location.Y=627|Color=8388608|FontID=1|IsHidden=T|Text=130°|Name=Viewing Angle
|RECORD=41|OwnerIndex=2203|IndexInSheet=39|OwnerPartId=-1|Location.X=189|Location.Y=627|Color=8388608|FontID=1|IsHidden=T|Text=Rectangular|Name=Lens Style
|RECORD=41|OwnerIndex=2203|IndexInSheet=40|OwnerPartId=-1|Location.X=189|Location.Y=627|Color=8388608|FontID=1|IsHidden=T|Text=Green|Name=Illumination Color
|RECORD=41|OwnerIndex=2203|IndexInSheet=41|OwnerPartId=-1|Location.X=189|Location.Y=627|Color=8388608|FontID=1|IsHidden=T|Text=20mA|Name=Test Current
|RECORD=41|OwnerIndex=2203|IndexInSheet=42|OwnerPartId=-1|Location.X=189|Location.Y=627|Color=8388608|FontID=1|IsHidden=T|Text=1608|Name=Case Code (Metric)
|RECORD=41|OwnerIndex=2203|IndexInSheet=43|OwnerPartId=-1|Location.X=189|Location.Y=627|Color=8388608|FontID=1|IsHidden=T|Text=Clear|Name=Lens Transparency
|RECORD=41|OwnerIndex=2203|IndexInSheet=44|OwnerPartId=-1|Location.X=189|Location.Y=627|Color=8388608|FontID=1|IsHidden=T|Text=35mcd|Name=Luminous Intensity
|RECORD=41|OwnerIndex=2203|IndexInSheet=45|OwnerPartId=-1|Location.X=189|Location.Y=627|Color=8388608|FontID=1|IsHidden=T|Text=1|Name=Number of Elements
|RECORD=41|OwnerIndex=2203|IndexInSheet=46|OwnerPartId=-1|Location.X=189|Location.Y=627|Color=8388608|FontID=1|IsHidden=T|Text=574nm|Name=Wavelength
|RECORD=34|OwnerIndex=2203|IndexInSheet=-1|OwnerPartId=-1|Location.X=185|Location.Y=585|Orientation=1|Color=8388608|FontID=2|Text=D4|Name=Designator|ReadOnlyState=1
|RECORD=41|OwnerIndex=2203|IndexInSheet=-1|OwnerPartId=1|Location.X=239|Location.Y=565|Orientation=1|Color=8388608|FontID=2|Text=LTST-C191KGKT|Name=Comment
|RECORD=44|OwnerIndex=2203
|RECORD=45|OwnerIndex=2255|IndexInSheet=-1|UseComponentLibrary=T|ModelName=FP-LTST-C191KGKT-MFG|ModelType=PCBLIB|DatafileCount=1|ModelDatafileEntity0=FP-LTST-C191KGKT-MFG|ModelDatafileKind0=PCBLib|IsCurrent=T|DatalinksLocked=T|DatabaseDatalinksLocked=T
|RECORD=46|OwnerIndex=2256
|RECORD=48|OwnerIndex=2256
|RECORD=17|IndexInSheet=127|OwnerPartId=-1|Style=4|ShowNetName=T|Location.X=675|Location.Y=865|Orientation=3|Color=128|FontID=1|Text=GND
|RECORD=17|IndexInSheet=128|OwnerPartId=-1|Style=4|ShowNetName=T|Location.X=340|Location.Y=285|Orientation=3|Color=128|FontID=1|Text=GND
|RECORD=1|LibReference=57b8017c1ce60d7b1362a625e7a4ba1|ComponentDescription=DC DC CONVERTER 0.7-5V|PartCount=2|DisplayModeCount=1|IndexInSheet=129|OwnerPartId=-1|Location.X=585|Location.Y=555|CurrentPartId=1|LibraryPath=*|SourceLibraryName=Altium Content Vault|TargetFileName=*|AreaColor=11599871|Color=128|PartIDLocked=T|DesignItemId=CMP-20596-000049-1|AllPinCount=23|ComponentKindVersion2=5
|RECORD=14|OwnerIndex=2261|IsNotAccesible=T|OwnerPartId=1|Location.X=605|Location.Y=335|Corner.X=765|Corner.Y=565|LineWidth=1|Color=128|AreaColor=11599871|IsSolid=T
|RECORD=2|OwnerIndex=2261|OwnerPartId=1|Electrical=7|PinConglomerate=58|PinLength=20|Location.X=605|Location.Y=555|Name=Vin|Designator=1|PinName_PositionConglomerate=16|Name_CustomFontID=1|PinDesignator_PositionConglomerate=16|Designator_CustomFontID=1|PinPropagationDelay=0.000000E+000
|RECORD=2|OwnerIndex=2261|OwnerPartId=1|Electrical=7|PinConglomerate=58|PinLength=20|Location.X=605|Location.Y=545|Name=Vin|Designator=2|PinName_PositionConglomerate=16|Name_CustomFontID=1|PinDesignator_PositionConglomerate=16|Designator_CustomFontID=1|PinPropagationDelay=0.000000E+000
|RECORD=2|OwnerIndex=2261|OwnerPartId=1|Electrical=7|PinConglomerate=56|PinLength=20|Location.X=765|Location.Y=555|Name=Vout|Designator=6|PinName_PositionConglomerate=16|Name_CustomFontID=1|PinDesignator_PositionConglomerate=16|Designator_CustomFontID=1|PinPropagationDelay=0.000000E+000
|RECORD=2|OwnerIndex=2261|OwnerPartId=1|Electrical=7|PinConglomerate=56|PinLength=20|Location.X=765|Location.Y=545|Name=Vout|Designator=7|PinName_PositionConglomerate=16|Name_CustomFontID=1|PinDesignator_PositionConglomerate=16|Designator_CustomFontID=1|PinPropagationDelay=0.000000E+000
|RECORD=2|OwnerIndex=2261|OwnerPartId=1|PinConglomerate=58|PinLength=20|Location.X=605|Location.Y=525|Name=ON/OFF|Designator=12|PinName_PositionConglomerate=16|Name_CustomFontID=1|PinDesignator_PositionConglomerate=16|Designator_CustomFontID=1|PinPropagationDelay=0.000000E+000
|RECORD=2|OwnerIndex=2261|OwnerPartId=1|Electrical=3|PinConglomerate=58|PinLength=20|Location.X=605|Location.Y=505|Name=PWGOOD|Designator=11|PinName_PositionConglomerate=16|Name_CustomFontID=1|PinDesignator_PositionConglomerate=16|Designator_CustomFontID=1|PinPropagationDelay=0.000000E+000
|RECORD=2|OwnerIndex=2261|OwnerPartId=1|Electrical=4|PinConglomerate=56|PinLength=20|Location.X=765|Location.Y=525|Name=Sense|Designator=5|PinName_PositionConglomerate=16|Name_CustomFontID=1|PinDesignator_PositionConglomerate=16|Designator_CustomFontID=1|PinPropagationDelay=0.000000E+000
|RECORD=2|OwnerIndex=2261|OwnerPartId=1|Electrical=4|PinConglomerate=56|PinLength=20|Location.X=765|Location.Y=505|Name=Trim|Designator=4|PinName_PositionConglomerate=16|Name_CustomFontID=1|PinDesignator_PositionConglomerate=16|Designator_CustomFontID=1|PinPropagationDelay=0.000000E+000
|RECORD=2|OwnerIndex=2261|OwnerPartId=1|Electrical=7|PinConglomerate=56|PinLength=20|Location.X=765|Location.Y=485|Name=GND|Designator=3|PinName_PositionConglomerate=16|Name_CustomFontID=1|PinDesignator_PositionConglomerate=16|Designator_CustomFontID=1|PinPropagationDelay=0.000000E+000
|RECORD=2|OwnerIndex=2261|OwnerPartId=1|Electrical=7|PinConglomerate=56|PinLength=20|Location.X=765|Location.Y=475|Name=GND|Designator=8|PinName_PositionConglomerate=16|Name_CustomFontID=1|PinDesignator_PositionConglomerate=16|Designator_CustomFontID=1|PinPropagationDelay=0.000000E+000
|RECORD=2|OwnerIndex=2261|OwnerPartId=1|Electrical=7|PinConglomerate=56|PinLength=20|Location.X=765|Location.Y=465|Name=GND|Designator=9|PinName_PositionConglomerate=16|Name_CustomFontID=1|PinDesignator_PositionConglomerate=16|Designator_CustomFontID=1|PinPropagationDelay=0.000000E+000
|RECORD=2|OwnerIndex=2261|OwnerPartId=1|Electrical=7|PinConglomerate=56|PinLength=20|Location.X=765|Location.Y=455|Name=GND|Designator=10|PinName_PositionConglomerate=16|Name_CustomFontID=1|PinDesignator_PositionConglomerate=16|Designator_CustomFontID=1|PinPropagationDelay=0.000000E+000
|RECORD=2|OwnerIndex=2261|OwnerPartId=1|Electrical=7|PinConglomerate=56|PinLength=20|Location.X=765|Location.Y=445|Name=GND|Designator=13|PinName_PositionConglomerate=16|Name_CustomFontID=1|PinDesignator_PositionConglomerate=16|Designator_CustomFontID=1|PinPropagationDelay=0.000000E+000
|RECORD=2|OwnerIndex=2261|OwnerPartId=1|Electrical=7|PinConglomerate=56|PinLength=20|Location.X=765|Location.Y=435|Name=GND|Designator=14|PinName_PositionConglomerate=16|Name_CustomFontID=1|PinDesignator_PositionConglomerate=16|Designator_CustomFontID=1|PinPropagationDelay=0.000000E+000
|RECORD=2|OwnerIndex=2261|OwnerPartId=1|Electrical=7|PinConglomerate=56|PinLength=20|Location.X=765|Location.Y=425|Name=GND(Thermal Pad)|Designator=23|PinName_PositionConglomerate=16|Name_CustomFontID=1|PinDesignator_PositionConglomerate=16|Designator_CustomFontID=1|PinPropagationDelay=0.000000E+000
|RECORD=2|OwnerIndex=2261|OwnerPartId=1|Electrical=7|PinConglomerate=56|PinLength=20|Location.X=765|Location.Y=415|Name=GND(Thermal Pad)|Designator=15|PinName_PositionConglomerate=16|Name_CustomFontID=1|PinDesignator_PositionConglomerate=16|Designator_CustomFontID=1|PinPropagationDelay=0.000000E+000
|RECORD=2|OwnerIndex=2261|OwnerPartId=1|Electrical=7|PinConglomerate=56|PinLength=20|Location.X=765|Location.Y=405|Name=GND(Thermal Pad)|Designator=16|PinName_PositionConglomerate=16|Name_CustomFontID=1|PinDesignator_PositionConglomerate=16|Designator_CustomFontID=1|PinPropagationDelay=0.000000E+000
|RECORD=2|OwnerIndex=2261|OwnerPartId=1|Electrical=7|PinConglomerate=56|PinLength=20|Location.X=765|Location.Y=395|Name=GND(Thermal Pad)|Designator=17|PinName_PositionConglomerate=16|Name_CustomFontID=1|PinDesignator_PositionConglomerate=16|Designator_CustomFontID=1|PinPropagationDelay=0.000000E+000
|RECORD=2|OwnerIndex=2261|OwnerPartId=1|Electrical=7|PinConglomerate=56|PinLength=20|Location.X=765|Location.Y=385|Name=GND(Thermal Pad)|Designator=18|PinName_PositionConglomerate=16|Name_CustomFontID=1|PinDesignator_PositionConglomerate=16|Designator_CustomFontID=1|PinPropagationDelay=0.000000E+000
|RECORD=2|OwnerIndex=2261|OwnerPartId=1|Electrical=7|PinConglomerate=56|PinLength=20|Location.X=765|Location.Y=375|Name=GND(Thermal Pad)|Designator=19|PinName_PositionConglomerate=16|Name_CustomFontID=1|PinDesignator_PositionConglomerate=16|Designator_CustomFontID=1|PinPropagationDelay=0.000000E+000
|RECORD=2|OwnerIndex=2261|OwnerPartId=1|Electrical=7|PinConglomerate=56|PinLength=20|Location.X=765|Location.Y=365|Name=GND(Thermal Pad)|Designator=20|PinName_PositionConglomerate=16|Name_CustomFontID=1|PinDesignator_PositionConglomerate=16|Designator_CustomFontID=1|PinPropagationDelay=0.000000E+000
|RECORD=2|OwnerIndex=2261|OwnerPartId=1|Electrical=7|PinConglomerate=56|PinLength=20|Location.X=765|Location.Y=355|Name=GND(Thermal Pad)|Designator=21|PinName_PositionConglomerate=16|Name_CustomFontID=1|PinDesignator_PositionConglomerate=16|Designator_CustomFontID=1|PinPropagationDelay=0.000000E+000
|RECORD=2|OwnerIndex=2261|OwnerPartId=1|Electrical=7|PinConglomerate=56|PinLength=20|Location.X=765|Location.Y=345|Name=GND(Thermal Pad)|Designator=22|PinName_PositionConglomerate=16|Name_CustomFontID=1|PinDesignator_PositionConglomerate=16|Designator_CustomFontID=1|PinPropagationDelay=0.000000E+000
|RECORD=41|OwnerIndex=2261|IndexInSheet=24|OwnerPartId=-1|Location.X=583|Location.Y=565|Color=8388608|FontID=1|IsHidden=T|Text=1|Name=Number of Outputs
|RECORD=41|OwnerIndex=2261|IndexInSheet=25|OwnerPartId=-1|Location.X=583|Location.Y=565|Color=8388608|FontID=1|IsHidden=T|Text=6A|Name=Max Output Current
|RECORD=41|OwnerIndex=2261|IndexInSheet=26|OwnerPartId=-1|Location.X=583|Location.Y=565|Color=8388608|FontID=1|IsHidden=T|Text=95%|Name=Efficiency
|RECORD=41|OwnerIndex=2261|IndexInSheet=27|OwnerPartId=-1|Location.X=583|Location.Y=565|Color=8388608|FontID=1|IsHidden=T|Text=14V|Name=Max Input Voltage
|RECORD=41|OwnerIndex=2261|IndexInSheet=28|OwnerPartId=-1|Location.X=583|Location.Y=565|Color=8388608|FontID=1|IsHidden=T|Text=SMD/SMT|Name=Case/Package
|RECORD=41|OwnerIndex=2261|IndexInSheet=29|OwnerPartId=-1|Location.X=583|Location.Y=565|Color=8388608|FontID=1|IsHidden=T|Text=Surface Mount|Name=Mount
|RECORD=41|OwnerIndex=2261|IndexInSheet=30|OwnerPartId=-1|Location.X=583|Location.Y=565|Color=8388608|FontID=1|IsHidden=T|Text=5V|Name=Voltage - Output 1
|RECORD=41|OwnerIndex=2261|IndexInSheet=31|OwnerPartId=-1|Location.X=583|Location.Y=565|Color=8388608|FontID=1|IsHidden=T|Text=Yes|Name=RoHS Compliant
|RECORD=41|OwnerIndex=2261|IndexInSheet=32|OwnerPartId=-1|Location.X=583|Location.Y=565|Color=8388608|FontID=1|IsHidden=T|Text=Tape and Reel|Name=Packaging
|RECORD=41|OwnerIndex=2261|IndexInSheet=33|OwnerPartId=-1|Location.X=583|Location.Y=565|Color=8388608|FontID=1|IsHidden=T|Text=8V|Name=Min Input Voltage
|RECORD=41|OwnerIndex=2261|IndexInSheet=34|OwnerPartId=-1|Location.X=583|Location.Y=565|Color=8388608|FontID=1|IsHidden=T|Text=-40°C|Name=Min Operating Temperature
|RECORD=41|OwnerIndex=2261|IndexInSheet=35|OwnerPartId=-1|Location.X=583|Location.Y=565|Color=8388608|FontID=1|IsHidden=T|Text=UVLO|Name=Features
|RECORD=41|OwnerIndex=2261|IndexInSheet=36|OwnerPartId=-1|Location.X=583|Location.Y=565|Color=8388608|FontID=1|IsHidden=T|Text=85°C|Name=Max Operating Temperature
|RECORD=34|OwnerIndex=2261|IndexInSheet=-1|OwnerPartId=-1|Location.X=605|Location.Y=565|Color=8388608|FontID=1|Text=U18|Name=Designator|ReadOnlyState=1
|RECORD=41|OwnerIndex=2261|IndexInSheet=-1|OwnerPartId=1|Location.X=605|Location.Y=325|Color=8388608|FontID=1|Text=DNI_MYMGK00506ERSR|Name=Comment
|RECORD=44|OwnerIndex=2261
|RECORD=45|OwnerIndex=2324|IndexInSheet=-1|UseComponentLibrary=T|ModelName=FP-MYMGK-12-MFG|ModelType=PCBLIB|DatafileCount=1|ModelDatafileEntity0=FP-MYMGK-12-MFG|ModelDatafileKind0=PCBLib|IsCurrent=T|DatalinksLocked=T|DatabaseDatalinksLocked=T
|RECORD=46|OwnerIndex=2325
|RECORD=48|OwnerIndex=2325
|RECORD=1|LibReference=MUN12AD06-SM|ComponentDescription=No Description Available|PartCount=2|DisplayModeCount=1|IndexInSheet=130|OwnerPartId=-1|Location.X=600|Location.Y=225|CurrentPartId=1|LibraryPath=*|SourceLibraryName=MUN12AD06-SM.SchLib|TargetFileName=*|AreaColor=11599871|Color=128|PartIDLocked=T|DesignItemId=MUN12AD06-SM|AllPinCount=25
|RECORD=41|OwnerIndex=2328|OwnerPartId=1|Location.X=600|Location.Y=225|FontID=1|IsHidden=T|Text=Cyntec|Name=Mfr_Name
|RECORD=41|OwnerIndex=2328|IndexInSheet=1|OwnerPartId=1|Location.X=700|Location.Y=265|FontID=1|IsHidden=T|Text=RefDes|Name=RefDes
|RECORD=41|OwnerIndex=2328|IndexInSheet=2|OwnerPartId=1|Location.X=700|Location.Y=255|FontID=1|IsHidden=T|Text=Type|Name=Type
|RECORD=2|OwnerIndex=2328|OwnerPartId=1|FormalType=1|Electrical=7|PinConglomerate=58|PinLength=30|Location.X=630|Location.Y=225|Name=VIN|Designator=1|SwapIdPin=0|SwapIDPart=0Ž&Ž1|PinPropagationDelay=0.000000E+000
|RECORD=2|OwnerIndex=2328|OwnerPartId=1|FormalType=1|Electrical=2|PinConglomerate=58|PinLength=30|Location.X=630|Location.Y=215|Name=PHASE|Designator=2|SwapIdPin=0|SwapIDPart=0Ž&Ž2|PinPropagationDelay=0.000000E+000
|RECORD=2|OwnerIndex=2328|OwnerPartId=1|FormalType=1|Electrical=2|PinConglomerate=58|PinLength=30|Location.X=630|Location.Y=205|Name=PHASE|Designator=3|SwapIdPin=0|SwapIDPart=0Ž&Ž3|PinPropagationDelay=0.000000E+000
|RECORD=2|OwnerIndex=2328|OwnerPartId=1|FormalType=1|Electrical=2|PinConglomerate=58|PinLength=30|Location.X=630|Location.Y=195|Name=PHASE|Designator=4|SwapIdPin=0|SwapIDPart=0Ž&Ž4|PinPropagationDelay=0.000000E+000
|RECORD=2|OwnerIndex=2328|OwnerPartId=1|FormalType=1|Electrical=7|PinConglomerate=58|PinLength=30|Location.X=630|Location.Y=185|Name=GND|Designator=5|SwapIdPin=0|SwapIDPart=0Ž&Ž5|PinPropagationDelay=0.000000E+000
|RECORD=2|OwnerIndex=2328|OwnerPartId=1|FormalType=1|Electrical=7|PinConglomerate=58|PinLength=30|Location.X=630|Location.Y=175|Name=GND|Designator=6|SwapIdPin=0|SwapIDPart=0Ž&Ž6|PinPropagationDelay=0.000000E+000
|RECORD=2|OwnerIndex=2328|OwnerPartId=1|FormalType=1|Electrical=7|PinConglomerate=58|PinLength=30|Location.X=630|Location.Y=165|Name=GND|Designator=7|SwapIdPin=0|SwapIDPart=0Ž&Ž7|PinPropagationDelay=0.000000E+000
|RECORD=2|OwnerIndex=2328|OwnerPartId=1|FormalType=1|PinConglomerate=58|PinLength=30|Location.X=630|Location.Y=155|Name=EN|Designator=8|SwapIdPin=0|SwapIDPart=0Ž&Ž8|PinPropagationDelay=0.000000E+000
|RECORD=2|OwnerIndex=2328|OwnerPartId=1|FormalType=1|Electrical=2|PinConglomerate=58|PinLength=30|Location.X=630|Location.Y=145|Name=PGOOD|Designator=9|SwapIdPin=0|SwapIDPart=0Ž&Ž9|PinPropagationDelay=0.000000E+000
|RECORD=2|OwnerIndex=2328|OwnerPartId=1|FormalType=1|Electrical=2|PinConglomerate=58|PinLength=30|Location.X=630|Location.Y=135|Name=VOUT|Designator=10|SwapIdPin=0|SwapIDPart=0Ž&Ž10|PinPropagationDelay=0.000000E+000
|RECORD=2|OwnerIndex=2328|OwnerPartId=1|FormalType=1|Electrical=2|PinConglomerate=58|PinLength=30|Location.X=630|Location.Y=125|Name=VOUT|Designator=11|SwapIdPin=0|SwapIDPart=0Ž&Ž11|PinPropagationDelay=0.000000E+000
|RECORD=2|OwnerIndex=2328|OwnerPartId=1|FormalType=1|Electrical=2|PinConglomerate=58|PinLength=30|Location.X=630|Location.Y=115|Name=VOUT|Designator=12|SwapIdPin=0|SwapIDPart=0Ž&Ž12|PinPropagationDelay=0.000000E+000
|RECORD=2|OwnerIndex=2328|OwnerPartId=1|FormalType=1|Electrical=2|PinConglomerate=56|PinLength=30|Location.X=770|Location.Y=105|Name=VOUT|Designator=13|SwapIdPin=0|SwapIDPart=0Ž&Ž13|PinPropagationDelay=0.000000E+000
|RECORD=2|OwnerIndex=2328|OwnerPartId=1|FormalType=1|Electrical=2|PinConglomerate=56|PinLength=30|Location.X=770|Location.Y=115|Name=VOUT|Designator=14|SwapIdPin=0|SwapIDPart=0Ž&Ž14|PinPropagationDelay=0.000000E+000
|RECORD=2|OwnerIndex=2328|OwnerPartId=1|FormalType=1|Electrical=4|PinConglomerate=56|PinLength=30|Location.X=770|Location.Y=125|Name=ILIM|Designator=15|SwapIdPin=0|SwapIDPart=0Ž&Ž15|PinPropagationDelay=0.000000E+000
|RECORD=2|OwnerIndex=2328|OwnerPartId=1|FormalType=1|PinConglomerate=56|PinLength=30|Location.X=770|Location.Y=135|Name=FB|Designator=16|SwapIdPin=0|SwapIDPart=0Ž&Ž16|PinPropagationDelay=0.000000E+000
|RECORD=2|OwnerIndex=2328|OwnerPartId=1|FormalType=1|Electrical=7|PinConglomerate=56|PinLength=30|Location.X=770|Location.Y=145|Name=VCC|Designator=17|SwapIdPin=0|SwapIDPart=0Ž&Ž17|PinPropagationDelay=0.000000E+000
|RECORD=2|OwnerIndex=2328|OwnerPartId=1|FormalType=1|Electrical=7|PinConglomerate=56|PinLength=30|Location.X=770|Location.Y=155|Name=BST|Designator=18|SwapIdPin=0|SwapIDPart=0Ž&Ž18|PinPropagationDelay=0.000000E+000
|RECORD=2|OwnerIndex=2328|OwnerPartId=1|FormalType=1|Electrical=7|PinConglomerate=56|PinLength=30|Location.X=770|Location.Y=165|Name=VIN|Designator=19|SwapIdPin=0|SwapIDPart=0Ž&Ž19|PinPropagationDelay=0.000000E+000
|RECORD=2|OwnerIndex=2328|OwnerPartId=1|FormalType=1|Electrical=7|PinConglomerate=56|PinLength=30|Location.X=770|Location.Y=175|Name=VIN|Designator=20|SwapIdPin=0|SwapIDPart=0Ž&Ž20|PinPropagationDelay=0.000000E+000
|RECORD=2|OwnerIndex=2328|OwnerPartId=1|FormalType=1|Electrical=7|PinConglomerate=56|PinLength=30|Location.X=770|Location.Y=185|Name=VIN_TPD|Designator=21|SwapIdPin=0|SwapIDPart=0Ž&Ž21|PinPropagationDelay=0.000000E+000
|RECORD=2|OwnerIndex=2328|OwnerPartId=1|FormalType=1|Electrical=2|PinConglomerate=56|PinLength=30|Location.X=770|Location.Y=195|Name=PHASE_TPD|Designator=22|SwapIdPin=0|SwapIDPart=0Ž&Ž22|PinPropagationDelay=0.000000E+000
|RECORD=2|OwnerIndex=2328|OwnerPartId=1|FormalType=1|Electrical=7|PinConglomerate=56|PinLength=30|Location.X=770|Location.Y=205|Name=GND_TPD|Designator=23|SwapIdPin=0|SwapIDPart=0Ž&Ž23|PinPropagationDelay=0.000000E+000
|RECORD=2|OwnerIndex=2328|OwnerPartId=1|FormalType=1|Electrical=2|PinConglomerate=56|PinLength=30|Location.X=770|Location.Y=215|Name=VOUT_TPD|Designator=24|SwapIdPin=0|SwapIDPart=0Ž&Ž24|PinPropagationDelay=0.000000E+000
|RECORD=2|OwnerIndex=2328|OwnerPartId=1|FormalType=1|Electrical=7|PinConglomerate=56|PinLength=30|Location.X=770|Location.Y=225|Name=GND_TPD|Designator=25|SwapIdPin=0|SwapIDPart=0Ž&Ž25|PinPropagationDelay=0.000000E+000
|RECORD=14|OwnerIndex=2328|IsNotAccesible=T|IndexInSheet=28|OwnerPartId=1|Location.X=630|Location.Y=85|Corner.X=770|Corner.Y=245|LineWidth=1|AreaColor=11599871|IsSolid=T|Transparent=T
|RECORD=34|OwnerIndex=2328|IndexInSheet=-1|OwnerPartId=-1|Location.X=630|Location.Y=245|Color=8388608|FontID=1|Text=U24|Name=Designator|ReadOnlyState=1
|RECORD=41|OwnerIndex=2328|IndexInSheet=-1|OwnerPartId=-1|Location.X=630|Location.Y=75|Color=8388608|FontID=1|Text=MUN12AD06-SM|Name=Comment
|RECORD=44|OwnerIndex=2328
|RECORD=45|OwnerIndex=2385|IndexInSheet=-1|ModelName=MUN12AD06-SM_CYN|ModelType=PCBLIB|DatafileCount=1|ModelDatafileEntity0=MUN12AD06-SM_CYN|ModelDatafileKind0=PCBLIB|IsCurrent=T
|RECORD=46|OwnerIndex=2386
|RECORD=48|OwnerIndex=2386
|RECORD=17|IndexInSheet=131|OwnerPartId=-1|ShowNetName=T|Location.X=805|Location.Y=565|Orientation=1|Color=128|FontID=1|Text=P3V3_SENSE
|RECORD=17|IndexInSheet=132|OwnerPartId=-1|ShowNetName=T|Location.X=565|Location.Y=565|Orientation=1|Color=128|FontID=1|Text=+12V
|RECORD=17|IndexInSheet=133|OwnerPartId=-1|ShowNetName=T|Location.X=435|Location.Y=580|Orientation=1|Color=128|FontID=1|Text=+12V
|RECORD=17|IndexInSheet=134|OwnerPartId=-1|Style=4|ShowNetName=T|Location.X=800|Location.Y=335|Orientation=3|Color=128|FontID=1|Text=GND
|RECORD=1|LibReference=203bc49f2ac43e59fd269a8c329ed05|ComponentDescription=470uF 10V  ±10% 500mO 2917  SMD Tantalum Capacitor|PartCount=2|DisplayModeCount=1|IndexInSheet=135|OwnerPartId=-1|Location.X=960|Location.Y=355|CurrentPartId=1|LibraryPath=*|SourceLibraryName=Altium Content Vault|TargetFileName=*|AreaColor=11599871|Color=128|PartIDLocked=T|DesignItemId=CMP-04424-000243-1|AllPinCount=2
|RECORD=2|OwnerIndex=2393|OwnerPartId=1|Electrical=4|PinConglomerate=51|PinLength=8|Location.X=960|Location.Y=343|Name=C|Designator=1|PinPropagationDelay=0.000000E+000
|RECORD=2|OwnerIndex=2393|OwnerPartId=1|Electrical=4|PinConglomerate=49|PinLength=8|Location.X=960|Location.Y=347|Name=A|Designator=2|PinPropagationDelay=0.000000E+000
|RECORD=5|OwnerIndex=2393|IsNotAccesible=T|IndexInSheet=2|OwnerPartId=1|LineWidth=1|Color=16711680|LocationCount=4|X1=950|Y1=339|X2=955|Y2=345|X3=965|Y3=345|X4=970|Y4=339
|RECORD=13|OwnerIndex=2393|IsNotAccesible=T|IndexInSheet=3|OwnerPartId=1|Location.X=950|Location.Y=347|Corner.X=970|Corner.Y=347|LineWidth=1|Color=16711680
|RECORD=13|OwnerIndex=2393|IsNotAccesible=T|IndexInSheet=4|OwnerPartId=1|Location.X=960|Location.Y=343|Corner.X=960|Corner.Y=341|LineWidth=1|Color=16711680
|RECORD=13|OwnerIndex=2393|IsNotAccesible=T|IndexInSheet=5|OwnerPartId=1|Location.X=960|Location.Y=347|Corner.X=960|Corner.Y=350|LineWidth=1|Color=16711680
|RECORD=4|OwnerIndex=2393|IsNotAccesible=T|IndexInSheet=6|OwnerPartId=1|Location.X=949|Location.Y=357|Justification=6|Color=8388608|FontID=1|Text=+
|RECORD=41|OwnerIndex=2393|IndexInSheet=7|OwnerPartId=-1|Location.X=949|Location.Y=357|Color=8388608|FontID=1|IsHidden=T|Text=Flat|Name=Construction
|RECORD=41|OwnerIndex=2393|IndexInSheet=8|OwnerPartId=-1|Location.X=949|Location.Y=357|Color=8388608|FontID=1|IsHidden=T|Text=4.3mm|Name=Width
|RECORD=41|OwnerIndex=2393|IndexInSheet=9|OwnerPartId=-1|Location.X=949|Location.Y=357|Color=8388608|FontID=1|IsHidden=T|Text=Surface Mount|Name=Mount
|RECORD=41|OwnerIndex=2393|IndexInSheet=10|OwnerPartId=-1|Location.X=949|Location.Y=357|Color=8388608|FontID=1|IsHidden=T|Text=10%|Name=Tolerance
|RECORD=41|OwnerIndex=2393|IndexInSheet=11|OwnerPartId=-1|Location.X=949|Location.Y=357|Color=8388608|FontID=1|IsHidden=T|Text=125°C|Name=Max Operating Temperature
|RECORD=41|OwnerIndex=2393|IndexInSheet=12|OwnerPartId=-1|Location.X=949|Location.Y=357|Color=8388608|FontID=1|IsHidden=T|Text=-55°C|Name=Min Operating Temperature
|RECORD=41|OwnerIndex=2393|IndexInSheet=13|OwnerPartId=-1|Location.X=949|Location.Y=357|Color=8388608|FontID=1|IsHidden=T|Text=7.3mm|Name=Length
|RECORD=41|OwnerIndex=2393|IndexInSheet=14|OwnerPartId=-1|Location.X=949|Location.Y=357|Color=8388608|FontID=1|IsHidden=T|Text=10V|Name=Voltage
|RECORD=41|OwnerIndex=2393|IndexInSheet=15|OwnerPartId=-1|Location.X=949|Location.Y=357|Color=8388608|FontID=1|IsHidden=T|Text=10%|Name=Dissipation Factor
|RECORD=41|OwnerIndex=2393|IndexInSheet=16|OwnerPartId=-1|Location.X=949|Location.Y=357|Color=8388608|FontID=1|IsHidden=T|Text=47uA|Name=Leakage Current
|RECORD=41|OwnerIndex=2393|IndexInSheet=17|OwnerPartId=-1|Location.X=949|Location.Y=357|Color=8388608|FontID=1|IsHidden=T|Text=No SVHC|Name=REACH SVHC
|RECORD=41|OwnerIndex=2393|IndexInSheet=18|OwnerPartId=-1|Location.X=949|Location.Y=357|Color=8388608|FontID=1|IsHidden=T|Text=Lead Free|Name=Lead Free
|RECORD=41|OwnerIndex=2393|IndexInSheet=19|OwnerPartId=-1|Location.X=949|Location.Y=357|Color=8388608|FontID=1|IsHidden=T|Text=2917|Name=Case/Package
|RECORD=41|OwnerIndex=2393|IndexInSheet=20|OwnerPartId=-1|Location.X=949|Location.Y=357|Color=8388608|FontID=1|IsHidden=T|Text=10V|Name=Voltage Rating
|RECORD=41|OwnerIndex=2393|IndexInSheet=21|OwnerPartId=-1|Location.X=949|Location.Y=357|Color=8388608|FontID=1|IsHidden=T|Text=500mR|Name=ESR (Equivalent Series Resistance)
|RECORD=41|OwnerIndex=2393|IndexInSheet=22|OwnerPartId=-1|Location.X=949|Location.Y=357|Color=8388608|FontID=1|IsHidden=T|Text=470uF|Name=Capacitance
|RECORD=41|OwnerIndex=2393|IndexInSheet=23|OwnerPartId=-1|Location.X=949|Location.Y=357|Color=8388608|FontID=1|IsHidden=T|Text=TAJ|Name=Series
|RECORD=41|OwnerIndex=2393|IndexInSheet=24|OwnerPartId=-1|Location.X=949|Location.Y=357|Color=8388608|FontID=1|IsHidden=T|Text=4.1mm|Name=Height
|RECORD=41|OwnerIndex=2393|IndexInSheet=25|OwnerPartId=-1|Location.X=949|Location.Y=357|Color=8388608|FontID=1|IsHidden=T|Text=Yes|Name=RoHS Compliant
|RECORD=41|OwnerIndex=2393|IndexInSheet=26|OwnerPartId=-1|Location.X=949|Location.Y=357|Color=8388608|FontID=1|IsHidden=T|Text=Tape and Reel|Name=Packaging
|RECORD=41|OwnerIndex=2393|IndexInSheet=27|OwnerPartId=-1|Location.X=949|Location.Y=357|Color=8388608|FontID=1|IsHidden=T|Text=10V|Name=Voltage Rating (DC)
|RECORD=41|OwnerIndex=2393|IndexInSheet=28|OwnerPartId=-1|Location.X=949|Location.Y=357|Color=8388608|FontID=1|IsHidden=T|Text=No|Name=Radiation Hardening
|RECORD=41|OwnerIndex=2393|IndexInSheet=29|OwnerPartId=-1|Location.X=949|Location.Y=357|Color=8388608|FontID=1|IsHidden=T|Text=Tantalum|Name=Dielectric Material
|RECORD=41|OwnerIndex=2393|IndexInSheet=30|OwnerPartId=-1|Location.X=949|Location.Y=357|Color=8388608|FontID=1|IsHidden=T|Text=2|Name=Number of Pins
|RECORD=41|OwnerIndex=2393|IndexInSheet=31|OwnerPartId=-1|Location.X=949|Location.Y=357|Color=8388608|FontID=1|IsHidden=T|Text=4.3mm|Name=Depth
|RECORD=41|OwnerIndex=2393|IndexInSheet=32|OwnerPartId=-1|Location.X=949|Location.Y=357|Color=8388608|FontID=1|IsHidden=T|Text=7343|Name=Case Code (Metric)
|RECORD=41|OwnerIndex=2393|IndexInSheet=33|OwnerPartId=-1|Location.X=949|Location.Y=357|Color=8388608|FontID=1|IsHidden=T|Text=2917|Name=Case Code (Imperial)
|RECORD=41|OwnerIndex=2393|IndexInSheet=34|OwnerPartId=-1|Location.X=949|Location.Y=357|Color=8388608|FontID=1|IsHidden=T|Text=SMD/SMT|Name=Termination
|RECORD=41|OwnerIndex=2393|IndexInSheet=35|OwnerPartId=-1|Location.X=949|Location.Y=357|Color=8388608|FontID=1|IsHidden=T|Text=Polar|Name=Polarity
|RECORD=41|OwnerIndex=2393|IndexInSheet=36|OwnerPartId=-1|Location.X=949|Location.Y=357|Color=8388608|FontID=1|IsHidden=T|Text=4.4mm|Name=Lead Pitch
|RECORD=41|OwnerIndex=2393|IndexInSheet=37|OwnerPartId=-1|Location.X=949|Location.Y=357|Color=8388608|FontID=1|IsHidden=T|Text=General Purpose|Name=Features
|RECORD=41|OwnerIndex=2393|IndexInSheet=38|OwnerPartId=-1|Location.X=949|Location.Y=357|Color=8388608|FontID=1|IsHidden=T|Text=0.169inch|Name=Height - Seated (Max)
|RECORD=41|OwnerIndex=2393|IndexInSheet=39|OwnerPartId=-1|Location.X=949|Location.Y=357|Color=8388608|FontID=1|IsHidden=T|Text=1|Name=Package Quantity
|RECORD=34|OwnerIndex=2393|IndexInSheet=-1|OwnerPartId=-1|Location.X=945|Location.Y=335|Orientation=1|Color=8388608|FontID=2|Text=C4|Name=Designator|ReadOnlyState=1
|RECORD=41|OwnerIndex=2393|IndexInSheet=-1|OwnerPartId=1|Location.X=985|Location.Y=315|Orientation=1|Color=8388608|FontID=2|Text=470uF_10V_2917|Name=Comment
|RECORD=44|OwnerIndex=2393
|RECORD=45|OwnerIndex=2438|IndexInSheet=-1|UseComponentLibrary=T|ModelName=FP-TAJE-MFG|ModelType=PCBLIB|DatafileCount=1|ModelDatafileEntity0=FP-TAJE-MFG|ModelDatafileKind0=PCBLib|IsCurrent=T|DatalinksLocked=T|DatabaseDatalinksLocked=T
|RECORD=46|OwnerIndex=2439
|RECORD=48|OwnerIndex=2439
|RECORD=1|LibReference=RES|PartCount=2|DisplayModeCount=2|IndexInSheet=136|OwnerPartId=-1|Location.X=820|Location.Y=475|Orientation=1|CurrentPartId=1|SourceLibraryName=Altium Content Vault|TargetFileName=*|AreaColor=11599871|Color=128|PartIDLocked=F|DesignItemId=CMP-2002-05848-1|AllPinCount=2
|RECORD=2|OwnerIndex=2442|OwnerPartId=1|OwnerPartDisplayMode=1|FormalType=1|Electrical=4|PinConglomerate=33|PinLength=10|Location.X=830|Location.Y=495|Name=2|Designator=2|PinPropagationDelay=0.000000E+000
|RECORD=2|OwnerIndex=2442|OwnerPartId=1|OwnerPartDisplayMode=1|FormalType=1|Electrical=4|PinConglomerate=35|PinLength=10|Location.X=830|Location.Y=475|Name=1|Designator=1|PinPropagationDelay=0.000000E+000
|RECORD=14|OwnerIndex=2442|IsNotAccesible=T|IndexInSheet=2|OwnerPartId=1|OwnerPartDisplayMode=1|Location.X=826|Location.Y=475|Corner.X=834|Corner.Y=495|LineWidth=1|Color=16711680|AreaColor=11599871
|RECORD=2|OwnerIndex=2442|OwnerPartId=1|FormalType=1|Electrical=4|PinConglomerate=33|PinLength=10|Location.X=830|Location.Y=495|Name=2|Designator=2|PinPropagationDelay=0.000000E+000
|RECORD=2|OwnerIndex=2442|OwnerPartId=1|FormalType=1|Electrical=4|PinConglomerate=35|PinLength=10|Location.X=830|Location.Y=475|Name=1|Designator=1|PinPropagationDelay=0.000000E+000
|RECORD=6|OwnerIndex=2442|IsNotAccesible=T|IndexInSheet=5|OwnerPartId=1|LineWidth=1|Color=16711680|LocationCount=10|X1=830|Y1=495|X2=830|Y2=491|X3=832|Y3=490|X4=828|Y4=488|X5=832|Y5=486|X6=828|Y6=484|X7=832|Y7=482|X8=828|Y8=480|X9=830|Y9=479|X10=830|Y10=475
|RECORD=41|OwnerIndex=2442|IndexInSheet=6|OwnerPartId=-1|Location.X=827|Location.Y=507|Color=8388608|FontID=1|IsHidden=T|Text=ERA-2AED222X|Name=Part Number
|RECORD=41|OwnerIndex=2442|IndexInSheet=7|OwnerPartId=-1|Location.X=827|Location.Y=507|Color=8388608|FontID=1|IsHidden=T|Text=Panasonic|Name=Manufacturer
|RECORD=34|OwnerIndex=2442|IndexInSheet=-1|OwnerPartId=-1|Location.X=833|Location.Y=486|Color=8388608|FontID=1|Text=R61|Name=Designator|ReadOnlyState=1
|RECORD=41|OwnerIndex=2442|IndexInSheet=-1|OwnerPartId=-1|Location.X=833|Location.Y=476|Color=8388608|FontID=1|Text=2.2K_0.5%_0402|Name=Comment
|RECORD=44|OwnerIndex=2442
|RECORD=45|OwnerIndex=2457|IndexInSheet=-1|Description=Chip Resistor, 2-Leads, Body 1.00x0.50mm, IPC Low Density|UseComponentLibrary=T|ModelName=RESC1005X40X25ML10T10|ModelType=PCBLIB|DatafileCount=1|ModelDatafileEntity0=RESC1005X40X25ML10T10|ModelDatafileKind0=PCBLib|IsCurrent=T|DatalinksLocked=T|DatabaseDatalinksLocked=T
|RECORD=46|OwnerIndex=2458
|RECORD=48|OwnerIndex=2458
|RECORD=41|OwnerIndex=2460|IndexInSheet=-1|OwnerPartId=-1|Color=8388608|FontID=1|IsHidden=T|Text=2D|Name=Available Preview Images
|RECORD=45|OwnerIndex=2457|IndexInSheet=-1|Description=Chip Resistor, 2-Leads, Body 1.00x0.50mm, IPC High Density|UseComponentLibrary=T|ModelName=RESC1005X40X25LL10T10|ModelType=PCBLIB|DatafileCount=1|ModelDatafileEntity0=RESC1005X40X25LL10T10|ModelDatafileKind0=PCBLib|DatalinksLocked=T|DatabaseDatalinksLocked=T
|RECORD=46|OwnerIndex=2462
|RECORD=48|OwnerIndex=2462
|RECORD=41|OwnerIndex=2464|IndexInSheet=-1|OwnerPartId=-1|Color=8388608|FontID=1|IsHidden=T|Text=2D|Name=Available Preview Images
|RECORD=45|OwnerIndex=2457|IndexInSheet=-1|Description=Chip Resistor, 2-Leads, Body 1.00x0.50mm, IPC Medium Density|UseComponentLibrary=T|ModelName=RESC1005X40X25NL10T10|ModelType=PCBLIB|DatafileCount=1|ModelDatafileEntity0=RESC1005X40X25NL10T10|ModelDatafileKind0=PCBLib|DatalinksLocked=T|DatabaseDatalinksLocked=T
|RECORD=46|OwnerIndex=2466
|RECORD=48|OwnerIndex=2466
|RECORD=41|OwnerIndex=2468|IndexInSheet=-1|OwnerPartId=-1|Color=8388608|FontID=1|IsHidden=T|Text=2D|Name=Available Preview Images
|RECORD=1|LibReference=1029c3af85768c4190bb7ad29bc67b5|ComponentDescription=Automotive Metal Thin Film Chip Resistor, 0402, 22O, 0.5%, 100ppm/°C, 0.0625W, 75V|PartCount=2|DisplayModeCount=1|IndexInSheet=137|OwnerPartId=-1|Location.X=830|Location.Y=385|Orientation=1|CurrentPartId=1|LibraryPath=*|SourceLibraryName=Altium Content Vault|TargetFileName=*|AreaColor=11599871|Color=128|PartIDLocked=T|DesignItemId=CMP-2002-01415-2|AllPinCount=2
|RECORD=2|OwnerIndex=2470|OwnerPartId=1|Electrical=4|PinConglomerate=51|PinLength=20|Location.X=830|Location.Y=405|Name=1|Designator=1|PinPropagationDelay=0.000000E+000
|RECORD=2|OwnerIndex=2470|OwnerPartId=1|Electrical=4|PinConglomerate=49|PinLength=20|Location.X=830|Location.Y=435|Name=2|Designator=2|PinPropagationDelay=0.000000E+000
|RECORD=13|OwnerIndex=2470|IsNotAccesible=T|IndexInSheet=2|OwnerPartId=1|Location.X=830|Location.Y=405|Corner.X=825|Corner.Y=408|LineWidth=1|Color=16711680
|RECORD=13|OwnerIndex=2470|IsNotAccesible=T|IndexInSheet=3|OwnerPartId=1|Location.X=825|Location.Y=408|Corner.X=835|Corner.Y=413|LineWidth=1|Color=16711680
|RECORD=13|OwnerIndex=2470|IsNotAccesible=T|IndexInSheet=4|OwnerPartId=1|Location.X=835|Location.Y=413|Corner.X=825|Corner.Y=418|LineWidth=1|Color=16711680
|RECORD=13|OwnerIndex=2470|IsNotAccesible=T|IndexInSheet=5|OwnerPartId=1|Location.X=825|Location.Y=418|Corner.X=835|Corner.Y=423|LineWidth=1|Color=16711680
|RECORD=13|OwnerIndex=2470|IsNotAccesible=T|IndexInSheet=6|OwnerPartId=1|Location.X=835|Location.Y=423|Corner.X=825|Corner.Y=428|LineWidth=1|Color=16711680
|RECORD=13|OwnerIndex=2470|IsNotAccesible=T|IndexInSheet=7|OwnerPartId=1|Location.X=825|Location.Y=428|Corner.X=835|Corner.Y=433|LineWidth=1|Color=16711680
|RECORD=13|OwnerIndex=2470|IsNotAccesible=T|IndexInSheet=8|OwnerPartId=1|Location.X=835|Location.Y=433|Corner.X=830|Corner.Y=435|LineWidth=1|Color=16711680
|RECORD=13|OwnerIndex=2470|IsNotAccesible=T|IndexInSheet=9|OwnerPartId=1|Location.X=830|Location.Y=405|Corner.X=830|Corner.Y=402|LineWidth=1|Color=16711680
|RECORD=13|OwnerIndex=2470|IsNotAccesible=T|IndexInSheet=10|OwnerPartId=1|Location.X=830|Location.Y=435|Corner.X=830|Corner.Y=438|LineWidth=1|Color=16711680
|RECORD=41|OwnerIndex=2470|IndexInSheet=11|OwnerPartId=-1|Location.X=824|Location.Y=457|Color=8388608|FontID=1|IsHidden=T|Text=100ppm/°C|Name=Temperature Coefficient
|RECORD=41|OwnerIndex=2470|IndexInSheet=12|OwnerPartId=-1|Location.X=824|Location.Y=457|Color=8388608|FontID=1|IsHidden=T|Text=Yes|Name=RoHS Compliant
|RECORD=41|OwnerIndex=2470|IndexInSheet=13|OwnerPartId=-1|Location.X=824|Location.Y=457|Color=8388608|FontID=1|IsHidden=T|Text=75V|Name=Voltage Rating
|RECORD=41|OwnerIndex=2470|IndexInSheet=14|OwnerPartId=-1|Location.X=824|Location.Y=457|Color=8388608|FontID=1|IsHidden=T|Text=0.016inch|Name=Height
|RECORD=41|OwnerIndex=2470|IndexInSheet=15|OwnerPartId=-1|Location.X=824|Location.Y=457|Color=8388608|FontID=1|IsHidden=T|Text=25V|Name=Voltage Rating (DC)
|RECORD=41|OwnerIndex=2470|IndexInSheet=16|OwnerPartId=-1|Location.X=824|Location.Y=457|Color=8388608|FontID=1|IsHidden=T|Text=Lead Free|Name=Lead Free
|RECORD=41|OwnerIndex=2470|IndexInSheet=17|OwnerPartId=-1|Location.X=824|Location.Y=457|Color=8388608|FontID=1|IsHidden=T|Text=Tape and Reel|Name=Packaging
|RECORD=41|OwnerIndex=2470|IndexInSheet=18|OwnerPartId=-1|Location.X=824|Location.Y=457|Color=8388608|FontID=1|IsHidden=T|Text=SMD/SMT|Name=Termination
|RECORD=41|OwnerIndex=2470|IndexInSheet=19|OwnerPartId=-1|Location.X=824|Location.Y=457|Color=8388608|FontID=1|IsHidden=T|Text=63mW|Name=Max Power Dissipation
|RECORD=41|OwnerIndex=2470|IndexInSheet=20|OwnerPartId=-1|Location.X=824|Location.Y=457|Color=8388608|FontID=1|IsHidden=T|Text=0.039inch|Name=Length
|RECORD=41|OwnerIndex=2470|IndexInSheet=21|OwnerPartId=-1|Location.X=824|Location.Y=457|Color=8388608|FontID=1|IsHidden=T|Text=1|Name=Package Quantity
|RECORD=41|OwnerIndex=2470|IndexInSheet=22|OwnerPartId=-1|Location.X=824|Location.Y=457|Color=8388608|FontID=1|IsHidden=T|Text=2.3E-05oz|Name=Weight
|RECORD=41|OwnerIndex=2470|IndexInSheet=23|OwnerPartId=-1|Location.X=824|Location.Y=457|Color=8388608|FontID=1|IsHidden=T|Text=0402|Name=Case/Package
|RECORD=41|OwnerIndex=2470|IndexInSheet=24|OwnerPartId=-1|Location.X=824|Location.Y=457|Color=8388608|FontID=1|IsHidden=T|Text=63mW|Name=Power Rating
|RECORD=41|OwnerIndex=2470|IndexInSheet=25|OwnerPartId=-1|Location.X=824|Location.Y=457|Color=8388608|FontID=1|IsHidden=T|Text=1005|Name=Case Code (Metric)
|RECORD=41|OwnerIndex=2470|IndexInSheet=26|OwnerPartId=-1|Location.X=824|Location.Y=457|Color=8388608|FontID=1|IsHidden=T|Text=155°C|Name=Max Operating Temperature
|RECORD=41|OwnerIndex=2470|IndexInSheet=27|OwnerPartId=-1|Location.X=824|Location.Y=457|Color=8388608|FontID=1|IsHidden=T|Text=RG|Name=Series
|RECORD=41|OwnerIndex=2470|IndexInSheet=28|OwnerPartId=-1|Location.X=824|Location.Y=457|Color=8388608|FontID=1|IsHidden=T|Text=0.02inch|Name=Width
|RECORD=41|OwnerIndex=2470|IndexInSheet=29|OwnerPartId=-1|Location.X=824|Location.Y=457|Color=8388608|FontID=1|IsHidden=T|Text=2|Name=Number of Terminations
|RECORD=41|OwnerIndex=2470|IndexInSheet=30|OwnerPartId=-1|Location.X=824|Location.Y=457|Color=8388608|FontID=1|IsHidden=T|Text=Automotive AEC-Q200|Name=Features
|RECORD=41|OwnerIndex=2470|IndexInSheet=31|OwnerPartId=-1|Location.X=824|Location.Y=457|Color=8388608|FontID=1|IsHidden=T|Text=22R|Name=Resistance
|RECORD=41|OwnerIndex=2470|IndexInSheet=32|OwnerPartId=-1|Location.X=824|Location.Y=457|Color=8388608|FontID=1|IsHidden=T|Text=-55°C|Name=Min Operating Temperature
|RECORD=41|OwnerIndex=2470|IndexInSheet=33|OwnerPartId=-1|Location.X=824|Location.Y=457|Color=8388608|FontID=1|IsHidden=T|Text=0402|Name=Case Code (Imperial)
|RECORD=41|OwnerIndex=2470|IndexInSheet=34|OwnerPartId=-1|Location.X=824|Location.Y=457|Color=8388608|FontID=1|IsHidden=T|Text=0.5%|Name=Tolerance
|RECORD=41|OwnerIndex=2470|IndexInSheet=35|OwnerPartId=-1|Location.X=824|Location.Y=457|Color=8388608|FontID=1|IsHidden=T|Text=Thin Film|Name=Resistor Type
|RECORD=34|OwnerIndex=2470|IndexInSheet=-1|OwnerPartId=-1|Location.X=836|Location.Y=429|Color=8388608|FontID=1|Text=R63|Name=Designator|ReadOnlyState=1
|RECORD=41|OwnerIndex=2470|IndexInSheet=-1|OwnerPartId=1|Location.X=836|Location.Y=419|Color=8388608|FontID=1|Text=22_0.5%_0402|Name=Comment
|RECORD=44|OwnerIndex=2470
|RECORD=45|OwnerIndex=2511|IndexInSheet=-1|UseComponentLibrary=T|ModelName=FP-RG1005-IPC_A|ModelType=PCBLIB|DatafileCount=1|ModelDatafileEntity0=FP-RG1005-IPC_A|ModelDatafileKind0=PCBLib|IsCurrent=T|DatalinksLocked=T|DatabaseDatalinksLocked=T
|RECORD=46|OwnerIndex=2512
|RECORD=48|OwnerIndex=2512
|RECORD=45|OwnerIndex=2511|IndexInSheet=-1|UseComponentLibrary=T|ModelName=FP-RG1005-IPC_C|ModelType=PCBLIB|DatafileCount=1|ModelDatafileEntity0=FP-RG1005-IPC_C|ModelDatafileKind0=PCBLib|DatalinksLocked=T|DatabaseDatalinksLocked=T
|RECORD=46|OwnerIndex=2515
|RECORD=48|OwnerIndex=2515
|RECORD=45|OwnerIndex=2511|IndexInSheet=-1|UseComponentLibrary=T|ModelName=FP-RG1005-IPC_B|ModelType=PCBLIB|DatafileCount=1|ModelDatafileEntity0=FP-RG1005-IPC_B|ModelDatafileKind0=PCBLib|DatalinksLocked=T|DatabaseDatalinksLocked=T
|RECORD=46|OwnerIndex=2518
|RECORD=48|OwnerIndex=2518
|RECORD=45|OwnerIndex=2511|IndexInSheet=-1|UseComponentLibrary=T|ModelName=FP-RG1005-MFG|ModelType=PCBLIB|DatafileCount=1|ModelDatafileEntity0=FP-RG1005-MFG|ModelDatafileKind0=PCBLib|DatalinksLocked=T|DatabaseDatalinksLocked=T
|RECORD=46|OwnerIndex=2521
|RECORD=48|OwnerIndex=2521
|RECORD=1|LibReference=57b8017c1ce60d7b1362a625e7a4ba1|ComponentDescription=DC DC CONVERTER 0.7-5V|PartCount=2|DisplayModeCount=1|IndexInSheet=138|OwnerPartId=-1|Location.X=895|Location.Y=740|CurrentPartId=1|LibraryPath=*|SourceLibraryName=Altium Content Vault|TargetFileName=*|AreaColor=11599871|Color=128|PartIDLocked=T|DesignItemId=CMP-20596-000049-1|AllPinCount=23|ComponentKindVersion2=5
|RECORD=14|OwnerIndex=2524|IsNotAccesible=T|OwnerPartId=1|Location.X=915|Location.Y=520|Corner.X=1075|Corner.Y=750|LineWidth=1|Color=128|AreaColor=11599871|IsSolid=T
|RECORD=2|OwnerIndex=2524|OwnerPartId=1|Electrical=7|PinConglomerate=58|PinLength=20|Location.X=915|Location.Y=740|Name=Vin|Designator=1|PinName_PositionConglomerate=16|Name_CustomFontID=1|PinDesignator_PositionConglomerate=16|Designator_CustomFontID=1|PinPropagationDelay=0.000000E+000
|RECORD=2|OwnerIndex=2524|OwnerPartId=1|Electrical=7|PinConglomerate=58|PinLength=20|Location.X=915|Location.Y=730|Name=Vin|Designator=2|PinName_PositionConglomerate=16|Name_CustomFontID=1|PinDesignator_PositionConglomerate=16|Designator_CustomFontID=1|PinPropagationDelay=0.000000E+000
|RECORD=2|OwnerIndex=2524|OwnerPartId=1|Electrical=7|PinConglomerate=56|PinLength=20|Location.X=1075|Location.Y=740|Name=Vout|Designator=6|PinName_PositionConglomerate=16|Name_CustomFontID=1|PinDesignator_PositionConglomerate=16|Designator_CustomFontID=1|PinPropagationDelay=0.000000E+000
|RECORD=2|OwnerIndex=2524|OwnerPartId=1|Electrical=7|PinConglomerate=56|PinLength=20|Location.X=1075|Location.Y=730|Name=Vout|Designator=7|PinName_PositionConglomerate=16|Name_CustomFontID=1|PinDesignator_PositionConglomerate=16|Designator_CustomFontID=1|PinPropagationDelay=0.000000E+000
|RECORD=2|OwnerIndex=2524|OwnerPartId=1|PinConglomerate=58|PinLength=20|Location.X=915|Location.Y=710|Name=ON/OFF|Designator=12|PinName_PositionConglomerate=16|Name_CustomFontID=1|PinDesignator_PositionConglomerate=16|Designator_CustomFontID=1|PinPropagationDelay=0.000000E+000
|RECORD=2|OwnerIndex=2524|OwnerPartId=1|Electrical=3|PinConglomerate=58|PinLength=20|Location.X=915|Location.Y=690|Name=PWGOOD|Designator=11|PinName_PositionConglomerate=16|Name_CustomFontID=1|PinDesignator_PositionConglomerate=16|Designator_CustomFontID=1|PinPropagationDelay=0.000000E+000
|RECORD=2|OwnerIndex=2524|OwnerPartId=1|Electrical=4|PinConglomerate=56|PinLength=20|Location.X=1075|Location.Y=710|Name=Sense|Designator=5|PinName_PositionConglomerate=16|Name_CustomFontID=1|PinDesignator_PositionConglomerate=16|Designator_CustomFontID=1|PinPropagationDelay=0.000000E+000
|RECORD=2|OwnerIndex=2524|OwnerPartId=1|Electrical=4|PinConglomerate=56|PinLength=20|Location.X=1075|Location.Y=690|Name=Trim|Designator=4|PinName_PositionConglomerate=16|Name_CustomFontID=1|PinDesignator_PositionConglomerate=16|Designator_CustomFontID=1|PinPropagationDelay=0.000000E+000
|RECORD=2|OwnerIndex=2524|OwnerPartId=1|Electrical=7|PinConglomerate=56|PinLength=20|Location.X=1075|Location.Y=670|Name=GND|Designator=3|PinName_PositionConglomerate=16|Name_CustomFontID=1|PinDesignator_PositionConglomerate=16|Designator_CustomFontID=1|PinPropagationDelay=0.000000E+000
|RECORD=2|OwnerIndex=2524|OwnerPartId=1|Electrical=7|PinConglomerate=56|PinLength=20|Location.X=1075|Location.Y=660|Name=GND|Designator=8|PinName_PositionConglomerate=16|Name_CustomFontID=1|PinDesignator_PositionConglomerate=16|Designator_CustomFontID=1|PinPropagationDelay=0.000000E+000
|RECORD=2|OwnerIndex=2524|OwnerPartId=1|Electrical=7|PinConglomerate=56|PinLength=20|Location.X=1075|Location.Y=650|Name=GND|Designator=9|PinName_PositionConglomerate=16|Name_CustomFontID=1|PinDesignator_PositionConglomerate=16|Designator_CustomFontID=1|PinPropagationDelay=0.000000E+000
|RECORD=2|OwnerIndex=2524|OwnerPartId=1|Electrical=7|PinConglomerate=56|PinLength=20|Location.X=1075|Location.Y=640|Name=GND|Designator=10|PinName_PositionConglomerate=16|Name_CustomFontID=1|PinDesignator_PositionConglomerate=16|Designator_CustomFontID=1|PinPropagationDelay=0.000000E+000
|RECORD=2|OwnerIndex=2524|OwnerPartId=1|Electrical=7|PinConglomerate=56|PinLength=20|Location.X=1075|Location.Y=630|Name=GND|Designator=13|PinName_PositionConglomerate=16|Name_CustomFontID=1|PinDesignator_PositionConglomerate=16|Designator_CustomFontID=1|PinPropagationDelay=0.000000E+000
|RECORD=2|OwnerIndex=2524|OwnerPartId=1|Electrical=7|PinConglomerate=56|PinLength=20|Location.X=1075|Location.Y=620|Name=GND|Designator=14|PinName_PositionConglomerate=16|Name_CustomFontID=1|PinDesignator_PositionConglomerate=16|Designator_CustomFontID=1|PinPropagationDelay=0.000000E+000
|RECORD=2|OwnerIndex=2524|OwnerPartId=1|Electrical=7|PinConglomerate=56|PinLength=20|Location.X=1075|Location.Y=610|Name=GND(Thermal Pad)|Designator=23|PinName_PositionConglomerate=16|Name_CustomFontID=1|PinDesignator_PositionConglomerate=16|Designator_CustomFontID=1|PinPropagationDelay=0.000000E+000
|RECORD=2|OwnerIndex=2524|OwnerPartId=1|Electrical=7|PinConglomerate=56|PinLength=20|Location.X=1075|Location.Y=600|Name=GND(Thermal Pad)|Designator=15|PinName_PositionConglomerate=16|Name_CustomFontID=1|PinDesignator_PositionConglomerate=16|Designator_CustomFontID=1|PinPropagationDelay=0.000000E+000
|RECORD=2|OwnerIndex=2524|OwnerPartId=1|Electrical=7|PinConglomerate=56|PinLength=20|Location.X=1075|Location.Y=590|Name=GND(Thermal Pad)|Designator=16|PinName_PositionConglomerate=16|Name_CustomFontID=1|PinDesignator_PositionConglomerate=16|Designator_CustomFontID=1|PinPropagationDelay=0.000000E+000
|RECORD=2|OwnerIndex=2524|OwnerPartId=1|Electrical=7|PinConglomerate=56|PinLength=20|Location.X=1075|Location.Y=580|Name=GND(Thermal Pad)|Designator=17|PinName_PositionConglomerate=16|Name_CustomFontID=1|PinDesignator_PositionConglomerate=16|Designator_CustomFontID=1|PinPropagationDelay=0.000000E+000
|RECORD=2|OwnerIndex=2524|OwnerPartId=1|Electrical=7|PinConglomerate=56|PinLength=20|Location.X=1075|Location.Y=570|Name=GND(Thermal Pad)|Designator=18|PinName_PositionConglomerate=16|Name_CustomFontID=1|PinDesignator_PositionConglomerate=16|Designator_CustomFontID=1|PinPropagationDelay=0.000000E+000
|RECORD=2|OwnerIndex=2524|OwnerPartId=1|Electrical=7|PinConglomerate=56|PinLength=20|Location.X=1075|Location.Y=560|Name=GND(Thermal Pad)|Designator=19|PinName_PositionConglomerate=16|Name_CustomFontID=1|PinDesignator_PositionConglomerate=16|Designator_CustomFontID=1|PinPropagationDelay=0.000000E+000
|RECORD=2|OwnerIndex=2524|OwnerPartId=1|Electrical=7|PinConglomerate=56|PinLength=20|Location.X=1075|Location.Y=550|Name=GND(Thermal Pad)|Designator=20|PinName_PositionConglomerate=16|Name_CustomFontID=1|PinDesignator_PositionConglomerate=16|Designator_CustomFontID=1|PinPropagationDelay=0.000000E+000
|RECORD=2|OwnerIndex=2524|OwnerPartId=1|Electrical=7|PinConglomerate=56|PinLength=20|Location.X=1075|Location.Y=540|Name=GND(Thermal Pad)|Designator=21|PinName_PositionConglomerate=16|Name_CustomFontID=1|PinDesignator_PositionConglomerate=16|Designator_CustomFontID=1|PinPropagationDelay=0.000000E+000
|RECORD=2|OwnerIndex=2524|OwnerPartId=1|Electrical=7|PinConglomerate=56|PinLength=20|Location.X=1075|Location.Y=530|Name=GND(Thermal Pad)|Designator=22|PinName_PositionConglomerate=16|Name_CustomFontID=1|PinDesignator_PositionConglomerate=16|Designator_CustomFontID=1|PinPropagationDelay=0.000000E+000
|RECORD=41|OwnerIndex=2524|IndexInSheet=24|OwnerPartId=-1|Location.X=893|Location.Y=750|Color=8388608|FontID=1|IsHidden=T|Text=1|Name=Number of Outputs
|RECORD=41|OwnerIndex=2524|IndexInSheet=25|OwnerPartId=-1|Location.X=893|Location.Y=750|Color=8388608|FontID=1|IsHidden=T|Text=6A|Name=Max Output Current
|RECORD=41|OwnerIndex=2524|IndexInSheet=26|OwnerPartId=-1|Location.X=893|Location.Y=750|Color=8388608|FontID=1|IsHidden=T|Text=95%|Name=Efficiency
|RECORD=41|OwnerIndex=2524|IndexInSheet=27|OwnerPartId=-1|Location.X=893|Location.Y=750|Color=8388608|FontID=1|IsHidden=T|Text=14V|Name=Max Input Voltage
|RECORD=41|OwnerIndex=2524|IndexInSheet=28|OwnerPartId=-1|Location.X=893|Location.Y=750|Color=8388608|FontID=1|IsHidden=T|Text=SMD/SMT|Name=Case/Package
|RECORD=41|OwnerIndex=2524|IndexInSheet=29|OwnerPartId=-1|Location.X=893|Location.Y=750|Color=8388608|FontID=1|IsHidden=T|Text=Surface Mount|Name=Mount
|RECORD=41|OwnerIndex=2524|IndexInSheet=30|OwnerPartId=-1|Location.X=893|Location.Y=750|Color=8388608|FontID=1|IsHidden=T|Text=5V|Name=Voltage - Output 1
|RECORD=41|OwnerIndex=2524|IndexInSheet=31|OwnerPartId=-1|Location.X=893|Location.Y=750|Color=8388608|FontID=1|IsHidden=T|Text=Yes|Name=RoHS Compliant
|RECORD=41|OwnerIndex=2524|IndexInSheet=32|OwnerPartId=-1|Location.X=893|Location.Y=750|Color=8388608|FontID=1|IsHidden=T|Text=Tape and Reel|Name=Packaging
|RECORD=41|OwnerIndex=2524|IndexInSheet=33|OwnerPartId=-1|Location.X=893|Location.Y=750|Color=8388608|FontID=1|IsHidden=T|Text=8V|Name=Min Input Voltage
|RECORD=41|OwnerIndex=2524|IndexInSheet=34|OwnerPartId=-1|Location.X=893|Location.Y=750|Color=8388608|FontID=1|IsHidden=T|Text=-40°C|Name=Min Operating Temperature
|RECORD=41|OwnerIndex=2524|IndexInSheet=35|OwnerPartId=-1|Location.X=893|Location.Y=750|Color=8388608|FontID=1|IsHidden=T|Text=UVLO|Name=Features
|RECORD=41|OwnerIndex=2524|IndexInSheet=36|OwnerPartId=-1|Location.X=893|Location.Y=750|Color=8388608|FontID=1|IsHidden=T|Text=85°C|Name=Max Operating Temperature
|RECORD=34|OwnerIndex=2524|IndexInSheet=-1|OwnerPartId=-1|Location.X=915|Location.Y=750|Color=8388608|FontID=1|Text=U5|Name=Designator|ReadOnlyState=1
|RECORD=41|OwnerIndex=2524|IndexInSheet=-1|OwnerPartId=1|Location.X=915|Location.Y=510|Color=8388608|FontID=1|Text=DNI_MYMGK00506ERSR|Name=Comment
|RECORD=44|OwnerIndex=2524
|RECORD=45|OwnerIndex=2587|IndexInSheet=-1|UseComponentLibrary=T|ModelName=FP-MYMGK-12-MFG|ModelType=PCBLIB|DatafileCount=1|ModelDatafileEntity0=FP-MYMGK-12-MFG|ModelDatafileKind0=PCBLib|IsCurrent=T|DatalinksLocked=T|DatabaseDatalinksLocked=T
|RECORD=46|OwnerIndex=2588
|RECORD=48|OwnerIndex=2588
|RECORD=17|IndexInSheet=139|OwnerPartId=-1|ShowNetName=T|Location.X=1115|Location.Y=750|Orientation=1|Color=128|FontID=1|Text=P5V_SENSE
|RECORD=17|IndexInSheet=140|OwnerPartId=-1|ShowNetName=T|Location.X=875|Location.Y=750|Orientation=1|Color=128|FontID=1|Text=+12V
|RECORD=17|IndexInSheet=141|OwnerPartId=-1|ShowNetName=T|Location.X=725|Location.Y=735|Orientation=1|Color=128|FontID=1|Text=+12V
|RECORD=17|IndexInSheet=142|OwnerPartId=-1|Style=4|ShowNetName=T|Location.X=1110|Location.Y=520|Orientation=3|Color=128|FontID=1|Text=GND
|RECORD=1|LibReference=RES|PartCount=2|DisplayModeCount=2|IndexInSheet=143|OwnerPartId=-1|Location.X=1130|Location.Y=660|Orientation=1|CurrentPartId=1|SourceLibraryName=Altium Content Vault|TargetFileName=*|AreaColor=11599871|Color=128|PartIDLocked=F|DesignItemId=CMP-2002-05839-1|AllPinCount=2
|RECORD=2|OwnerIndex=2595|OwnerPartId=1|OwnerPartDisplayMode=1|FormalType=1|Electrical=4|PinConglomerate=33|PinLength=10|Location.X=1140|Location.Y=680|Name=2|Designator=2|PinPropagationDelay=0.000000E+000
|RECORD=2|OwnerIndex=2595|OwnerPartId=1|OwnerPartDisplayMode=1|FormalType=1|Electrical=4|PinConglomerate=35|PinLength=10|Location.X=1140|Location.Y=660|Name=1|Designator=1|PinPropagationDelay=0.000000E+000
|RECORD=14|OwnerIndex=2595|IsNotAccesible=T|IndexInSheet=2|OwnerPartId=1|OwnerPartDisplayMode=1|Location.X=1136|Location.Y=660|Corner.X=1144|Corner.Y=680|LineWidth=1|Color=16711680|AreaColor=11599871
|RECORD=2|OwnerIndex=2595|OwnerPartId=1|FormalType=1|Electrical=4|PinConglomerate=33|PinLength=10|Location.X=1140|Location.Y=680|Name=2|Designator=2|PinPropagationDelay=0.000000E+000
|RECORD=2|OwnerIndex=2595|OwnerPartId=1|FormalType=1|Electrical=4|PinConglomerate=35|PinLength=10|Location.X=1140|Location.Y=660|Name=1|Designator=1|PinPropagationDelay=0.000000E+000
|RECORD=6|OwnerIndex=2595|IsNotAccesible=T|IndexInSheet=5|OwnerPartId=1|LineWidth=1|Color=16711680|LocationCount=10|X1=1140|Y1=680|X2=1140|Y2=676|X3=1142|Y3=675|X4=1138|Y4=673|X5=1142|Y5=671|X6=1138|Y6=669|X7=1142|Y7=667|X8=1138|Y8=665|X9=1140|Y9=664|X10=1140|Y10=660
|RECORD=41|OwnerIndex=2595|IndexInSheet=6|OwnerPartId=-1|Location.X=1137|Location.Y=692|Color=8388608|FontID=1|IsHidden=T|Text=ERA-2AED122X|Name=Part Number
|RECORD=41|OwnerIndex=2595|IndexInSheet=7|OwnerPartId=-1|Location.X=1137|Location.Y=692|Color=8388608|FontID=1|IsHidden=T|Text=Panasonic|Name=Manufacturer
|RECORD=34|OwnerIndex=2595|IndexInSheet=-1|OwnerPartId=-1|Location.X=1143|Location.Y=671|Color=8388608|FontID=1|Text=R26|Name=Designator|ReadOnlyState=1
|RECORD=41|OwnerIndex=2595|IndexInSheet=-1|OwnerPartId=-1|Location.X=1143|Location.Y=661|Color=8388608|FontID=1|Text=1.2K_0.5%_0402|Name=Comment
|RECORD=44|OwnerIndex=2595
|RECORD=45|OwnerIndex=2610|IndexInSheet=-1|Description=Chip Resistor, 2-Leads, Body 1.00x0.50mm, IPC Low Density|UseComponentLibrary=T|ModelName=RESC1005X40X25ML10T10|ModelType=PCBLIB|DatafileCount=1|ModelDatafileEntity0=RESC1005X40X25ML10T10|ModelDatafileKind0=PCBLib|IsCurrent=T|DatalinksLocked=T|DatabaseDatalinksLocked=T
|RECORD=46|OwnerIndex=2611
|RECORD=48|OwnerIndex=2611
|RECORD=41|OwnerIndex=2613|IndexInSheet=-1|OwnerPartId=-1|Color=8388608|FontID=1|IsHidden=T|Text=2D|Name=Available Preview Images
|RECORD=45|OwnerIndex=2610|IndexInSheet=-1|Description=Chip Resistor, 2-Leads, Body 1.00x0.50mm, IPC High Density|UseComponentLibrary=T|ModelName=RESC1005X40X25LL10T10|ModelType=PCBLIB|DatafileCount=1|ModelDatafileEntity0=RESC1005X40X25LL10T10|ModelDatafileKind0=PCBLib|DatalinksLocked=T|DatabaseDatalinksLocked=T
|RECORD=46|OwnerIndex=2615
|RECORD=48|OwnerIndex=2615
|RECORD=41|OwnerIndex=2617|IndexInSheet=-1|OwnerPartId=-1|Color=8388608|FontID=1|IsHidden=T|Text=2D|Name=Available Preview Images
|RECORD=45|OwnerIndex=2610|IndexInSheet=-1|Description=Chip Resistor, 2-Leads, Body 1.00x0.50mm, IPC Medium Density|UseComponentLibrary=T|ModelName=RESC1005X40X25NL10T10|ModelType=PCBLIB|DatafileCount=1|ModelDatafileEntity0=RESC1005X40X25NL10T10|ModelDatafileKind0=PCBLib|DatalinksLocked=T|DatabaseDatalinksLocked=T
|RECORD=46|OwnerIndex=2619
|RECORD=48|OwnerIndex=2619
|RECORD=41|OwnerIndex=2621|IndexInSheet=-1|OwnerPartId=-1|Color=8388608|FontID=1|IsHidden=T|Text=2D|Name=Available Preview Images
|RECORD=1|LibReference=1029c3af85768c4190bb7ad29bc67b5|ComponentDescription=RES SMD 160 OHM 0.5% 1/16W 0402|PartCount=2|DisplayModeCount=1|IndexInSheet=144|OwnerPartId=-1|Location.X=1140|Location.Y=570|Orientation=1|CurrentPartId=1|LibraryPath=*|SourceLibraryName=Altium Content Vault|TargetFileName=*|AreaColor=11599871|Color=128|PartIDLocked=T|DesignItemId=CMP-03412-035461-1|AllPinCount=2
|RECORD=2|OwnerIndex=2623|OwnerPartId=1|Electrical=4|PinConglomerate=51|PinLength=20|Location.X=1140|Location.Y=590|Name=1|Designator=1|PinPropagationDelay=0.000000E+000
|RECORD=2|OwnerIndex=2623|OwnerPartId=1|Electrical=4|PinConglomerate=49|PinLength=20|Location.X=1140|Location.Y=620|Name=2|Designator=2|PinPropagationDelay=0.000000E+000
|RECORD=13|OwnerIndex=2623|IsNotAccesible=T|IndexInSheet=2|OwnerPartId=1|Location.X=1140|Location.Y=590|Corner.X=1135|Corner.Y=593|LineWidth=1|Color=16711680
|RECORD=13|OwnerIndex=2623|IsNotAccesible=T|IndexInSheet=3|OwnerPartId=1|Location.X=1135|Location.Y=593|Corner.X=1145|Corner.Y=598|LineWidth=1|Color=16711680
|RECORD=13|OwnerIndex=2623|IsNotAccesible=T|IndexInSheet=4|OwnerPartId=1|Location.X=1145|Location.Y=598|Corner.X=1135|Corner.Y=603|LineWidth=1|Color=16711680
|RECORD=13|OwnerIndex=2623|IsNotAccesible=T|IndexInSheet=5|OwnerPartId=1|Location.X=1135|Location.Y=603|Corner.X=1145|Corner.Y=608|LineWidth=1|Color=16711680
|RECORD=13|OwnerIndex=2623|IsNotAccesible=T|IndexInSheet=6|OwnerPartId=1|Location.X=1145|Location.Y=608|Corner.X=1135|Corner.Y=613|LineWidth=1|Color=16711680
|RECORD=13|OwnerIndex=2623|IsNotAccesible=T|IndexInSheet=7|OwnerPartId=1|Location.X=1135|Location.Y=613|Corner.X=1145|Corner.Y=618|LineWidth=1|Color=16711680
|RECORD=13|OwnerIndex=2623|IsNotAccesible=T|IndexInSheet=8|OwnerPartId=1|Location.X=1145|Location.Y=618|Corner.X=1140|Corner.Y=620|LineWidth=1|Color=16711680
|RECORD=13|OwnerIndex=2623|IsNotAccesible=T|IndexInSheet=9|OwnerPartId=1|Location.X=1140|Location.Y=590|Corner.X=1140|Corner.Y=587|LineWidth=1|Color=16711680
|RECORD=13|OwnerIndex=2623|IsNotAccesible=T|IndexInSheet=10|OwnerPartId=1|Location.X=1140|Location.Y=620|Corner.X=1140|Corner.Y=623|LineWidth=1|Color=16711680
|RECORD=41|OwnerIndex=2623|IndexInSheet=11|OwnerPartId=-1|Location.X=1134|Location.Y=642|Color=8388608|FontID=1|IsHidden=T|Text=Passive Components|Name=Device Class L1
|RECORD=41|OwnerIndex=2623|IndexInSheet=12|OwnerPartId=-1|Location.X=1134|Location.Y=642|Color=8388608|FontID=1|IsHidden=T|Text=0.005|Name=Tolerance
|RECORD=41|OwnerIndex=2623|IndexInSheet=13|OwnerPartId=-1|Location.X=1134|Location.Y=642|Color=8388608|FontID=1|IsHidden=T|Text=Resistors|Name=Device Class L2
|RECORD=41|OwnerIndex=2623|IndexInSheet=14|OwnerPartId=-1|Location.X=1134|Location.Y=642|Color=8388608|FontID=1|IsHidden=T|Text=Chip SMD Resistors|Name=Device Class L3
|RECORD=41|OwnerIndex=2623|IndexInSheet=15|OwnerPartId=-1|Location.X=1134|Location.Y=642|Color=8388608|FontID=1|IsHidden=T|Text=RT0402|Name=Package
|RECORD=41|OwnerIndex=2623|IndexInSheet=16|OwnerPartId=-1|Location.X=1134|Location.Y=642|Color=8388608|FontID=1|IsHidden=T|Text=0.35mm|Name=Height
|RECORD=41|OwnerIndex=2623|IndexInSheet=17|OwnerPartId=-1|Location.X=1134|Location.Y=642|Color=8388608|FontID=3|IsHidden=T|Text=https://octopart.com/rt0402dre07160rl-yageo-1216058|Name=Octopart
|RECORD=41|OwnerIndex=2623|IndexInSheet=18|OwnerPartId=-1|Location.X=1134|Location.Y=642|Color=8388608|FontID=1|IsHidden=T|Text=+155°C|Name=Temperature Range High
|RECORD=41|OwnerIndex=2623|IndexInSheet=19|OwnerPartId=-1|Location.X=1134|Location.Y=642|Color=8388608|FontID=3|IsHidden=T|Text=http://www.yageo.com/documents/recent/PYu-RT_1-to-0.01_RoHS_L_9.pdf|Name=ComponentLink2URL
|RECORD=41|OwnerIndex=2623|IndexInSheet=20|OwnerPartId=-1|Location.X=1134|Location.Y=642|Color=8388608|FontID=1|IsHidden=T|Text=160O|Name=Value
|RECORD=41|OwnerIndex=2623|IndexInSheet=21|OwnerPartId=-1|Location.X=1134|Location.Y=642|Color=8388608|FontID=1|IsHidden=T|Text=-55°C|Name=Temperature Range Low
|RECORD=41|OwnerIndex=2623|IndexInSheet=22|OwnerPartId=-1|Location.X=1134|Location.Y=642|Color=8388608|FontID=1|IsHidden=T|Text=-55°C to +155°C|Name=Temperature
|RECORD=41|OwnerIndex=2623|IndexInSheet=23|OwnerPartId=-1|Location.X=1134|Location.Y=642|Color=8388608|FontID=1|IsHidden=T|Text=RESC10050X30|Name=Ipc Land Pattern Name
|RECORD=41|OwnerIndex=2623|IndexInSheet=24|OwnerPartId=-1|Location.X=1134|Location.Y=642|Color=8388608|FontID=3|IsHidden=T|Text=http://www.yageo.com/exep/pages/download/literatures/PYu-R_Mount_10.pdf|Name=Footprint Url
|RECORD=41|OwnerIndex=2623|IndexInSheet=25|OwnerPartId=-1|Location.X=1134|Location.Y=642|Color=8388608|FontID=1|IsHidden=T|Text=RT|Name=Series
|RECORD=41|OwnerIndex=2623|IndexInSheet=26|OwnerPartId=-1|Location.X=1134|Location.Y=642|Color=8388608|FontID=1|IsHidden=T|Text=Thin Film|Name=Composition
|RECORD=41|OwnerIndex=2623|IndexInSheet=27|OwnerPartId=-1|Location.X=1134|Location.Y=642|Color=8388608|FontID=1|IsHidden=T|Text=RT0402DRE07160RL|Name=Manufacturer Part Number
|RECORD=41|OwnerIndex=2623|IndexInSheet=28|OwnerPartId=-1|Location.X=1134|Location.Y=642|Color=8388608|FontID=1|IsHidden=T|Text=No|Name=Automotive
|RECORD=41|OwnerIndex=2623|IndexInSheet=29|OwnerPartId=-1|Location.X=1134|Location.Y=642|Color=8388608|FontID=1|IsHidden=T|Text=160O|Name=Resistance
|RECORD=41|OwnerIndex=2623|IndexInSheet=30|OwnerPartId=-1|Location.X=1134|Location.Y=642|Color=8388608|FontID=1|IsHidden=T|Text=50V|Name=Voltage Rating
|RECORD=41|OwnerIndex=2623|IndexInSheet=31|OwnerPartId=-1|Location.X=1134|Location.Y=642|Color=8388608|FontID=1|IsHidden=T|Text=Datasheet|Name=ComponentLink2Description
|RECORD=41|OwnerIndex=2623|IndexInSheet=32|OwnerPartId=-1|Location.X=1134|Location.Y=642|Color=8388608|FontID=1|IsHidden=T|Text=Res|Name=Category
|RECORD=41|OwnerIndex=2623|IndexInSheet=33|OwnerPartId=-1|Location.X=1134|Location.Y=642|Color=8388608|FontID=1|IsHidden=T|Text=Yes|Name=Lead Free
|RECORD=41|OwnerIndex=2623|IndexInSheet=34|OwnerPartId=-1|Location.X=1134|Location.Y=642|Color=8388608|FontID=1|IsHidden=T|Text=50 ppm/°C|Name=Temperature Coefficient
|RECORD=41|OwnerIndex=2623|IndexInSheet=35|OwnerPartId=-1|Location.X=1134|Location.Y=642|Color=8388608|FontID=1|IsHidden=T|Text=Yageo|Name=Manufacturer
|RECORD=41|OwnerIndex=2623|IndexInSheet=36|OwnerPartId=-1|Location.X=1134|Location.Y=642|Color=8388608|FontID=1|IsHidden=T|Text=0.063W|Name=Power Rating
|RECORD=41|OwnerIndex=2623|IndexInSheet=37|OwnerPartId=-1|Location.X=1134|Location.Y=642|Color=8388608|FontID=1|IsHidden=T|Text=RES SMD 160 OHM 0.5% 1/16W 0402|Name=Digikey Description
|RECORD=41|OwnerIndex=2623|IndexInSheet=38|OwnerPartId=-1|Location.X=1134|Location.Y=642|Color=8388608|FontID=1|IsHidden=T|Text=TRUE|Name=RoHS
|RECORD=34|OwnerIndex=2623|IndexInSheet=-1|OwnerPartId=-1|Location.X=1146|Location.Y=614|Color=8388608|FontID=1|Text=R27|Name=Designator|ReadOnlyState=1
|RECORD=41|OwnerIndex=2623|IndexInSheet=-1|OwnerPartId=1|Location.X=1146|Location.Y=604|Color=8388608|FontID=1|Text=160_0.5%_0402|Name=Comment
|RECORD=44|OwnerIndex=2623
|RECORD=45|OwnerIndex=2667|IndexInSheet=-1|UseComponentLibrary=T|ModelName=FP-RT0402-MFG|ModelType=PCBLIB|DatafileCount=1|ModelDatafileEntity0=FP-RT0402-MFG|ModelDatafileKind0=PCBLib|IsCurrent=T|DatalinksLocked=T|DatabaseDatalinksLocked=T
|RECORD=46|OwnerIndex=2668
|RECORD=48|OwnerIndex=2668
|RECORD=45|OwnerIndex=2667|IndexInSheet=-1|UseComponentLibrary=T|ModelName=FP-RT0402-IPC_C|ModelType=PCBLIB|DatafileCount=1|ModelDatafileEntity0=FP-RT0402-IPC_C|ModelDatafileKind0=PCBLib|DatalinksLocked=T|DatabaseDatalinksLocked=T
|RECORD=46|OwnerIndex=2671
|RECORD=48|OwnerIndex=2671
|RECORD=45|OwnerIndex=2667|IndexInSheet=-1|UseComponentLibrary=T|ModelName=FP-RT0402-IPC_B|ModelType=PCBLIB|DatafileCount=1|ModelDatafileEntity0=FP-RT0402-IPC_B|ModelDatafileKind0=PCBLib|DatalinksLocked=T|DatabaseDatalinksLocked=T
|RECORD=46|OwnerIndex=2674
|RECORD=48|OwnerIndex=2674
|RECORD=45|OwnerIndex=2667|IndexInSheet=-1|UseComponentLibrary=T|ModelName=FP-RT0402-IPC_A|ModelType=PCBLIB|DatafileCount=1|ModelDatafileEntity0=FP-RT0402-IPC_A|ModelDatafileKind0=PCBLib|DatalinksLocked=T|DatabaseDatalinksLocked=T
|RECORD=46|OwnerIndex=2677
|RECORD=48|OwnerIndex=2677
|RECORD=4|IndexInSheet=145|OwnerPartId=-1|Location.X=805|Location.Y=1025|Color=8388608|FontID=8|Text=Two power supply options
|RECORD=17|IndexInSheet=146|OwnerPartId=-1|ShowNetName=T|Location.X=580|Location.Y=240|Orientation=1|Color=128|FontID=1|Text=+12V
|RECORD=17|IndexInSheet=147|OwnerPartId=-1|Style=4|ShowNetName=T|Location.X=580|Location.Y=90|Orientation=3|Color=128|FontID=1|Text=GND
|RECORD=17|IndexInSheet=148|OwnerPartId=-1|ShowNetName=T|Location.X=535|Location.Y=215|Orientation=2|Color=255|FontID=1|Text=P3V3_MUN_PHASE|IsCrossSheetConnector=T
|RECORD=17|IndexInSheet=149|OwnerPartId=-1|ShowNetName=T|Location.X=840|Location.Y=195|Color=255|FontID=1|Text=P3V3_MUN_PHASE|IsCrossSheetConnector=T
|RECORD=17|IndexInSheet=150|OwnerPartId=-1|ShowNetName=T|Location.X=850|Location.Y=185|Color=128|FontID=1|Text=+12V
|RECORD=17|IndexInSheet=151|OwnerPartId=-1|Style=4|ShowNetName=T|Location.X=850|Location.Y=225|Color=128|FontID=1|Text=GND
|RECORD=17|IndexInSheet=152|OwnerPartId=-1|ShowNetName=T|Location.X=545|Location.Y=115|Orientation=2|Color=128|FontID=1|Text=P3V3_SENSE
|RECORD=17|IndexInSheet=153|OwnerPartId=-1|ShowNetName=T|Location.X=840|Location.Y=105|Color=128|FontID=1|Text=P3V3_SENSE
|RECORD=17|IndexInSheet=154|OwnerPartId=-1|ShowNetName=T|Location.X=885|Location.Y=215|Color=128|FontID=1|Text=P3V3_SENSE
|RECORD=1|LibReference=RES-2|ComponentDescription=Chip Resistor, 0 Ohm, 0.1 W, -55 to 155 degC, 0402 (1005 Metric), RoHS, Tape and Reel|PartCount=2|DisplayModeCount=1|IndexInSheet=155|OwnerPartId=-1|Location.X=480|Location.Y=155|CurrentPartId=1|LibraryPath=*|SourceLibraryName=Altium Content Vault|TargetFileName=*|AreaColor=11599871|Color=128|PartIDLocked=T|DesignItemId=CMP-2000-07451-1|AllPinCount=2
|RECORD=2|OwnerIndex=2690|OwnerPartId=1|FormalType=1|Electrical=4|PinConglomerate=32|PinLength=10|Location.X=500|Location.Y=155|Name=2|Designator=2|PinPropagationDelay=0.000000E+000
|RECORD=2|OwnerIndex=2690|OwnerPartId=1|FormalType=1|Electrical=4|PinConglomerate=34|PinLength=10|Location.X=480|Location.Y=155|Name=1|Designator=1|PinPropagationDelay=0.000000E+000
|RECORD=6|OwnerIndex=2690|IsNotAccesible=T|IndexInSheet=2|OwnerPartId=1|LineWidth=1|Color=16711680|LocationCount=10|X1=500|Y1=155|X2=496|Y2=155|X3=495|Y3=153|X4=493|Y4=157|X5=491|Y5=153|X6=489|Y6=157|X7=487|Y7=153|X8=485|Y8=157|X9=484|Y9=155|X10=480|Y10=155
|RECORD=41|OwnerIndex=2690|IndexInSheet=3|OwnerPartId=-1|Location.X=468|Location.Y=170|Color=8388608|FontID=1|IsHidden=T|Text=50V|Name=Voltage Rating (DC)
|RECORD=41|OwnerIndex=2690|IndexInSheet=4|OwnerPartId=-1|Location.X=468|Location.Y=170|Color=8388608|FontID=1|IsHidden=T|Text=2|Name=Number of Terminations
|RECORD=41|OwnerIndex=2690|IndexInSheet=5|OwnerPartId=-1|Location.X=468|Location.Y=170|Color=8388608|FontID=1|IsHidden=T|Text=SurfaceMount|Name=Mount
|RECORD=41|OwnerIndex=2690|IndexInSheet=6|OwnerPartId=-1|Location.X=468|Location.Y=170|Color=8388608|FontID=1|IsHidden=T|Text=0.35mm|Name=Height
|RECORD=41|OwnerIndex=2690|IndexInSheet=7|OwnerPartId=-1|Location.X=468|Location.Y=170|Color=8388608|FontID=1|IsHidden=T|Text=TapeandReel|Name=Packaging
|RECORD=41|OwnerIndex=2690|IndexInSheet=8|OwnerPartId=-1|Location.X=468|Location.Y=170|Color=8388608|FontID=1|IsHidden=T|Text=Tin|Name=Contact Plating
|RECORD=41|OwnerIndex=2690|IndexInSheet=9|OwnerPartId=-1|Location.X=468|Location.Y=170|Color=8388608|FontID=3|IsHidden=T|Text=http://www.panasonic.com/|Name=Manufacturer URL
|RECORD=41|OwnerIndex=2690|IndexInSheet=10|OwnerPartId=-1|Location.X=468|Location.Y=170|Color=8388608|FontID=1|IsHidden=T|Text=ThickFilm|Name=Composition
|RECORD=41|OwnerIndex=2690|IndexInSheet=11|OwnerPartId=-1|Location.X=468|Location.Y=170|Color=8388608|FontID=1|IsHidden=T|Text=155degC|Name=Max Operating Temperature
|RECORD=41|OwnerIndex=2690|IndexInSheet=12|OwnerPartId=-1|Location.X=468|Location.Y=170|Color=8388608|FontID=1|IsHidden=T|Text=600ppm/??C|Name=Temperature Coefficient
|RECORD=41|OwnerIndex=2690|IndexInSheet=13|OwnerPartId=-1|Location.X=468|Location.Y=170|Color=8388608|FontID=1|IsHidden=T|Text=NoSVHC|Name=REACH SVHC
|RECORD=41|OwnerIndex=2690|IndexInSheet=14|OwnerPartId=-1|Location.X=468|Location.Y=170|Color=8388608|FontID=1|IsHidden=T|Text=0402|Name=Case/Package
|RECORD=41|OwnerIndex=2690|IndexInSheet=15|OwnerPartId=-1|Location.X=468|Location.Y=170|Color=8388608|FontID=1|IsHidden=T|Text=100mW|Name=Max Power Dissipation
|RECORD=41|OwnerIndex=2690|IndexInSheet=16|OwnerPartId=-1|Location.X=468|Location.Y=170|Color=8388608|FontID=1|IsHidden=T|Text=402|Name=Package Reference
|RECORD=41|OwnerIndex=2690|IndexInSheet=17|OwnerPartId=-1|Location.X=468|Location.Y=170|Color=8388608|FontID=1|IsHidden=T|Text=0.5mm|Name=Depth
|RECORD=41|OwnerIndex=2690|IndexInSheet=18|OwnerPartId=-1|Location.X=468|Location.Y=170|Color=8388608|FontID=1|IsHidden=T|Text=Panasonic|Name=Manufacturer
|RECORD=41|OwnerIndex=2690|IndexInSheet=19|OwnerPartId=-1|Location.X=468|Location.Y=170|Color=8388608|FontID=1|IsHidden=T|Text=2-Pin Surface Mount Device, Body 1 x 0.5 mm|Name=Package Description
|RECORD=41|OwnerIndex=2690|IndexInSheet=20|OwnerPartId=-1|Location.X=468|Location.Y=170|Color=8388608|FontID=3|IsHidden=T|Text=https://industrial.panasonic.com/cdbs/www-data/pdf/RDA0000/AOA0000C301.pdf|Name=Datasheet URL
|RECORD=41|OwnerIndex=2690|IndexInSheet=21|OwnerPartId=-1|Location.X=468|Location.Y=170|Color=8388608|FontID=1|IsHidden=T|Text=True|Name=RoHSCompliant
|RECORD=41|OwnerIndex=2690|IndexInSheet=22|OwnerPartId=-1|Location.X=468|Location.Y=170|Color=8388608|FontID=1|IsHidden=T|Text=0402|Name=Case Code (Imperial)
|RECORD=41|OwnerIndex=2690|IndexInSheet=23|OwnerPartId=-1|Location.X=468|Location.Y=170|Color=8388608|FontID=1|IsHidden=T|Text=0mOhm|Name=Resistance
|RECORD=41|OwnerIndex=2690|IndexInSheet=24|OwnerPartId=-1|Location.X=468|Location.Y=170|Color=8388608|FontID=1|IsHidden=T|Text=Not|Name=Military Standard
|RECORD=41|OwnerIndex=2690|IndexInSheet=25|OwnerPartId=-1|Location.X=468|Location.Y=170|Color=8388608|FontID=1|IsHidden=T|Text=5%|Name=Tolerance
|RECORD=41|OwnerIndex=2690|IndexInSheet=26|OwnerPartId=-1|Location.X=468|Location.Y=170|Color=8388608|FontID=1|IsHidden=T|Text=-55degC|Name=Min Operating Temperature
|RECORD=41|OwnerIndex=2690|IndexInSheet=27|OwnerPartId=-1|Location.X=468|Location.Y=170|Color=8388608|FontID=1|IsHidden=T|Text=100mW|Name=Power Rating
|RECORD=41|OwnerIndex=2690|IndexInSheet=28|OwnerPartId=-1|Location.X=468|Location.Y=170|Color=8388608|FontID=1|IsHidden=T|Text=03/2015|Name=Datasheet Version
|RECORD=41|OwnerIndex=2690|IndexInSheet=29|OwnerPartId=-1|Location.X=468|Location.Y=170|Color=8388608|FontID=1|IsHidden=T|Text=1mm|Name=Length
|RECORD=41|OwnerIndex=2690|IndexInSheet=30|OwnerPartId=-1|Location.X=468|Location.Y=170|Color=8388608|FontID=1|IsHidden=T|Text=1005|Name=Case Code (Metric)
|RECORD=41|OwnerIndex=2690|IndexInSheet=31|OwnerPartId=-1|Location.X=468|Location.Y=170|Color=8388608|FontID=1|IsHidden=T|Text=SMD/SMT|Name=Termination
|RECORD=41|OwnerIndex=2690|IndexInSheet=32|OwnerPartId=-1|Location.X=468|Location.Y=170|Color=8388608|FontID=1|IsHidden=T|Text=SurfaceMount|Name=Mounting Technology
|RECORD=41|OwnerIndex=2690|IndexInSheet=33|OwnerPartId=-1|Location.X=468|Location.Y=170|Color=8388608|FontID=1|IsHidden=T|Text=50V|Name=Voltage Rating
|RECORD=41|OwnerIndex=2690|IndexInSheet=34|OwnerPartId=-1|Location.X=468|Location.Y=170|Color=8388608|FontID=1|IsHidden=T|Text=0.02inch|Name=Width
|RECORD=41|OwnerIndex=2690|IndexInSheet=35|OwnerPartId=-1|Location.X=468|Location.Y=170|Color=8388608|FontID=1|IsHidden=T|Text=1|Name=Package Quantity
|RECORD=41|OwnerIndex=2690|IndexInSheet=36|OwnerPartId=-1|Location.X=468|Location.Y=170|Color=8388608|FontID=1|IsHidden=T|Text=LeadFree|Name=Lead Free
|RECORD=41|OwnerIndex=2690|IndexInSheet=37|OwnerPartId=-1|Location.X=468|Location.Y=170|Color=8388608|FontID=1|IsHidden=T|Text=No|Name=Radiation Hardening
|RECORD=34|OwnerIndex=2690|IndexInSheet=-1|OwnerPartId=-1|Location.X=460|Location.Y=155|Color=8388608|FontID=1|Text=R69|Name=Designator|ReadOnlyState=1
|RECORD=41|OwnerIndex=2690|IndexInSheet=-1|OwnerPartId=-1|Location.X=500|Location.Y=155|Color=8388608|FontID=1|Text=0_1%_0402|Name=Comment
|RECORD=44|OwnerIndex=2690
|RECORD=45|OwnerIndex=2733|IndexInSheet=-1|Description=Chip Resistor, 2-Leads, Body 1.05x0.55mm, IPC High Density|UseComponentLibrary=T|ModelName=RESC1005X40X25LL05T05|ModelType=PCBLIB|DatafileCount=1|ModelDatafileEntity0=RESC1005X40X25LL05T05|ModelDatafileKind0=PCBLib|IsCurrent=T|DatalinksLocked=T|DatabaseDatalinksLocked=T
|RECORD=46|OwnerIndex=2734
|RECORD=48|OwnerIndex=2734
|RECORD=41|OwnerIndex=2736|IndexInSheet=-1|OwnerPartId=-1|Color=8388608|FontID=1|IsHidden=T|Text=2D|Name=Available Preview Images
|RECORD=45|OwnerIndex=2733|IndexInSheet=-1|Description=Chip Resistor, 2-Leads, Body 1.05x0.55mm, IPC Low Density|UseComponentLibrary=T|ModelName=RESC1005X40X25ML05T05|ModelType=PCBLIB|DatafileCount=1|ModelDatafileEntity0=RESC1005X40X25ML05T05|ModelDatafileKind0=PCBLib|DatalinksLocked=T|DatabaseDatalinksLocked=T
|RECORD=46|OwnerIndex=2738
|RECORD=48|OwnerIndex=2738
|RECORD=41|OwnerIndex=2740|IndexInSheet=-1|OwnerPartId=-1|Color=8388608|FontID=1|IsHidden=T|Text=2D|Name=Available Preview Images
|RECORD=45|OwnerIndex=2733|IndexInSheet=-1|Description=Chip Resistor, 2-Leads, Body 1.05x0.55mm, IPC Medium Density|UseComponentLibrary=T|ModelName=RESC1005X40X25NL05T05|ModelType=PCBLIB|DatafileCount=1|ModelDatafileEntity0=RESC1005X40X25NL05T05|ModelDatafileKind0=PCBLib|DatalinksLocked=T|DatabaseDatalinksLocked=T
|RECORD=46|OwnerIndex=2742
|RECORD=48|OwnerIndex=2742
|RECORD=41|OwnerIndex=2744|IndexInSheet=-1|OwnerPartId=-1|Color=8388608|FontID=1|IsHidden=T|Text=2D|Name=Available Preview Images
|RECORD=1|LibReference=RES|PartCount=2|DisplayModeCount=2|IndexInSheet=156|OwnerPartId=-1|Location.X=500|Location.Y=130|Orientation=2|CurrentPartId=1|SourceLibraryName=Altium Content Vault|TargetFileName=*|AreaColor=11599871|Color=128|PartIDLocked=F|DesignItemId=CMP-2002-05217-1|AllPinCount=2
|RECORD=2|OwnerIndex=2746|OwnerPartId=1|OwnerPartDisplayMode=1|FormalType=1|Electrical=4|PinConglomerate=34|PinLength=10|Location.X=480|Location.Y=140|Name=2|Designator=2|PinPropagationDelay=0.000000E+000
|RECORD=2|OwnerIndex=2746|OwnerPartId=1|OwnerPartDisplayMode=1|FormalType=1|Electrical=4|PinConglomerate=32|PinLength=10|Location.X=500|Location.Y=140|Name=1|Designator=1|PinPropagationDelay=0.000000E+000
|RECORD=14|OwnerIndex=2746|IsNotAccesible=T|IndexInSheet=2|OwnerPartId=1|OwnerPartDisplayMode=1|Location.X=480|Location.Y=136|Corner.X=500|Corner.Y=144|LineWidth=1|Color=16711680|AreaColor=11599871
|RECORD=2|OwnerIndex=2746|OwnerPartId=1|FormalType=1|Electrical=4|PinConglomerate=34|PinLength=10|Location.X=480|Location.Y=140|Name=2|Designator=2|PinPropagationDelay=0.000000E+000
|RECORD=2|OwnerIndex=2746|OwnerPartId=1|FormalType=1|Electrical=4|PinConglomerate=32|PinLength=10|Location.X=500|Location.Y=140|Name=1|Designator=1|PinPropagationDelay=0.000000E+000
|RECORD=6|OwnerIndex=2746|IsNotAccesible=T|IndexInSheet=5|OwnerPartId=1|LineWidth=1|Color=16711680|LocationCount=10|X1=480|Y1=140|X2=484|Y2=140|X3=485|Y3=142|X4=487|Y4=138|X5=489|Y5=142|X6=491|Y6=138|X7=493|Y7=142|X8=495|Y8=138|X9=496|Y9=140|X10=500|Y10=140
|RECORD=41|OwnerIndex=2746|IndexInSheet=6|OwnerPartId=-1|Location.X=468|Location.Y=143|Color=8388608|FontID=1|IsHidden=T|Text=Bourns|Name=Manufacturer
|RECORD=41|OwnerIndex=2746|IndexInSheet=7|OwnerPartId=-1|Location.X=468|Location.Y=143|Color=8388608|FontID=1|IsHidden=T|Text=CR0402-FX-4701GLF|Name=Part Number
|RECORD=34|OwnerIndex=2746|IndexInSheet=-1|OwnerPartId=-1|Location.X=479|Location.Y=143|Color=8388608|FontID=1|Text=R70|Name=Designator|ReadOnlyState=1
|RECORD=41|OwnerIndex=2746|IndexInSheet=-1|OwnerPartId=-1|Location.X=479|Location.Y=127|Color=8388608|FontID=1|Text=4.7K_1%_0402|Name=Comment
|RECORD=44|OwnerIndex=2746
|RECORD=45|OwnerIndex=2761|IndexInSheet=-1|Description=Chip Resistor, 2-Leads, Body 1.00x0.50mm, IPC Medium Density|UseComponentLibrary=T|ModelName=RESC1005X40X25NL10T10|ModelType=PCBLIB|DatafileCount=1|ModelDatafileEntity0=RESC1005X40X25NL10T10|ModelDatafileKind0=PCBLib|IsCurrent=T|DatalinksLocked=T|DatabaseDatalinksLocked=T
|RECORD=46|OwnerIndex=2762
|RECORD=48|OwnerIndex=2762
|RECORD=41|OwnerIndex=2764|IndexInSheet=-1|OwnerPartId=-1|Color=8388608|FontID=1|IsHidden=T|Text=2D|Name=Available Preview Images
|RECORD=45|OwnerIndex=2761|IndexInSheet=-1|Description=Chip Resistor, 2-Leads, Body 1.00x0.50mm, IPC High Density|UseComponentLibrary=T|ModelName=RESC1005X40X25LL10T10|ModelType=PCBLIB|DatafileCount=1|ModelDatafileEntity0=RESC1005X40X25LL10T10|ModelDatafileKind0=PCBLib|DatalinksLocked=T|DatabaseDatalinksLocked=T
|RECORD=46|OwnerIndex=2766
|RECORD=48|OwnerIndex=2766
|RECORD=41|OwnerIndex=2768|IndexInSheet=-1|OwnerPartId=-1|Color=8388608|FontID=1|IsHidden=T|Text=2D|Name=Available Preview Images
|RECORD=45|OwnerIndex=2761|IndexInSheet=-1|Description=Chip Resistor, 2-Leads, Body 1.00x0.50mm, IPC Low Density|UseComponentLibrary=T|ModelName=RESC1005X40X25ML10T10|ModelType=PCBLIB|DatafileCount=1|ModelDatafileEntity0=RESC1005X40X25ML10T10|ModelDatafileKind0=PCBLib|DatalinksLocked=T|DatabaseDatalinksLocked=T
|RECORD=46|OwnerIndex=2770
|RECORD=48|OwnerIndex=2770
|RECORD=41|OwnerIndex=2772|IndexInSheet=-1|OwnerPartId=-1|Color=8388608|FontID=1|IsHidden=T|Text=2D|Name=Available Preview Images
|RECORD=17|IndexInSheet=157|OwnerPartId=-1|ShowNetName=T|Location.X=440|Location.Y=180|Orientation=1|Color=128|FontID=1|Text=+12V
|RECORD=17|IndexInSheet=158|OwnerPartId=-1|ShowNetName=T|Location.X=875|Location.Y=145|Color=128|FontID=1|Text=P3V3_MUN_VCC
|RECORD=17|IndexInSheet=159|OwnerPartId=-1|ShowNetName=T|Location.X=985|Location.Y=180|Orientation=1|Color=128|FontID=1|Text=P3V3_MUN_VCC
|RECORD=1|LibReference=b4654b650e69147ec39a6b967a45e02|ComponentDescription=Multilayer Ceramic Capacitors 2.2µF ±10% 16V X5R SMD 0402|PartCount=2|DisplayModeCount=1|IndexInSheet=160|OwnerPartId=-1|Location.X=985|Location.Y=170|CurrentPartId=1|LibraryPath=*|SourceLibraryName=Altium Content Vault|TargetFileName=*|AreaColor=11599871|Color=128|PartIDLocked=T|DesignItemId=CMP-2000-05998-2|AllPinCount=2
|RECORD=2|OwnerIndex=2777|OwnerPartId=1|Electrical=4|PinConglomerate=49|PinLength=7|Location.X=985|Location.Y=163|Name=1|Designator=1|PinPropagationDelay=0.000000E+000
|RECORD=2|OwnerIndex=2777|OwnerPartId=1|Electrical=4|PinConglomerate=51|PinLength=6|Location.X=985|Location.Y=156|Name=2|Designator=2|PinPropagationDelay=0.000000E+000
|RECORD=13|OwnerIndex=2777|IsNotAccesible=T|IndexInSheet=2|OwnerPartId=1|Location.X=995|Location.Y=163|Corner.X=975|Corner.Y=163|LineWidth=1|Color=16711680
|RECORD=13|OwnerIndex=2777|IsNotAccesible=T|IndexInSheet=3|OwnerPartId=1|Location.X=995|Location.Y=157|Corner.X=975|Corner.Y=157|LineWidth=1|Color=16711680
|RECORD=13|OwnerIndex=2777|IsNotAccesible=T|IndexInSheet=4|OwnerPartId=1|Location.X=985|Location.Y=163|Corner.X=985|Corner.Y=166|LineWidth=1|Color=16711680
|RECORD=13|OwnerIndex=2777|IsNotAccesible=T|IndexInSheet=5|OwnerPartId=1|Location.X=985|Location.Y=156|Corner.X=985|Corner.Y=155|LineWidth=1|Color=16711680
|RECORD=41|OwnerIndex=2777|IndexInSheet=6|OwnerPartId=-1|Location.X=974|Location.Y=172|Color=8388608|FontID=1|IsHidden=T|Text=No SVHC|Name=REACH SVHC
|RECORD=41|OwnerIndex=2777|IndexInSheet=7|OwnerPartId=-1|Location.X=974|Location.Y=172|Color=8388608|FontID=1|IsHidden=T|Text=C|Name=Series
|RECORD=41|OwnerIndex=2777|IndexInSheet=8|OwnerPartId=-1|Location.X=974|Location.Y=172|Color=8388608|FontID=1|IsHidden=T|Text=SMD/SMT|Name=Termination
|RECORD=41|OwnerIndex=2777|IndexInSheet=9|OwnerPartId=-1|Location.X=974|Location.Y=172|Color=8388608|FontID=1|IsHidden=T|Text=0402|Name=Case Code (Imperial)
|RECORD=41|OwnerIndex=2777|IndexInSheet=10|OwnerPartId=-1|Location.X=974|Location.Y=172|Color=8388608|FontID=1|IsHidden=T|Text=0.5mm|Name=Depth
|RECORD=41|OwnerIndex=2777|IndexInSheet=11|OwnerPartId=-1|Location.X=974|Location.Y=172|Color=8388608|FontID=1|IsHidden=T|Text=Surface Mount|Name=Mount
|RECORD=41|OwnerIndex=2777|IndexInSheet=12|OwnerPartId=-1|Location.X=974|Location.Y=172|Color=8388608|FontID=1|IsHidden=T|Text=0.02inch|Name=Width
|RECORD=41|OwnerIndex=2777|IndexInSheet=13|OwnerPartId=-1|Location.X=974|Location.Y=172|Color=8388608|FontID=1|IsHidden=T|Text=1|Name=Package Quantity
|RECORD=41|OwnerIndex=2777|IndexInSheet=14|OwnerPartId=-1|Location.X=974|Location.Y=172|Color=8388608|FontID=1|IsHidden=T|Text=Ceramic|Name=Dielectric Material
|RECORD=41|OwnerIndex=2777|IndexInSheet=15|OwnerPartId=-1|Location.X=974|Location.Y=172|Color=8388608|FontID=1|IsHidden=T|Text=1mm|Name=Length
|RECORD=41|OwnerIndex=2777|IndexInSheet=16|OwnerPartId=-1|Location.X=974|Location.Y=172|Color=8388608|FontID=1|IsHidden=T|Text=Tape and Reel|Name=Packaging
|RECORD=41|OwnerIndex=2777|IndexInSheet=17|OwnerPartId=-1|Location.X=974|Location.Y=172|Color=8388608|FontID=1|IsHidden=T|Text=1005|Name=Case Code (Metric)
|RECORD=41|OwnerIndex=2777|IndexInSheet=18|OwnerPartId=-1|Location.X=974|Location.Y=172|Color=8388608|FontID=1|IsHidden=T|Text=Yes|Name=RoHS Compliant
|RECORD=41|OwnerIndex=2777|IndexInSheet=19|OwnerPartId=-1|Location.X=974|Location.Y=172|Color=8388608|FontID=1|IsHidden=T|Text=X5R|Name=Dielectric
|RECORD=41|OwnerIndex=2777|IndexInSheet=20|OwnerPartId=-1|Location.X=974|Location.Y=172|Color=8388608|FontID=1|IsHidden=T|Text=85°C|Name=Max Operating Temperature
|RECORD=41|OwnerIndex=2777|IndexInSheet=21|OwnerPartId=-1|Location.X=974|Location.Y=172|Color=8388608|FontID=1|IsHidden=T|Text=Lead Free|Name=Lead Free
|RECORD=41|OwnerIndex=2777|IndexInSheet=22|OwnerPartId=-1|Location.X=974|Location.Y=172|Color=8388608|FontID=1|IsHidden=T|Text=2.3E-05oz|Name=Weight
|RECORD=41|OwnerIndex=2777|IndexInSheet=23|OwnerPartId=-1|Location.X=974|Location.Y=172|Color=8388608|FontID=1|IsHidden=T|Text=0.022inch|Name=Thickness
|RECORD=41|OwnerIndex=2777|IndexInSheet=24|OwnerPartId=-1|Location.X=974|Location.Y=172|Color=8388608|FontID=1|IsHidden=T|Text=2.2uF|Name=Capacitance
|RECORD=41|OwnerIndex=2777|IndexInSheet=25|OwnerPartId=-1|Location.X=974|Location.Y=172|Color=8388608|FontID=1|IsHidden=T|Text=16V|Name=Voltage Rating (DC)
|RECORD=41|OwnerIndex=2777|IndexInSheet=26|OwnerPartId=-1|Location.X=974|Location.Y=172|Color=8388608|FontID=1|IsHidden=T|Text=10%|Name=Tolerance
|RECORD=41|OwnerIndex=2777|IndexInSheet=27|OwnerPartId=-1|Location.X=974|Location.Y=172|Color=8388608|FontID=1|IsHidden=T|Text=16V|Name=Voltage Rating
|RECORD=41|OwnerIndex=2777|IndexInSheet=28|OwnerPartId=-1|Location.X=974|Location.Y=172|Color=8388608|FontID=1|IsHidden=T|Text=Ceramic|Name=Resistor Type
|RECORD=41|OwnerIndex=2777|IndexInSheet=29|OwnerPartId=-1|Location.X=974|Location.Y=172|Color=8388608|FontID=1|IsHidden=T|Text=0.5mm|Name=Height
|RECORD=41|OwnerIndex=2777|IndexInSheet=30|OwnerPartId=-1|Location.X=974|Location.Y=172|Color=8388608|FontID=1|IsHidden=T|Text=0402|Name=Case/Package
|RECORD=41|OwnerIndex=2777|IndexInSheet=31|OwnerPartId=-1|Location.X=974|Location.Y=172|Color=8388608|FontID=1|IsHidden=T|Text=-55°C|Name=Min Operating Temperature
|RECORD=34|OwnerIndex=2777|IndexInSheet=-1|OwnerPartId=-1|Location.X=975|Location.Y=150|Orientation=1|Color=8388608|FontID=2|Text=C5|Name=Designator|ReadOnlyState=1
|RECORD=41|OwnerIndex=2777|IndexInSheet=-1|OwnerPartId=1|Location.X=1005|Location.Y=125|Orientation=1|Color=8388608|FontID=2|Text=2.2uF_16V_0402|Name=Comment
|RECORD=44|OwnerIndex=2777
|RECORD=45|OwnerIndex=2814|IndexInSheet=-1|UseComponentLibrary=T|ModelName=FP-C1005-050-0_05-IPC_A|ModelType=PCBLIB|DatafileCount=1|ModelDatafileEntity0=FP-C1005-050-0_05-IPC_A|ModelDatafileKind0=PCBLib|IsCurrent=T|DatalinksLocked=T|DatabaseDatalinksLocked=T
|RECORD=46|OwnerIndex=2815
|RECORD=48|OwnerIndex=2815
|RECORD=45|OwnerIndex=2814|IndexInSheet=-1|UseComponentLibrary=T|ModelName=FP-C1005-050-0_05-MFG|ModelType=PCBLIB|DatafileCount=1|ModelDatafileEntity0=FP-C1005-050-0_05-MFG|ModelDatafileKind0=PCBLib|DatalinksLocked=T|DatabaseDatalinksLocked=T
|RECORD=46|OwnerIndex=2818
|RECORD=48|OwnerIndex=2818
|RECORD=45|OwnerIndex=2814|IndexInSheet=-1|UseComponentLibrary=T|ModelName=FP-C1005-050-0_05-IPC_C|ModelType=PCBLIB|DatafileCount=1|ModelDatafileEntity0=FP-C1005-050-0_05-IPC_C|ModelDatafileKind0=PCBLib|DatalinksLocked=T|DatabaseDatalinksLocked=T
|RECORD=46|OwnerIndex=2821
|RECORD=48|OwnerIndex=2821
|RECORD=45|OwnerIndex=2814|IndexInSheet=-1|UseComponentLibrary=T|ModelName=FP-C1005-050-0_05-IPC_B|ModelType=PCBLIB|DatafileCount=1|ModelDatafileEntity0=FP-C1005-050-0_05-IPC_B|ModelDatafileKind0=PCBLib|DatalinksLocked=T|DatabaseDatalinksLocked=T
|RECORD=46|OwnerIndex=2824
|RECORD=48|OwnerIndex=2824
|RECORD=17|IndexInSheet=161|OwnerPartId=-1|Style=4|ShowNetName=T|Location.X=985|Location.Y=135|Orientation=3|Color=128|FontID=1|Text=GND
|RECORD=1|LibReference=1029c3af85768c4190bb7ad29bc67b5|ComponentDescription=RES SMD 88.7K OHM 0.5% 1/16W|PartCount=2|DisplayModeCount=1|IndexInSheet=162|OwnerPartId=-1|Location.X=630|Location.Y=275|CurrentPartId=1|LibraryPath=*|SourceLibraryName=Altium Content Vault|TargetFileName=*|AreaColor=11599871|Color=128|PartIDLocked=T|DesignItemId=CMP-2002-03021-2|AllPinCount=2
|RECORD=2|OwnerIndex=2828|OwnerPartId=1|Electrical=4|PinConglomerate=50|PinLength=20|Location.X=650|Location.Y=275|Name=1|Designator=1|PinPropagationDelay=0.000000E+000
|RECORD=2|OwnerIndex=2828|OwnerPartId=1|Electrical=4|PinConglomerate=48|PinLength=20|Location.X=680|Location.Y=275|Name=2|Designator=2|PinPropagationDelay=0.000000E+000
|RECORD=13|OwnerIndex=2828|IsNotAccesible=T|IndexInSheet=2|OwnerPartId=1|Location.X=650|Location.Y=275|Corner.X=653|Corner.Y=280|LineWidth=1|Color=16711680
|RECORD=13|OwnerIndex=2828|IsNotAccesible=T|IndexInSheet=3|OwnerPartId=1|Location.X=653|Location.Y=280|Corner.X=658|Corner.Y=270|LineWidth=1|Color=16711680
|RECORD=13|OwnerIndex=2828|IsNotAccesible=T|IndexInSheet=4|OwnerPartId=1|Location.X=658|Location.Y=270|Corner.X=663|Corner.Y=280|LineWidth=1|Color=16711680
|RECORD=13|OwnerIndex=2828|IsNotAccesible=T|IndexInSheet=5|OwnerPartId=1|Location.X=663|Location.Y=280|Corner.X=668|Corner.Y=270|LineWidth=1|Color=16711680
|RECORD=13|OwnerIndex=2828|IsNotAccesible=T|IndexInSheet=6|OwnerPartId=1|Location.X=668|Location.Y=270|Corner.X=673|Corner.Y=280|LineWidth=1|Color=16711680
|RECORD=13|OwnerIndex=2828|IsNotAccesible=T|IndexInSheet=7|OwnerPartId=1|Location.X=673|Location.Y=280|Corner.X=678|Corner.Y=270|LineWidth=1|Color=16711680
|RECORD=13|OwnerIndex=2828|IsNotAccesible=T|IndexInSheet=8|OwnerPartId=1|Location.X=678|Location.Y=270|Corner.X=680|Corner.Y=275|LineWidth=1|Color=16711680
|RECORD=13|OwnerIndex=2828|IsNotAccesible=T|IndexInSheet=9|OwnerPartId=1|Location.X=650|Location.Y=275|Corner.X=647|Corner.Y=275|LineWidth=1|Color=16711680
|RECORD=13|OwnerIndex=2828|IsNotAccesible=T|IndexInSheet=10|OwnerPartId=1|Location.X=680|Location.Y=275|Corner.X=683|Corner.Y=275|LineWidth=1|Color=16711680
|RECORD=41|OwnerIndex=2828|IndexInSheet=11|OwnerPartId=-1|Location.X=628|Location.Y=281|Color=8388608|FontID=1|IsHidden=T|Text=+155°C|Name=Temperature Range High
|RECORD=41|OwnerIndex=2828|IndexInSheet=12|OwnerPartId=-1|Location.X=628|Location.Y=281|Color=8388608|FontID=1|IsHidden=T|Text=Thin Film|Name=Composition
|RECORD=41|OwnerIndex=2828|IndexInSheet=13|OwnerPartId=-1|Location.X=628|Location.Y=281|Color=8388608|FontID=1|IsHidden=T|Text=Datasheet|Name=ComponentLink2Description
|RECORD=41|OwnerIndex=2828|IndexInSheet=14|OwnerPartId=-1|Location.X=628|Location.Y=281|Color=8388608|FontID=1|IsHidden=T|Text=TRUE|Name=RoHS
|RECORD=41|OwnerIndex=2828|IndexInSheet=15|OwnerPartId=-1|Location.X=628|Location.Y=281|Color=8388608|FontID=1|IsHidden=T|Text=Res|Name=Category
|RECORD=41|OwnerIndex=2828|IndexInSheet=16|OwnerPartId=-1|Location.X=628|Location.Y=281|Color=8388608|FontID=1|IsHidden=T|Text=RESC10050X30|Name=Ipc Land Pattern Name
|RECORD=41|OwnerIndex=2828|IndexInSheet=17|OwnerPartId=-1|Location.X=628|Location.Y=281|Color=8388608|FontID=3|IsHidden=T|Text=https://octopart.com/rt0402dre0788k7l-yageo-1439224|Name=Octopart
|RECORD=41|OwnerIndex=2828|IndexInSheet=18|OwnerPartId=-1|Location.X=628|Location.Y=281|Color=8388608|FontID=3|IsHidden=T|Text=http://www.yageo.com/documents/recent/PYu-RT_1-to-0.01_RoHS_L_9.pdf|Name=ComponentLink2URL
|RECORD=41|OwnerIndex=2828|IndexInSheet=19|OwnerPartId=-1|Location.X=628|Location.Y=281|Color=8388608|FontID=1|IsHidden=T|Text=RES SMD 88.7K OHM 0.5% 1/16W|Name=Digikey Description
|RECORD=41|OwnerIndex=2828|IndexInSheet=20|OwnerPartId=-1|Location.X=628|Location.Y=281|Color=8388608|FontID=1|IsHidden=T|Text=0.35mm|Name=Height
|RECORD=41|OwnerIndex=2828|IndexInSheet=21|OwnerPartId=-1|Location.X=628|Location.Y=281|Color=8388608|FontID=1|IsHidden=T|Text=RT|Name=Series
|RECORD=41|OwnerIndex=2828|IndexInSheet=22|OwnerPartId=-1|Location.X=628|Location.Y=281|Color=8388608|FontID=1|IsHidden=T|Text=50V|Name=Voltage Rating
|RECORD=41|OwnerIndex=2828|IndexInSheet=23|OwnerPartId=-1|Location.X=628|Location.Y=281|Color=8388608|FontID=3|IsHidden=T|Text=http://www.yageo.com/exep/pages/download/literatures/PYu-R_Mount_10.pdf|Name=Footprint Url
|RECORD=41|OwnerIndex=2828|IndexInSheet=24|OwnerPartId=-1|Location.X=628|Location.Y=281|Color=8388608|FontID=1|IsHidden=T|Text=Resistors|Name=Device Class L2
|RECORD=41|OwnerIndex=2828|IndexInSheet=25|OwnerPartId=-1|Location.X=628|Location.Y=281|Color=8388608|FontID=1|IsHidden=T|Text=-55°C to +155°C|Name=Temperature
|RECORD=41|OwnerIndex=2828|IndexInSheet=26|OwnerPartId=-1|Location.X=628|Location.Y=281|Color=8388608|FontID=1|IsHidden=T|Text=0.063W|Name=Power Rating
|RECORD=41|OwnerIndex=2828|IndexInSheet=27|OwnerPartId=-1|Location.X=628|Location.Y=281|Color=8388608|FontID=1|IsHidden=T|Text=-55°C|Name=Temperature Range Low
|RECORD=41|OwnerIndex=2828|IndexInSheet=28|OwnerPartId=-1|Location.X=628|Location.Y=281|Color=8388608|FontID=1|IsHidden=T|Text=Yageo|Name=Manufacturer
|RECORD=41|OwnerIndex=2828|IndexInSheet=29|OwnerPartId=-1|Location.X=628|Location.Y=281|Color=8388608|FontID=1|IsHidden=T|Text=RT0402|Name=Package
|RECORD=41|OwnerIndex=2828|IndexInSheet=30|OwnerPartId=-1|Location.X=628|Location.Y=281|Color=8388608|FontID=1|IsHidden=T|Text=Passive Components|Name=Device Class L1
|RECORD=41|OwnerIndex=2828|IndexInSheet=31|OwnerPartId=-1|Location.X=628|Location.Y=281|Color=8388608|FontID=1|IsHidden=T|Text=88.7KO|Name=Value
|RECORD=41|OwnerIndex=2828|IndexInSheet=32|OwnerPartId=-1|Location.X=628|Location.Y=281|Color=8388608|FontID=1|IsHidden=T|Text=No|Name=Automotive
|RECORD=41|OwnerIndex=2828|IndexInSheet=33|OwnerPartId=-1|Location.X=628|Location.Y=281|Color=8388608|FontID=1|IsHidden=T|Text=RT0402DRE0788K7L|Name=Manufacturer Part Number
|RECORD=41|OwnerIndex=2828|IndexInSheet=34|OwnerPartId=-1|Location.X=628|Location.Y=281|Color=8388608|FontID=1|IsHidden=T|Text=50 ppm/°C|Name=Temperature Coefficient
|RECORD=41|OwnerIndex=2828|IndexInSheet=35|OwnerPartId=-1|Location.X=628|Location.Y=281|Color=8388608|FontID=1|IsHidden=T|Text=Yes|Name=Lead Free
|RECORD=41|OwnerIndex=2828|IndexInSheet=36|OwnerPartId=-1|Location.X=628|Location.Y=281|Color=8388608|FontID=1|IsHidden=T|Text=Chip SMD Resistors|Name=Device Class L3
|RECORD=41|OwnerIndex=2828|IndexInSheet=37|OwnerPartId=-1|Location.X=628|Location.Y=281|Color=8388608|FontID=1|IsHidden=T|Text=0.005|Name=Tolerance
|RECORD=41|OwnerIndex=2828|IndexInSheet=38|OwnerPartId=-1|Location.X=628|Location.Y=281|Color=8388608|FontID=1|IsHidden=T|Text=88.7KO|Name=Resistance
|RECORD=34|OwnerIndex=2828|IndexInSheet=-1|OwnerPartId=-1|Location.X=646|Location.Y=281|Color=8388608|FontID=1|Text=R67|Name=Designator|ReadOnlyState=1
|RECORD=41|OwnerIndex=2828|IndexInSheet=-1|OwnerPartId=1|Location.X=646|Location.Y=259|Color=8388608|FontID=1|Text=88.7K_0.5%_0402|Name=Comment
|RECORD=44|OwnerIndex=2828
|RECORD=45|OwnerIndex=2872|IndexInSheet=-1|UseComponentLibrary=T|ModelName=FP-RT0402-MFG|ModelType=PCBLIB|DatafileCount=1|ModelDatafileEntity0=FP-RT0402-MFG|ModelDatafileKind0=PCBLib|IsCurrent=T|DatalinksLocked=T|DatabaseDatalinksLocked=T
|RECORD=46|OwnerIndex=2873
|RECORD=48|OwnerIndex=2873
|RECORD=45|OwnerIndex=2872|IndexInSheet=-1|UseComponentLibrary=T|ModelName=FP-RT0402-IPC_C|ModelType=PCBLIB|DatafileCount=1|ModelDatafileEntity0=FP-RT0402-IPC_C|ModelDatafileKind0=PCBLib|DatalinksLocked=T|DatabaseDatalinksLocked=T
|RECORD=46|OwnerIndex=2876
|RECORD=48|OwnerIndex=2876
|RECORD=45|OwnerIndex=2872|IndexInSheet=-1|UseComponentLibrary=T|ModelName=FP-RT0402-IPC_B|ModelType=PCBLIB|DatafileCount=1|ModelDatafileEntity0=FP-RT0402-IPC_B|ModelDatafileKind0=PCBLib|DatalinksLocked=T|DatabaseDatalinksLocked=T
|RECORD=46|OwnerIndex=2879
|RECORD=48|OwnerIndex=2879
|RECORD=45|OwnerIndex=2872|IndexInSheet=-1|UseComponentLibrary=T|ModelName=FP-RT0402-IPC_A|ModelType=PCBLIB|DatafileCount=1|ModelDatafileEntity0=FP-RT0402-IPC_A|ModelDatafileKind0=PCBLib|DatalinksLocked=T|DatabaseDatalinksLocked=T
|RECORD=46|OwnerIndex=2882
|RECORD=48|OwnerIndex=2882
|RECORD=1|LibReference=RES|PartCount=2|DisplayModeCount=2|IndexInSheet=163|OwnerPartId=-1|Location.X=735|Location.Y=285|CurrentPartId=1|SourceLibraryName=Altium Content Vault|TargetFileName=*|AreaColor=11599871|Color=128|PartIDLocked=F|DesignItemId=CMP-2002-02670-1|AllPinCount=2
|RECORD=2|OwnerIndex=2885|OwnerPartId=1|OwnerPartDisplayMode=1|FormalType=1|Electrical=4|PinConglomerate=32|PinLength=10|Location.X=755|Location.Y=275|Name=2|Designator=2|PinPropagationDelay=0.000000E+000
|RECORD=2|OwnerIndex=2885|OwnerPartId=1|OwnerPartDisplayMode=1|FormalType=1|Electrical=4|PinConglomerate=34|PinLength=10|Location.X=735|Location.Y=275|Name=1|Designator=1|PinPropagationDelay=0.000000E+000
|RECORD=14|OwnerIndex=2885|IsNotAccesible=T|IndexInSheet=2|OwnerPartId=1|OwnerPartDisplayMode=1|Location.X=735|Location.Y=271|Corner.X=755|Corner.Y=279|LineWidth=1|Color=16711680|AreaColor=11599871
|RECORD=2|OwnerIndex=2885|OwnerPartId=1|FormalType=1|Electrical=4|PinConglomerate=32|PinLength=10|Location.X=755|Location.Y=275|Name=2|Designator=2|PinPropagationDelay=0.000000E+000
|RECORD=2|OwnerIndex=2885|OwnerPartId=1|FormalType=1|Electrical=4|PinConglomerate=34|PinLength=10|Location.X=735|Location.Y=275|Name=1|Designator=1|PinPropagationDelay=0.000000E+000
|RECORD=6|OwnerIndex=2885|IsNotAccesible=T|IndexInSheet=5|OwnerPartId=1|LineWidth=1|Color=16711680|LocationCount=10|X1=755|Y1=275|X2=751|Y2=275|X3=750|Y3=273|X4=748|Y4=277|X5=746|Y5=273|X6=744|Y6=277|X7=742|Y7=273|X8=740|Y8=277|X9=739|Y9=275|X10=735|Y10=275
|RECORD=41|OwnerIndex=2885|IndexInSheet=6|OwnerPartId=-1|Location.X=723|Location.Y=288|Color=8388608|FontID=1|IsHidden=T|Text=RT0402DRD072KL|Name=Part Number
|RECORD=41|OwnerIndex=2885|IndexInSheet=7|OwnerPartId=-1|Location.X=723|Location.Y=288|Color=8388608|FontID=1|IsHidden=T|Text=Yageo|Name=Manufacturer
|RECORD=34|OwnerIndex=2885|IndexInSheet=-1|OwnerPartId=-1|Location.X=734|Location.Y=278|Color=8388608|FontID=1|Text=R68|Name=Designator|ReadOnlyState=1
|RECORD=41|OwnerIndex=2885|IndexInSheet=-1|OwnerPartId=-1|Location.X=734|Location.Y=262|Color=8388608|FontID=1|Text=2K_0.5%_0402|Name=Comment
|RECORD=44|OwnerIndex=2885
|RECORD=45|OwnerIndex=2900|IndexInSheet=-1|Description=Chip Resistor, 2-Leads, Body 1.00x0.50mm, IPC High Density|UseComponentLibrary=T|ModelName=RESC1005X35X25LL10T10|ModelType=PCBLIB|DatafileCount=1|ModelDatafileEntity0=RESC1005X35X25LL10T10|ModelDatafileKind0=PCBLib|IsCurrent=T|DatalinksLocked=T|DatabaseDatalinksLocked=T
|RECORD=46|OwnerIndex=2901
|RECORD=48|OwnerIndex=2901
|RECORD=41|OwnerIndex=2903|IndexInSheet=-1|OwnerPartId=-1|Color=8388608|FontID=1|IsHidden=T|Text=2D|Name=Available Preview Images
|RECORD=45|OwnerIndex=2900|IndexInSheet=-1|Description=Chip Resistor, 2-Leads, Body 1.00x0.50mm, IPC Medium Density|UseComponentLibrary=T|ModelName=RESC1005X35X25NL10T10|ModelType=PCBLIB|DatafileCount=1|ModelDatafileEntity0=RESC1005X35X25NL10T10|ModelDatafileKind0=PCBLib|DatalinksLocked=T|DatabaseDatalinksLocked=T
|RECORD=46|OwnerIndex=2905
|RECORD=48|OwnerIndex=2905
|RECORD=41|OwnerIndex=2907|IndexInSheet=-1|OwnerPartId=-1|Color=8388608|FontID=1|IsHidden=T|Text=2D|Name=Available Preview Images
|RECORD=45|OwnerIndex=2900|IndexInSheet=-1|Description=Chip Resistor, 2-Leads, Body 1.00x0.50mm, IPC Low Density|UseComponentLibrary=T|ModelName=RESC1005X35X25ML10T10|ModelType=PCBLIB|DatafileCount=1|ModelDatafileEntity0=RESC1005X35X25ML10T10|ModelDatafileKind0=PCBLib|DatalinksLocked=T|DatabaseDatalinksLocked=T
|RECORD=46|OwnerIndex=2909
|RECORD=48|OwnerIndex=2909
|RECORD=41|OwnerIndex=2911|IndexInSheet=-1|OwnerPartId=-1|Color=8388608|FontID=1|IsHidden=T|Text=2D|Name=Available Preview Images
|RECORD=17|IndexInSheet=164|OwnerPartId=-1|ShowNetName=T|Location.X=790|Location.Y=275|Color=128|FontID=1|Text=P3V3_SENSE
|RECORD=17|IndexInSheet=165|OwnerPartId=-1|Style=4|ShowNetName=T|Location.X=865|Location.Y=120|Color=128|FontID=1|Text=GND
|RECORD=17|IndexInSheet=166|OwnerPartId=-1|ShowNetName=T|Location.X=820|Location.Y=135|Color=255|FontID=1|Text=P3V3_MUN_FB|IsCrossSheetConnector=T
|RECORD=17|IndexInSheet=167|OwnerPartId=-1|ShowNetName=T|Location.X=620|Location.Y=275|Orientation=2|Color=255|FontID=1|Text=P3V3_MUN_FB|IsCrossSheetConnector=T
|RECORD=1|LibReference=MUN12AD06-SM|ComponentDescription=No Description Available|PartCount=2|DisplayModeCount=1|IndexInSheet=168|OwnerPartId=-1|Location.X=980|Location.Y=950|CurrentPartId=1|LibraryPath=*|SourceLibraryName=MUN12AD06-SM.SchLib|TargetFileName=*|AreaColor=11599871|Color=128|PartIDLocked=T|DesignItemId=MUN12AD06-SM|AllPinCount=25
|RECORD=41|OwnerIndex=2917|OwnerPartId=1|Location.X=980|Location.Y=950|FontID=1|IsHidden=T|Text=Cyntec|Name=Mfr_Name
|RECORD=41|OwnerIndex=2917|IndexInSheet=1|OwnerPartId=1|Location.X=1080|Location.Y=990|FontID=1|IsHidden=T|Text=RefDes|Name=RefDes
|RECORD=41|OwnerIndex=2917|IndexInSheet=2|OwnerPartId=1|Location.X=1080|Location.Y=980|FontID=1|IsHidden=T|Text=Type|Name=Type
|RECORD=2|OwnerIndex=2917|OwnerPartId=1|FormalType=1|Electrical=7|PinConglomerate=58|PinLength=30|Location.X=1010|Location.Y=950|Name=VIN|Designator=1|SwapIdPin=0|SwapIDPart=0Ž&Ž1|PinPropagationDelay=0.000000E+000
|RECORD=2|OwnerIndex=2917|OwnerPartId=1|FormalType=1|Electrical=2|PinConglomerate=58|PinLength=30|Location.X=1010|Location.Y=940|Name=PHASE|Designator=2|SwapIdPin=0|SwapIDPart=0Ž&Ž2|PinPropagationDelay=0.000000E+000
|RECORD=2|OwnerIndex=2917|OwnerPartId=1|FormalType=1|Electrical=2|PinConglomerate=58|PinLength=30|Location.X=1010|Location.Y=930|Name=PHASE|Designator=3|SwapIdPin=0|SwapIDPart=0Ž&Ž3|PinPropagationDelay=0.000000E+000
|RECORD=2|OwnerIndex=2917|OwnerPartId=1|FormalType=1|Electrical=2|PinConglomerate=58|PinLength=30|Location.X=1010|Location.Y=920|Name=PHASE|Designator=4|SwapIdPin=0|SwapIDPart=0Ž&Ž4|PinPropagationDelay=0.000000E+000
|RECORD=2|OwnerIndex=2917|OwnerPartId=1|FormalType=1|Electrical=7|PinConglomerate=58|PinLength=30|Location.X=1010|Location.Y=910|Name=GND|Designator=5|SwapIdPin=0|SwapIDPart=0Ž&Ž5|PinPropagationDelay=0.000000E+000
|RECORD=2|OwnerIndex=2917|OwnerPartId=1|FormalType=1|Electrical=7|PinConglomerate=58|PinLength=30|Location.X=1010|Location.Y=900|Name=GND|Designator=6|SwapIdPin=0|SwapIDPart=0Ž&Ž6|PinPropagationDelay=0.000000E+000
|RECORD=2|OwnerIndex=2917|OwnerPartId=1|FormalType=1|Electrical=7|PinConglomerate=58|PinLength=30|Location.X=1010|Location.Y=890|Name=GND|Designator=7|SwapIdPin=0|SwapIDPart=0Ž&Ž7|PinPropagationDelay=0.000000E+000
|RECORD=2|OwnerIndex=2917|OwnerPartId=1|FormalType=1|PinConglomerate=58|PinLength=30|Location.X=1010|Location.Y=880|Name=EN|Designator=8|SwapIdPin=0|SwapIDPart=0Ž&Ž8|PinPropagationDelay=0.000000E+000
|RECORD=2|OwnerIndex=2917|OwnerPartId=1|FormalType=1|Electrical=2|PinConglomerate=58|PinLength=30|Location.X=1010|Location.Y=870|Name=PGOOD|Designator=9|SwapIdPin=0|SwapIDPart=0Ž&Ž9|PinPropagationDelay=0.000000E+000
|RECORD=2|OwnerIndex=2917|OwnerPartId=1|FormalType=1|Electrical=2|PinConglomerate=58|PinLength=30|Location.X=1010|Location.Y=860|Name=VOUT|Designator=10|SwapIdPin=0|SwapIDPart=0Ž&Ž10|PinPropagationDelay=0.000000E+000
|RECORD=2|OwnerIndex=2917|OwnerPartId=1|FormalType=1|Electrical=2|PinConglomerate=58|PinLength=30|Location.X=1010|Location.Y=850|Name=VOUT|Designator=11|SwapIdPin=0|SwapIDPart=0Ž&Ž11|PinPropagationDelay=0.000000E+000
|RECORD=2|OwnerIndex=2917|OwnerPartId=1|FormalType=1|Electrical=2|PinConglomerate=58|PinLength=30|Location.X=1010|Location.Y=840|Name=VOUT|Designator=12|SwapIdPin=0|SwapIDPart=0Ž&Ž12|PinPropagationDelay=0.000000E+000
|RECORD=2|OwnerIndex=2917|OwnerPartId=1|FormalType=1|Electrical=2|PinConglomerate=56|PinLength=30|Location.X=1150|Location.Y=830|Name=VOUT|Designator=13|SwapIdPin=0|SwapIDPart=0Ž&Ž13|PinPropagationDelay=0.000000E+000
|RECORD=2|OwnerIndex=2917|OwnerPartId=1|FormalType=1|Electrical=2|PinConglomerate=56|PinLength=30|Location.X=1150|Location.Y=840|Name=VOUT|Designator=14|SwapIdPin=0|SwapIDPart=0Ž&Ž14|PinPropagationDelay=0.000000E+000
|RECORD=2|OwnerIndex=2917|OwnerPartId=1|FormalType=1|Electrical=4|PinConglomerate=56|PinLength=30|Location.X=1150|Location.Y=850|Name=ILIM|Designator=15|SwapIdPin=0|SwapIDPart=0Ž&Ž15|PinPropagationDelay=0.000000E+000
|RECORD=2|OwnerIndex=2917|OwnerPartId=1|FormalType=1|PinConglomerate=56|PinLength=30|Location.X=1150|Location.Y=860|Name=FB|Designator=16|SwapIdPin=0|SwapIDPart=0Ž&Ž16|PinPropagationDelay=0.000000E+000
|RECORD=2|OwnerIndex=2917|OwnerPartId=1|FormalType=1|Electrical=7|PinConglomerate=56|PinLength=30|Location.X=1150|Location.Y=870|Name=VCC|Designator=17|SwapIdPin=0|SwapIDPart=0Ž&Ž17|PinPropagationDelay=0.000000E+000
|RECORD=2|OwnerIndex=2917|OwnerPartId=1|FormalType=1|Electrical=7|PinConglomerate=56|PinLength=30|Location.X=1150|Location.Y=880|Name=BST|Designator=18|SwapIdPin=0|SwapIDPart=0Ž&Ž18|PinPropagationDelay=0.000000E+000
|RECORD=2|OwnerIndex=2917|OwnerPartId=1|FormalType=1|Electrical=7|PinConglomerate=56|PinLength=30|Location.X=1150|Location.Y=890|Name=VIN|Designator=19|SwapIdPin=0|SwapIDPart=0Ž&Ž19|PinPropagationDelay=0.000000E+000
|RECORD=2|OwnerIndex=2917|OwnerPartId=1|FormalType=1|Electrical=7|PinConglomerate=56|PinLength=30|Location.X=1150|Location.Y=900|Name=VIN|Designator=20|SwapIdPin=0|SwapIDPart=0Ž&Ž20|PinPropagationDelay=0.000000E+000
|RECORD=2|OwnerIndex=2917|OwnerPartId=1|FormalType=1|Electrical=7|PinConglomerate=56|PinLength=30|Location.X=1150|Location.Y=910|Name=VIN_TPD|Designator=21|SwapIdPin=0|SwapIDPart=0Ž&Ž21|PinPropagationDelay=0.000000E+000
|RECORD=2|OwnerIndex=2917|OwnerPartId=1|FormalType=1|Electrical=2|PinConglomerate=56|PinLength=30|Location.X=1150|Location.Y=920|Name=PHASE_TPD|Designator=22|SwapIdPin=0|SwapIDPart=0Ž&Ž22|PinPropagationDelay=0.000000E+000
|RECORD=2|OwnerIndex=2917|OwnerPartId=1|FormalType=1|Electrical=7|PinConglomerate=56|PinLength=30|Location.X=1150|Location.Y=930|Name=GND_TPD|Designator=23|SwapIdPin=0|SwapIDPart=0Ž&Ž23|PinPropagationDelay=0.000000E+000
|RECORD=2|OwnerIndex=2917|OwnerPartId=1|FormalType=1|Electrical=2|PinConglomerate=56|PinLength=30|Location.X=1150|Location.Y=940|Name=VOUT_TPD|Designator=24|SwapIdPin=0|SwapIDPart=0Ž&Ž24|PinPropagationDelay=0.000000E+000
|RECORD=2|OwnerIndex=2917|OwnerPartId=1|FormalType=1|Electrical=7|PinConglomerate=56|PinLength=30|Location.X=1150|Location.Y=950|Name=GND_TPD|Designator=25|SwapIdPin=0|SwapIDPart=0Ž&Ž25|PinPropagationDelay=0.000000E+000
|RECORD=14|OwnerIndex=2917|IsNotAccesible=T|IndexInSheet=28|OwnerPartId=1|Location.X=1010|Location.Y=810|Corner.X=1150|Corner.Y=970|LineWidth=1|AreaColor=11599871|IsSolid=T|Transparent=T
|RECORD=34|OwnerIndex=2917|IndexInSheet=-1|OwnerPartId=-1|Location.X=1010|Location.Y=970|Color=8388608|FontID=1|Text=U1|Name=Designator|ReadOnlyState=1
|RECORD=41|OwnerIndex=2917|IndexInSheet=-1|OwnerPartId=-1|Location.X=1010|Location.Y=800|Color=8388608|FontID=1|Text=MUN12AD06-SM|Name=Comment
|RECORD=44|OwnerIndex=2917
|RECORD=45|OwnerIndex=2974|IndexInSheet=-1|ModelName=MUN12AD06-SM_CYN|ModelType=PCBLIB|DatafileCount=1|ModelDatafileEntity0=MUN12AD06-SM_CYN|ModelDatafileKind0=PCBLIB|IsCurrent=T
|RECORD=46|OwnerIndex=2975
|RECORD=48|OwnerIndex=2975
|RECORD=17|IndexInSheet=169|OwnerPartId=-1|ShowNetName=T|Location.X=960|Location.Y=965|Orientation=1|Color=128|FontID=1|Text=+12V
|RECORD=17|IndexInSheet=170|OwnerPartId=-1|Style=4|ShowNetName=T|Location.X=960|Location.Y=815|Orientation=3|Color=128|FontID=1|Text=GND
|RECORD=17|IndexInSheet=171|OwnerPartId=-1|ShowNetName=T|Location.X=915|Location.Y=940|Orientation=2|Color=255|FontID=1|Text=P5V_MUN_PHASE|IsCrossSheetConnector=T
|RECORD=17|IndexInSheet=172|OwnerPartId=-1|ShowNetName=T|Location.X=1220|Location.Y=920|Color=255|FontID=1|Text=P5V_MUN_PHASE|IsCrossSheetConnector=T
|RECORD=17|IndexInSheet=173|OwnerPartId=-1|ShowNetName=T|Location.X=1230|Location.Y=910|Color=128|FontID=1|Text=+12V
|RECORD=17|IndexInSheet=174|OwnerPartId=-1|Style=4|ShowNetName=T|Location.X=1230|Location.Y=950|Color=128|FontID=1|Text=GND
|RECORD=17|IndexInSheet=175|OwnerPartId=-1|ShowNetName=T|Location.X=925|Location.Y=840|Orientation=2|Color=128|FontID=1|Text=P5V_SENSE
|RECORD=17|IndexInSheet=176|OwnerPartId=-1|ShowNetName=T|Location.X=1220|Location.Y=830|Color=128|FontID=1|Text=P5V_SENSE
|RECORD=17|IndexInSheet=177|OwnerPartId=-1|ShowNetName=T|Location.X=1265|Location.Y=940|Color=128|FontID=1|Text=P5V_SENSE
|RECORD=1|LibReference=RES-2|ComponentDescription=Chip Resistor, 0 Ohm, 0.1 W, -55 to 155 degC, 0402 (1005 Metric), RoHS, Tape and Reel|PartCount=2|DisplayModeCount=1|IndexInSheet=178|OwnerPartId=-1|Location.X=860|Location.Y=880|CurrentPartId=1|LibraryPath=*|SourceLibraryName=Altium Content Vault|TargetFileName=*|AreaColor=11599871|Color=128|PartIDLocked=T|DesignItemId=CMP-2000-07451-1|AllPinCount=2
|RECORD=2|OwnerIndex=2987|OwnerPartId=1|FormalType=1|Electrical=4|PinConglomerate=32|PinLength=10|Location.X=880|Location.Y=880|Name=2|Designator=2|PinPropagationDelay=0.000000E+000
|RECORD=2|OwnerIndex=2987|OwnerPartId=1|FormalType=1|Electrical=4|PinConglomerate=34|PinLength=10|Location.X=860|Location.Y=880|Name=1|Designator=1|PinPropagationDelay=0.000000E+000
|RECORD=6|OwnerIndex=2987|IsNotAccesible=T|IndexInSheet=2|OwnerPartId=1|LineWidth=1|Color=16711680|LocationCount=10|X1=880|Y1=880|X2=876|Y2=880|X3=875|Y3=878|X4=873|Y4=882|X5=871|Y5=878|X6=869|Y6=882|X7=867|Y7=878|X8=865|Y8=882|X9=864|Y9=880|X10=860|Y10=880
|RECORD=41|OwnerIndex=2987|IndexInSheet=3|OwnerPartId=-1|Location.X=848|Location.Y=895|Color=8388608|FontID=1|IsHidden=T|Text=50V|Name=Voltage Rating (DC)
|RECORD=41|OwnerIndex=2987|IndexInSheet=4|OwnerPartId=-1|Location.X=848|Location.Y=895|Color=8388608|FontID=1|IsHidden=T|Text=2|Name=Number of Terminations
|RECORD=41|OwnerIndex=2987|IndexInSheet=5|OwnerPartId=-1|Location.X=848|Location.Y=895|Color=8388608|FontID=1|IsHidden=T|Text=SurfaceMount|Name=Mount
|RECORD=41|OwnerIndex=2987|IndexInSheet=6|OwnerPartId=-1|Location.X=848|Location.Y=895|Color=8388608|FontID=1|IsHidden=T|Text=0.35mm|Name=Height
|RECORD=41|OwnerIndex=2987|IndexInSheet=7|OwnerPartId=-1|Location.X=848|Location.Y=895|Color=8388608|FontID=1|IsHidden=T|Text=TapeandReel|Name=Packaging
|RECORD=41|OwnerIndex=2987|IndexInSheet=8|OwnerPartId=-1|Location.X=848|Location.Y=895|Color=8388608|FontID=1|IsHidden=T|Text=Tin|Name=Contact Plating
|RECORD=41|OwnerIndex=2987|IndexInSheet=9|OwnerPartId=-1|Location.X=848|Location.Y=895|Color=8388608|FontID=3|IsHidden=T|Text=http://www.panasonic.com/|Name=Manufacturer URL
|RECORD=41|OwnerIndex=2987|IndexInSheet=10|OwnerPartId=-1|Location.X=848|Location.Y=895|Color=8388608|FontID=1|IsHidden=T|Text=ThickFilm|Name=Composition
|RECORD=41|OwnerIndex=2987|IndexInSheet=11|OwnerPartId=-1|Location.X=848|Location.Y=895|Color=8388608|FontID=1|IsHidden=T|Text=155degC|Name=Max Operating Temperature
|RECORD=41|OwnerIndex=2987|IndexInSheet=12|OwnerPartId=-1|Location.X=848|Location.Y=895|Color=8388608|FontID=1|IsHidden=T|Text=600ppm/??C|Name=Temperature Coefficient
|RECORD=41|OwnerIndex=2987|IndexInSheet=13|OwnerPartId=-1|Location.X=848|Location.Y=895|Color=8388608|FontID=1|IsHidden=T|Text=NoSVHC|Name=REACH SVHC
|RECORD=41|OwnerIndex=2987|IndexInSheet=14|OwnerPartId=-1|Location.X=848|Location.Y=895|Color=8388608|FontID=1|IsHidden=T|Text=0402|Name=Case/Package
|RECORD=41|OwnerIndex=2987|IndexInSheet=15|OwnerPartId=-1|Location.X=848|Location.Y=895|Color=8388608|FontID=1|IsHidden=T|Text=100mW|Name=Max Power Dissipation
|RECORD=41|OwnerIndex=2987|IndexInSheet=16|OwnerPartId=-1|Location.X=848|Location.Y=895|Color=8388608|FontID=1|IsHidden=T|Text=402|Name=Package Reference
|RECORD=41|OwnerIndex=2987|IndexInSheet=17|OwnerPartId=-1|Location.X=848|Location.Y=895|Color=8388608|FontID=1|IsHidden=T|Text=0.5mm|Name=Depth
|RECORD=41|OwnerIndex=2987|IndexInSheet=18|OwnerPartId=-1|Location.X=848|Location.Y=895|Color=8388608|FontID=1|IsHidden=T|Text=Panasonic|Name=Manufacturer
|RECORD=41|OwnerIndex=2987|IndexInSheet=19|OwnerPartId=-1|Location.X=848|Location.Y=895|Color=8388608|FontID=1|IsHidden=T|Text=2-Pin Surface Mount Device, Body 1 x 0.5 mm|Name=Package Description
|RECORD=41|OwnerIndex=2987|IndexInSheet=20|OwnerPartId=-1|Location.X=848|Location.Y=895|Color=8388608|FontID=3|IsHidden=T|Text=https://industrial.panasonic.com/cdbs/www-data/pdf/RDA0000/AOA0000C301.pdf|Name=Datasheet URL
|RECORD=41|OwnerIndex=2987|IndexInSheet=21|OwnerPartId=-1|Location.X=848|Location.Y=895|Color=8388608|FontID=1|IsHidden=T|Text=True|Name=RoHSCompliant
|RECORD=41|OwnerIndex=2987|IndexInSheet=22|OwnerPartId=-1|Location.X=848|Location.Y=895|Color=8388608|FontID=1|IsHidden=T|Text=0402|Name=Case Code (Imperial)
|RECORD=41|OwnerIndex=2987|IndexInSheet=23|OwnerPartId=-1|Location.X=848|Location.Y=895|Color=8388608|FontID=1|IsHidden=T|Text=0mOhm|Name=Resistance
|RECORD=41|OwnerIndex=2987|IndexInSheet=24|OwnerPartId=-1|Location.X=848|Location.Y=895|Color=8388608|FontID=1|IsHidden=T|Text=Not|Name=Military Standard
|RECORD=41|OwnerIndex=2987|IndexInSheet=25|OwnerPartId=-1|Location.X=848|Location.Y=895|Color=8388608|FontID=1|IsHidden=T|Text=5%|Name=Tolerance
|RECORD=41|OwnerIndex=2987|IndexInSheet=26|OwnerPartId=-1|Location.X=848|Location.Y=895|Color=8388608|FontID=1|IsHidden=T|Text=-55degC|Name=Min Operating Temperature
|RECORD=41|OwnerIndex=2987|IndexInSheet=27|OwnerPartId=-1|Location.X=848|Location.Y=895|Color=8388608|FontID=1|IsHidden=T|Text=100mW|Name=Power Rating
|RECORD=41|OwnerIndex=2987|IndexInSheet=28|OwnerPartId=-1|Location.X=848|Location.Y=895|Color=8388608|FontID=1|IsHidden=T|Text=03/2015|Name=Datasheet Version
|RECORD=41|OwnerIndex=2987|IndexInSheet=29|OwnerPartId=-1|Location.X=848|Location.Y=895|Color=8388608|FontID=1|IsHidden=T|Text=1mm|Name=Length
|RECORD=41|OwnerIndex=2987|IndexInSheet=30|OwnerPartId=-1|Location.X=848|Location.Y=895|Color=8388608|FontID=1|IsHidden=T|Text=1005|Name=Case Code (Metric)
|RECORD=41|OwnerIndex=2987|IndexInSheet=31|OwnerPartId=-1|Location.X=848|Location.Y=895|Color=8388608|FontID=1|IsHidden=T|Text=SMD/SMT|Name=Termination
|RECORD=41|OwnerIndex=2987|IndexInSheet=32|OwnerPartId=-1|Location.X=848|Location.Y=895|Color=8388608|FontID=1|IsHidden=T|Text=SurfaceMount|Name=Mounting Technology
|RECORD=41|OwnerIndex=2987|IndexInSheet=33|OwnerPartId=-1|Location.X=848|Location.Y=895|Color=8388608|FontID=1|IsHidden=T|Text=50V|Name=Voltage Rating
|RECORD=41|OwnerIndex=2987|IndexInSheet=34|OwnerPartId=-1|Location.X=848|Location.Y=895|Color=8388608|FontID=1|IsHidden=T|Text=0.02inch|Name=Width
|RECORD=41|OwnerIndex=2987|IndexInSheet=35|OwnerPartId=-1|Location.X=848|Location.Y=895|Color=8388608|FontID=1|IsHidden=T|Text=1|Name=Package Quantity
|RECORD=41|OwnerIndex=2987|IndexInSheet=36|OwnerPartId=-1|Location.X=848|Location.Y=895|Color=8388608|FontID=1|IsHidden=T|Text=LeadFree|Name=Lead Free
|RECORD=41|OwnerIndex=2987|IndexInSheet=37|OwnerPartId=-1|Location.X=848|Location.Y=895|Color=8388608|FontID=1|IsHidden=T|Text=No|Name=Radiation Hardening
|RECORD=34|OwnerIndex=2987|IndexInSheet=-1|OwnerPartId=-1|Location.X=840|Location.Y=880|Color=8388608|FontID=1|Text=R4|Name=Designator|ReadOnlyState=1
|RECORD=41|OwnerIndex=2987|IndexInSheet=-1|OwnerPartId=-1|Location.X=880|Location.Y=880|Color=8388608|FontID=1|Text=0_1%_0402|Name=Comment
|RECORD=44|OwnerIndex=2987
|RECORD=45|OwnerIndex=3030|IndexInSheet=-1|Description=Chip Resistor, 2-Leads, Body 1.05x0.55mm, IPC High Density|UseComponentLibrary=T|ModelName=RESC1005X40X25LL05T05|ModelType=PCBLIB|DatafileCount=1|ModelDatafileEntity0=RESC1005X40X25LL05T05|ModelDatafileKind0=PCBLib|IsCurrent=T|DatalinksLocked=T|DatabaseDatalinksLocked=T
|RECORD=46|OwnerIndex=3031
|RECORD=48|OwnerIndex=3031
|RECORD=41|OwnerIndex=3033|IndexInSheet=-1|OwnerPartId=-1|Color=8388608|FontID=1|IsHidden=T|Text=2D|Name=Available Preview Images
|RECORD=45|OwnerIndex=3030|IndexInSheet=-1|Description=Chip Resistor, 2-Leads, Body 1.05x0.55mm, IPC Low Density|UseComponentLibrary=T|ModelName=RESC1005X40X25ML05T05|ModelType=PCBLIB|DatafileCount=1|ModelDatafileEntity0=RESC1005X40X25ML05T05|ModelDatafileKind0=PCBLib|DatalinksLocked=T|DatabaseDatalinksLocked=T
|RECORD=46|OwnerIndex=3035
|RECORD=48|OwnerIndex=3035
|RECORD=41|OwnerIndex=3037|IndexInSheet=-1|OwnerPartId=-1|Color=8388608|FontID=1|IsHidden=T|Text=2D|Name=Available Preview Images
|RECORD=45|OwnerIndex=3030|IndexInSheet=-1|Description=Chip Resistor, 2-Leads, Body 1.05x0.55mm, IPC Medium Density|UseComponentLibrary=T|ModelName=RESC1005X40X25NL05T05|ModelType=PCBLIB|DatafileCount=1|ModelDatafileEntity0=RESC1005X40X25NL05T05|ModelDatafileKind0=PCBLib|DatalinksLocked=T|DatabaseDatalinksLocked=T
|RECORD=46|OwnerIndex=3039
|RECORD=48|OwnerIndex=3039
|RECORD=41|OwnerIndex=3041|IndexInSheet=-1|OwnerPartId=-1|Color=8388608|FontID=1|IsHidden=T|Text=2D|Name=Available Preview Images
|RECORD=1|LibReference=RES|PartCount=2|DisplayModeCount=2|IndexInSheet=179|OwnerPartId=-1|Location.X=880|Location.Y=855|Orientation=2|CurrentPartId=1|SourceLibraryName=Altium Content Vault|TargetFileName=*|AreaColor=11599871|Color=128|PartIDLocked=F|DesignItemId=CMP-2002-05217-1|AllPinCount=2
|RECORD=2|OwnerIndex=3043|OwnerPartId=1|OwnerPartDisplayMode=1|FormalType=1|Electrical=4|PinConglomerate=34|PinLength=10|Location.X=860|Location.Y=865|Name=2|Designator=2|PinPropagationDelay=0.000000E+000
|RECORD=2|OwnerIndex=3043|OwnerPartId=1|OwnerPartDisplayMode=1|FormalType=1|Electrical=4|PinConglomerate=32|PinLength=10|Location.X=880|Location.Y=865|Name=1|Designator=1|PinPropagationDelay=0.000000E+000
|RECORD=14|OwnerIndex=3043|IsNotAccesible=T|IndexInSheet=2|OwnerPartId=1|OwnerPartDisplayMode=1|Location.X=860|Location.Y=861|Corner.X=880|Corner.Y=869|LineWidth=1|Color=16711680|AreaColor=11599871
|RECORD=2|OwnerIndex=3043|OwnerPartId=1|FormalType=1|Electrical=4|PinConglomerate=34|PinLength=10|Location.X=860|Location.Y=865|Name=2|Designator=2|PinPropagationDelay=0.000000E+000
|RECORD=2|OwnerIndex=3043|OwnerPartId=1|FormalType=1|Electrical=4|PinConglomerate=32|PinLength=10|Location.X=880|Location.Y=865|Name=1|Designator=1|PinPropagationDelay=0.000000E+000
|RECORD=6|OwnerIndex=3043|IsNotAccesible=T|IndexInSheet=5|OwnerPartId=1|LineWidth=1|Color=16711680|LocationCount=10|X1=860|Y1=865|X2=864|Y2=865|X3=865|Y3=867|X4=867|Y4=863|X5=869|Y5=867|X6=871|Y6=863|X7=873|Y7=867|X8=875|Y8=863|X9=876|Y9=865|X10=880|Y10=865
|RECORD=41|OwnerIndex=3043|IndexInSheet=6|OwnerPartId=-1|Location.X=848|Location.Y=868|Color=8388608|FontID=1|IsHidden=T|Text=Bourns|Name=Manufacturer
|RECORD=41|OwnerIndex=3043|IndexInSheet=7|OwnerPartId=-1|Location.X=848|Location.Y=868|Color=8388608|FontID=1|IsHidden=T|Text=CR0402-FX-4701GLF|Name=Part Number
|RECORD=34|OwnerIndex=3043|IndexInSheet=-1|OwnerPartId=-1|Location.X=859|Location.Y=868|Color=8388608|FontID=1|Text=R5|Name=Designator|ReadOnlyState=1
|RECORD=41|OwnerIndex=3043|IndexInSheet=-1|OwnerPartId=-1|Location.X=859|Location.Y=852|Color=8388608|FontID=1|Text=4.7K_1%_0402|Name=Comment
|RECORD=44|OwnerIndex=3043
|RECORD=45|OwnerIndex=3058|IndexInSheet=-1|Description=Chip Resistor, 2-Leads, Body 1.00x0.50mm, IPC Medium Density|UseComponentLibrary=T|ModelName=RESC1005X40X25NL10T10|ModelType=PCBLIB|DatafileCount=1|ModelDatafileEntity0=RESC1005X40X25NL10T10|ModelDatafileKind0=PCBLib|IsCurrent=T|DatalinksLocked=T|DatabaseDatalinksLocked=T
|RECORD=46|OwnerIndex=3059
|RECORD=48|OwnerIndex=3059
|RECORD=41|OwnerIndex=3061|IndexInSheet=-1|OwnerPartId=-1|Color=8388608|FontID=1|IsHidden=T|Text=2D|Name=Available Preview Images
|RECORD=45|OwnerIndex=3058|IndexInSheet=-1|Description=Chip Resistor, 2-Leads, Body 1.00x0.50mm, IPC High Density|UseComponentLibrary=T|ModelName=RESC1005X40X25LL10T10|ModelType=PCBLIB|DatafileCount=1|ModelDatafileEntity0=RESC1005X40X25LL10T10|ModelDatafileKind0=PCBLib|DatalinksLocked=T|DatabaseDatalinksLocked=T
|RECORD=46|OwnerIndex=3063
|RECORD=48|OwnerIndex=3063
|RECORD=41|OwnerIndex=3065|IndexInSheet=-1|OwnerPartId=-1|Color=8388608|FontID=1|IsHidden=T|Text=2D|Name=Available Preview Images
|RECORD=45|OwnerIndex=3058|IndexInSheet=-1|Description=Chip Resistor, 2-Leads, Body 1.00x0.50mm, IPC Low Density|UseComponentLibrary=T|ModelName=RESC1005X40X25ML10T10|ModelType=PCBLIB|DatafileCount=1|ModelDatafileEntity0=RESC1005X40X25ML10T10|ModelDatafileKind0=PCBLib|DatalinksLocked=T|DatabaseDatalinksLocked=T
|RECORD=46|OwnerIndex=3067
|RECORD=48|OwnerIndex=3067
|RECORD=41|OwnerIndex=3069|IndexInSheet=-1|OwnerPartId=-1|Color=8388608|FontID=1|IsHidden=T|Text=2D|Name=Available Preview Images
|RECORD=17|IndexInSheet=180|OwnerPartId=-1|ShowNetName=T|Location.X=820|Location.Y=905|Orientation=1|Color=128|FontID=1|Text=+12V
|RECORD=17|IndexInSheet=181|OwnerPartId=-1|ShowNetName=T|Location.X=1255|Location.Y=870|Color=128|FontID=1|Text=P5V_MUN_VCC
|RECORD=17|IndexInSheet=182|OwnerPartId=-1|ShowNetName=T|Location.X=1285|Location.Y=1035|Orientation=1|Color=128|FontID=1|Text=P5V_MUN_VCC
|RECORD=1|LibReference=b4654b650e69147ec39a6b967a45e02|ComponentDescription=Multilayer Ceramic Capacitors 2.2µF ±10% 16V X5R SMD 0402|PartCount=2|DisplayModeCount=1|IndexInSheet=183|OwnerPartId=-1|Location.X=1285|Location.Y=1025|CurrentPartId=1|LibraryPath=*|SourceLibraryName=Altium Content Vault|TargetFileName=*|AreaColor=11599871|Color=128|PartIDLocked=T|DesignItemId=CMP-2000-05998-2|AllPinCount=2
|RECORD=2|OwnerIndex=3074|OwnerPartId=1|Electrical=4|PinConglomerate=49|PinLength=7|Location.X=1285|Location.Y=1018|Name=1|Designator=1|PinPropagationDelay=0.000000E+000
|RECORD=2|OwnerIndex=3074|OwnerPartId=1|Electrical=4|PinConglomerate=51|PinLength=6|Location.X=1285|Location.Y=1011|Name=2|Designator=2|PinPropagationDelay=0.000000E+000
|RECORD=13|OwnerIndex=3074|IsNotAccesible=T|IndexInSheet=2|OwnerPartId=1|Location.X=1295|Location.Y=1018|Corner.X=1275|Corner.Y=1018|LineWidth=1|Color=16711680
|RECORD=13|OwnerIndex=3074|IsNotAccesible=T|IndexInSheet=3|OwnerPartId=1|Location.X=1295|Location.Y=1012|Corner.X=1275|Corner.Y=1012|LineWidth=1|Color=16711680
|RECORD=13|OwnerIndex=3074|IsNotAccesible=T|IndexInSheet=4|OwnerPartId=1|Location.X=1285|Location.Y=1018|Corner.X=1285|Corner.Y=1021|LineWidth=1|Color=16711680
|RECORD=13|OwnerIndex=3074|IsNotAccesible=T|IndexInSheet=5|OwnerPartId=1|Location.X=1285|Location.Y=1011|Corner.X=1285|Corner.Y=1010|LineWidth=1|Color=16711680
|RECORD=41|OwnerIndex=3074|IndexInSheet=6|OwnerPartId=-1|Location.X=1274|Location.Y=1027|Color=8388608|FontID=1|IsHidden=T|Text=No SVHC|Name=REACH SVHC
|RECORD=41|OwnerIndex=3074|IndexInSheet=7|OwnerPartId=-1|Location.X=1274|Location.Y=1027|Color=8388608|FontID=1|IsHidden=T|Text=C|Name=Series
|RECORD=41|OwnerIndex=3074|IndexInSheet=8|OwnerPartId=-1|Location.X=1274|Location.Y=1027|Color=8388608|FontID=1|IsHidden=T|Text=SMD/SMT|Name=Termination
|RECORD=41|OwnerIndex=3074|IndexInSheet=9|OwnerPartId=-1|Location.X=1274|Location.Y=1027|Color=8388608|FontID=1|IsHidden=T|Text=0402|Name=Case Code (Imperial)
|RECORD=41|OwnerIndex=3074|IndexInSheet=10|OwnerPartId=-1|Location.X=1274|Location.Y=1027|Color=8388608|FontID=1|IsHidden=T|Text=0.5mm|Name=Depth
|RECORD=41|OwnerIndex=3074|IndexInSheet=11|OwnerPartId=-1|Location.X=1274|Location.Y=1027|Color=8388608|FontID=1|IsHidden=T|Text=Surface Mount|Name=Mount
|RECORD=41|OwnerIndex=3074|IndexInSheet=12|OwnerPartId=-1|Location.X=1274|Location.Y=1027|Color=8388608|FontID=1|IsHidden=T|Text=0.02inch|Name=Width
|RECORD=41|OwnerIndex=3074|IndexInSheet=13|OwnerPartId=-1|Location.X=1274|Location.Y=1027|Color=8388608|FontID=1|IsHidden=T|Text=1|Name=Package Quantity
|RECORD=41|OwnerIndex=3074|IndexInSheet=14|OwnerPartId=-1|Location.X=1274|Location.Y=1027|Color=8388608|FontID=1|IsHidden=T|Text=Ceramic|Name=Dielectric Material
|RECORD=41|OwnerIndex=3074|IndexInSheet=15|OwnerPartId=-1|Location.X=1274|Location.Y=1027|Color=8388608|FontID=1|IsHidden=T|Text=1mm|Name=Length
|RECORD=41|OwnerIndex=3074|IndexInSheet=16|OwnerPartId=-1|Location.X=1274|Location.Y=1027|Color=8388608|FontID=1|IsHidden=T|Text=Tape and Reel|Name=Packaging
|RECORD=41|OwnerIndex=3074|IndexInSheet=17|OwnerPartId=-1|Location.X=1274|Location.Y=1027|Color=8388608|FontID=1|IsHidden=T|Text=1005|Name=Case Code (Metric)
|RECORD=41|OwnerIndex=3074|IndexInSheet=18|OwnerPartId=-1|Location.X=1274|Location.Y=1027|Color=8388608|FontID=1|IsHidden=T|Text=Yes|Name=RoHS Compliant
|RECORD=41|OwnerIndex=3074|IndexInSheet=19|OwnerPartId=-1|Location.X=1274|Location.Y=1027|Color=8388608|FontID=1|IsHidden=T|Text=X5R|Name=Dielectric
|RECORD=41|OwnerIndex=3074|IndexInSheet=20|OwnerPartId=-1|Location.X=1274|Location.Y=1027|Color=8388608|FontID=1|IsHidden=T|Text=85°C|Name=Max Operating Temperature
|RECORD=41|OwnerIndex=3074|IndexInSheet=21|OwnerPartId=-1|Location.X=1274|Location.Y=1027|Color=8388608|FontID=1|IsHidden=T|Text=Lead Free|Name=Lead Free
|RECORD=41|OwnerIndex=3074|IndexInSheet=22|OwnerPartId=-1|Location.X=1274|Location.Y=1027|Color=8388608|FontID=1|IsHidden=T|Text=2.3E-05oz|Name=Weight
|RECORD=41|OwnerIndex=3074|IndexInSheet=23|OwnerPartId=-1|Location.X=1274|Location.Y=1027|Color=8388608|FontID=1|IsHidden=T|Text=0.022inch|Name=Thickness
|RECORD=41|OwnerIndex=3074|IndexInSheet=24|OwnerPartId=-1|Location.X=1274|Location.Y=1027|Color=8388608|FontID=1|IsHidden=T|Text=2.2uF|Name=Capacitance
|RECORD=41|OwnerIndex=3074|IndexInSheet=25|OwnerPartId=-1|Location.X=1274|Location.Y=1027|Color=8388608|FontID=1|IsHidden=T|Text=16V|Name=Voltage Rating (DC)
|RECORD=41|OwnerIndex=3074|IndexInSheet=26|OwnerPartId=-1|Location.X=1274|Location.Y=1027|Color=8388608|FontID=1|IsHidden=T|Text=10%|Name=Tolerance
|RECORD=41|OwnerIndex=3074|IndexInSheet=27|OwnerPartId=-1|Location.X=1274|Location.Y=1027|Color=8388608|FontID=1|IsHidden=T|Text=16V|Name=Voltage Rating
|RECORD=41|OwnerIndex=3074|IndexInSheet=28|OwnerPartId=-1|Location.X=1274|Location.Y=1027|Color=8388608|FontID=1|IsHidden=T|Text=Ceramic|Name=Resistor Type
|RECORD=41|OwnerIndex=3074|IndexInSheet=29|OwnerPartId=-1|Location.X=1274|Location.Y=1027|Color=8388608|FontID=1|IsHidden=T|Text=0.5mm|Name=Height
|RECORD=41|OwnerIndex=3074|IndexInSheet=30|OwnerPartId=-1|Location.X=1274|Location.Y=1027|Color=8388608|FontID=1|IsHidden=T|Text=0402|Name=Case/Package
|RECORD=41|OwnerIndex=3074|IndexInSheet=31|OwnerPartId=-1|Location.X=1274|Location.Y=1027|Color=8388608|FontID=1|IsHidden=T|Text=-55°C|Name=Min Operating Temperature
|RECORD=34|OwnerIndex=3074|IndexInSheet=-1|OwnerPartId=-1|Location.X=1275|Location.Y=1005|Orientation=1|Color=8388608|FontID=2|Text=C3|Name=Designator|ReadOnlyState=1
|RECORD=41|OwnerIndex=3074|IndexInSheet=-1|OwnerPartId=1|Location.X=1305|Location.Y=980|Orientation=1|Color=8388608|FontID=2|Text=2.2uF_16V_0402|Name=Comment
|RECORD=44|OwnerIndex=3074
|RECORD=45|OwnerIndex=3111|IndexInSheet=-1|UseComponentLibrary=T|ModelName=FP-C1005-050-0_05-IPC_A|ModelType=PCBLIB|DatafileCount=1|ModelDatafileEntity0=FP-C1005-050-0_05-IPC_A|ModelDatafileKind0=PCBLib|IsCurrent=T|DatalinksLocked=T|DatabaseDatalinksLocked=T
|RECORD=46|OwnerIndex=3112
|RECORD=48|OwnerIndex=3112
|RECORD=45|OwnerIndex=3111|IndexInSheet=-1|UseComponentLibrary=T|ModelName=FP-C1005-050-0_05-MFG|ModelType=PCBLIB|DatafileCount=1|ModelDatafileEntity0=FP-C1005-050-0_05-MFG|ModelDatafileKind0=PCBLib|DatalinksLocked=T|DatabaseDatalinksLocked=T
|RECORD=46|OwnerIndex=3115
|RECORD=48|OwnerIndex=3115
|RECORD=45|OwnerIndex=3111|IndexInSheet=-1|UseComponentLibrary=T|ModelName=FP-C1005-050-0_05-IPC_C|ModelType=PCBLIB|DatafileCount=1|ModelDatafileEntity0=FP-C1005-050-0_05-IPC_C|ModelDatafileKind0=PCBLib|DatalinksLocked=T|DatabaseDatalinksLocked=T
|RECORD=46|OwnerIndex=3118
|RECORD=48|OwnerIndex=3118
|RECORD=45|OwnerIndex=3111|IndexInSheet=-1|UseComponentLibrary=T|ModelName=FP-C1005-050-0_05-IPC_B|ModelType=PCBLIB|DatafileCount=1|ModelDatafileEntity0=FP-C1005-050-0_05-IPC_B|ModelDatafileKind0=PCBLib|DatalinksLocked=T|DatabaseDatalinksLocked=T
|RECORD=46|OwnerIndex=3121
|RECORD=48|OwnerIndex=3121
|RECORD=17|IndexInSheet=184|OwnerPartId=-1|Style=4|ShowNetName=T|Location.X=1285|Location.Y=990|Orientation=3|Color=128|FontID=1|Text=GND
|RECORD=17|IndexInSheet=185|OwnerPartId=-1|ShowNetName=T|Location.X=1185|Location.Y=1000|Color=128|FontID=1|Text=P5V_SENSE
|RECORD=17|IndexInSheet=186|OwnerPartId=-1|Style=4|ShowNetName=T|Location.X=1245|Location.Y=845|Color=128|FontID=1|Text=GND
|RECORD=17|IndexInSheet=187|OwnerPartId=-1|ShowNetName=T|Location.X=1200|Location.Y=860|Color=255|FontID=1|Text=P5V_MUN_FB|IsCrossSheetConnector=T
|RECORD=17|IndexInSheet=188|OwnerPartId=-1|ShowNetName=T|Location.X=1000|Location.Y=1000|Orientation=2|Color=255|FontID=1|Text=P5V_MUN_FB|IsCrossSheetConnector=T
|RECORD=1|LibReference=MBRD10200CT-13|ComponentDescription=No Description Available|PartCount=2|DisplayModeCount=1|IndexInSheet=189|OwnerPartId=-1|Location.X=190|Location.Y=915|CurrentPartId=1|LibraryPath=*|SourceLibraryName=MBRD10200CT-13.SchLib|TargetFileName=*|AreaColor=11599871|Color=128|PartIDLocked=T|DesignItemId=MBRD10200CT-13|AllPinCount=3
|RECORD=41|OwnerIndex=3129|OwnerPartId=1|Location.X=188|Location.Y=925|FontID=1|IsHidden=T|Text=Diodes - Rectifiers, Arrays|Name=Type
|RECORD=41|OwnerIndex=3129|IndexInSheet=1|OwnerPartId=1|Location.X=188|Location.Y=925|FontID=1|IsHidden=T|Text=Diodes Inc|Name=Mfr_Name
|RECORD=41|OwnerIndex=3129|IndexInSheet=2|OwnerPartId=1|Location.X=188|Location.Y=925|FontID=1|IsHidden=T|Text=RefDes|Name=RefDes
|RECORD=2|OwnerIndex=3129|OwnerPartId=1|FormalType=1|Electrical=4|PinConglomerate=50|PinLength=30|Location.X=220|Location.Y=915|Name=1|Designator=1|SwapIdPin=0|SwapIDPart=0Ž&Ž1|PinPropagationDelay=0.000000E+000
|RECORD=2|OwnerIndex=3129|OwnerPartId=1|FormalType=1|Electrical=4|PinConglomerate=48|PinLength=30|Location.X=270|Location.Y=915|Name=2|Designator=2|SwapIdPin=0|SwapIDPart=0Ž&Ž2|PinPropagationDelay=0.000000E+000
|RECORD=2|OwnerIndex=3129|OwnerPartId=1|FormalType=1|Electrical=4|PinConglomerate=48|PinLength=30|Location.X=270|Location.Y=905|Name=3|Designator=3|SwapIdPin=0|SwapIDPart=0Ž&Ž3|PinPropagationDelay=0.000000E+000
|RECORD=13|OwnerIndex=3129|IsNotAccesible=T|IndexInSheet=6|OwnerPartId=1|Location.X=250|Location.Y=910|Corner.X=250|Corner.Y=900|LineWidth=1
|RECORD=13|OwnerIndex=3129|IsNotAccesible=T|IndexInSheet=7|OwnerPartId=1|Location.X=220|Location.Y=915|Corner.X=225|Corner.Y=915|LineWidth=1
|RECORD=13|OwnerIndex=3129|IsNotAccesible=T|IndexInSheet=8|OwnerPartId=1|Location.X=225|Location.Y=915|Corner.X=225|Corner.Y=905|LineWidth=1
|RECORD=13|OwnerIndex=3129|IsNotAccesible=T|IndexInSheet=9|OwnerPartId=1|Location.X=225|Location.Y=905|Corner.X=230|Corner.Y=905|LineWidth=1
|RECORD=13|OwnerIndex=3129|IsNotAccesible=T|IndexInSheet=10|OwnerPartId=1|Location.X=270|Location.Y=905|Corner.X=260|Corner.Y=905|LineWidth=1
|RECORD=13|OwnerIndex=3129|IsNotAccesible=T|IndexInSheet=11|OwnerPartId=1|Location.X=230|Location.Y=910|Corner.X=230|Corner.Y=900|LineWidth=1
|RECORD=13|OwnerIndex=3129|IsNotAccesible=T|IndexInSheet=12|OwnerPartId=1|Location.X=230|Location.Y=900|Corner.X=240|Corner.Y=905|LineWidth=1
|RECORD=13|OwnerIndex=3129|IsNotAccesible=T|IndexInSheet=13|OwnerPartId=1|Location.X=240|Location.Y=910|Corner.X=240|Corner.Y=900|LineWidth=1
|RECORD=13|OwnerIndex=3129|IsNotAccesible=T|IndexInSheet=14|OwnerPartId=1|Location.X=240|Location.Y=905|Corner.X=230|Corner.Y=910|LineWidth=1
|RECORD=13|OwnerIndex=3129|IsNotAccesible=T|IndexInSheet=15|OwnerPartId=1|Location.X=260|Location.Y=910|Corner.X=260|Corner.Y=900|LineWidth=1
|RECORD=13|OwnerIndex=3129|IsNotAccesible=T|IndexInSheet=16|OwnerPartId=1|Location.X=260|Location.Y=900|Corner.X=250|Corner.Y=905|LineWidth=1
|RECORD=13|OwnerIndex=3129|IsNotAccesible=T|IndexInSheet=17|OwnerPartId=1|Location.X=250|Location.Y=905|Corner.X=260|Corner.Y=910|LineWidth=1
|RECORD=13|OwnerIndex=3129|IsNotAccesible=T|IndexInSheet=18|OwnerPartId=1|Location.X=240|Location.Y=905|Corner.X=250|Corner.Y=905|LineWidth=1
|RECORD=13|OwnerIndex=3129|IsNotAccesible=T|IndexInSheet=19|OwnerPartId=1|Location.X=245|Location.Y=905|Corner.X=245|Corner.Y=915|LineWidth=1
|RECORD=13|OwnerIndex=3129|IsNotAccesible=T|IndexInSheet=20|OwnerPartId=1|Location.X=245|Location.Y=915|Corner.X=270|Corner.Y=915|LineWidth=1
|RECORD=14|OwnerIndex=3129|IsNotAccesible=T|IndexInSheet=21|OwnerPartId=1|Location.X=220|Location.Y=895|Corner.X=270|Corner.Y=925|LineWidth=1|AreaColor=11599871|IsSolid=T|Transparent=T
|RECORD=12|OwnerIndex=3129|IsNotAccesible=T|IndexInSheet=22|OwnerPartId=1|Location.X=245|Location.Y=905|Radius_Frac=50000|LineWidth=1|EndAngle=360.000
|RECORD=34|OwnerIndex=3129|IndexInSheet=-1|OwnerPartId=-1|Location.X=219|Location.Y=925|Color=8388608|FontID=1|Text=CR1|Name=Designator|ReadOnlyState=1
|RECORD=41|OwnerIndex=3129|IndexInSheet=-1|OwnerPartId=-1|Location.X=219|Location.Y=885|Color=8388608|FontID=1|Text=MBRD10200CT-13|Name=Comment
|RECORD=44|OwnerIndex=3129
|RECORD=45|OwnerIndex=3158|IndexInSheet=-1|ModelName=TO252(DPAK)_DIO|ModelType=PCBLIB|DatafileCount=1|ModelDatafileEntity0=TO252(DPAK)_DIO|ModelDatafileKind0=PCBLIB|IsCurrent=T
|RECORD=46|OwnerIndex=3159
|RECORD=48|OwnerIndex=3159
|RECORD=1|LibReference=203bc49f2ac43e59fd269a8c329ed05|ComponentDescription=470uF 10V  ±10% 500mO 2917  SMD Tantalum Capacitor|PartCount=2|DisplayModeCount=1|IndexInSheet=190|OwnerPartId=-1|Location.X=1375|Location.Y=920|CurrentPartId=1|LibraryPath=*|SourceLibraryName=Altium Content Vault|TargetFileName=*|AreaColor=11599871|Color=128|PartIDLocked=T|DesignItemId=CMP-04424-000243-1|AllPinCount=2
|RECORD=2|OwnerIndex=3162|OwnerPartId=1|Electrical=4|PinConglomerate=51|PinLength=8|Location.X=1375|Location.Y=908|Name=C|Designator=1|PinPropagationDelay=0.000000E+000
|RECORD=2|OwnerIndex=3162|OwnerPartId=1|Electrical=4|PinConglomerate=49|PinLength=8|Location.X=1375|Location.Y=912|Name=A|Designator=2|PinPropagationDelay=0.000000E+000
|RECORD=5|OwnerIndex=3162|IsNotAccesible=T|IndexInSheet=2|OwnerPartId=1|LineWidth=1|Color=16711680|LocationCount=4|X1=1365|Y1=904|X2=1370|Y2=910|X3=1380|Y3=910|X4=1385|Y4=904
|RECORD=13|OwnerIndex=3162|IsNotAccesible=T|IndexInSheet=3|OwnerPartId=1|Location.X=1365|Location.Y=912|Corner.X=1385|Corner.Y=912|LineWidth=1|Color=16711680
|RECORD=13|OwnerIndex=3162|IsNotAccesible=T|IndexInSheet=4|OwnerPartId=1|Location.X=1375|Location.Y=908|Corner.X=1375|Corner.Y=906|LineWidth=1|Color=16711680
|RECORD=13|OwnerIndex=3162|IsNotAccesible=T|IndexInSheet=5|OwnerPartId=1|Location.X=1375|Location.Y=912|Corner.X=1375|Corner.Y=915|LineWidth=1|Color=16711680
|RECORD=4|OwnerIndex=3162|IsNotAccesible=T|IndexInSheet=6|OwnerPartId=1|Location.X=1364|Location.Y=922|Justification=6|Color=8388608|FontID=1|Text=+
|RECORD=41|OwnerIndex=3162|IndexInSheet=7|OwnerPartId=-1|Location.X=1364|Location.Y=922|Color=8388608|FontID=1|IsHidden=T|Text=Flat|Name=Construction
|RECORD=41|OwnerIndex=3162|IndexInSheet=8|OwnerPartId=-1|Location.X=1364|Location.Y=922|Color=8388608|FontID=1|IsHidden=T|Text=4.3mm|Name=Width
|RECORD=41|OwnerIndex=3162|IndexInSheet=9|OwnerPartId=-1|Location.X=1364|Location.Y=922|Color=8388608|FontID=1|IsHidden=T|Text=Surface Mount|Name=Mount
|RECORD=41|OwnerIndex=3162|IndexInSheet=10|OwnerPartId=-1|Location.X=1364|Location.Y=922|Color=8388608|FontID=1|IsHidden=T|Text=10%|Name=Tolerance
|RECORD=41|OwnerIndex=3162|IndexInSheet=11|OwnerPartId=-1|Location.X=1364|Location.Y=922|Color=8388608|FontID=1|IsHidden=T|Text=125°C|Name=Max Operating Temperature
|RECORD=41|OwnerIndex=3162|IndexInSheet=12|OwnerPartId=-1|Location.X=1364|Location.Y=922|Color=8388608|FontID=1|IsHidden=T|Text=-55°C|Name=Min Operating Temperature
|RECORD=41|OwnerIndex=3162|IndexInSheet=13|OwnerPartId=-1|Location.X=1364|Location.Y=922|Color=8388608|FontID=1|IsHidden=T|Text=7.3mm|Name=Length
|RECORD=41|OwnerIndex=3162|IndexInSheet=14|OwnerPartId=-1|Location.X=1364|Location.Y=922|Color=8388608|FontID=1|IsHidden=T|Text=10V|Name=Voltage
|RECORD=41|OwnerIndex=3162|IndexInSheet=15|OwnerPartId=-1|Location.X=1364|Location.Y=922|Color=8388608|FontID=1|IsHidden=T|Text=10%|Name=Dissipation Factor
|RECORD=41|OwnerIndex=3162|IndexInSheet=16|OwnerPartId=-1|Location.X=1364|Location.Y=922|Color=8388608|FontID=1|IsHidden=T|Text=47uA|Name=Leakage Current
|RECORD=41|OwnerIndex=3162|IndexInSheet=17|OwnerPartId=-1|Location.X=1364|Location.Y=922|Color=8388608|FontID=1|IsHidden=T|Text=No SVHC|Name=REACH SVHC
|RECORD=41|OwnerIndex=3162|IndexInSheet=18|OwnerPartId=-1|Location.X=1364|Location.Y=922|Color=8388608|FontID=1|IsHidden=T|Text=Lead Free|Name=Lead Free
|RECORD=41|OwnerIndex=3162|IndexInSheet=19|OwnerPartId=-1|Location.X=1364|Location.Y=922|Color=8388608|FontID=1|IsHidden=T|Text=2917|Name=Case/Package
|RECORD=41|OwnerIndex=3162|IndexInSheet=20|OwnerPartId=-1|Location.X=1364|Location.Y=922|Color=8388608|FontID=1|IsHidden=T|Text=10V|Name=Voltage Rating
|RECORD=41|OwnerIndex=3162|IndexInSheet=21|OwnerPartId=-1|Location.X=1364|Location.Y=922|Color=8388608|FontID=1|IsHidden=T|Text=500mR|Name=ESR (Equivalent Series Resistance)
|RECORD=41|OwnerIndex=3162|IndexInSheet=22|OwnerPartId=-1|Location.X=1364|Location.Y=922|Color=8388608|FontID=1|IsHidden=T|Text=470uF|Name=Capacitance
|RECORD=41|OwnerIndex=3162|IndexInSheet=23|OwnerPartId=-1|Location.X=1364|Location.Y=922|Color=8388608|FontID=1|IsHidden=T|Text=TAJ|Name=Series
|RECORD=41|OwnerIndex=3162|IndexInSheet=24|OwnerPartId=-1|Location.X=1364|Location.Y=922|Color=8388608|FontID=1|IsHidden=T|Text=4.1mm|Name=Height
|RECORD=41|OwnerIndex=3162|IndexInSheet=25|OwnerPartId=-1|Location.X=1364|Location.Y=922|Color=8388608|FontID=1|IsHidden=T|Text=Yes|Name=RoHS Compliant
|RECORD=41|OwnerIndex=3162|IndexInSheet=26|OwnerPartId=-1|Location.X=1364|Location.Y=922|Color=8388608|FontID=1|IsHidden=T|Text=Tape and Reel|Name=Packaging
|RECORD=41|OwnerIndex=3162|IndexInSheet=27|OwnerPartId=-1|Location.X=1364|Location.Y=922|Color=8388608|FontID=1|IsHidden=T|Text=10V|Name=Voltage Rating (DC)
|RECORD=41|OwnerIndex=3162|IndexInSheet=28|OwnerPartId=-1|Location.X=1364|Location.Y=922|Color=8388608|FontID=1|IsHidden=T|Text=No|Name=Radiation Hardening
|RECORD=41|OwnerIndex=3162|IndexInSheet=29|OwnerPartId=-1|Location.X=1364|Location.Y=922|Color=8388608|FontID=1|IsHidden=T|Text=Tantalum|Name=Dielectric Material
|RECORD=41|OwnerIndex=3162|IndexInSheet=30|OwnerPartId=-1|Location.X=1364|Location.Y=922|Color=8388608|FontID=1|IsHidden=T|Text=2|Name=Number of Pins
|RECORD=41|OwnerIndex=3162|IndexInSheet=31|OwnerPartId=-1|Location.X=1364|Location.Y=922|Color=8388608|FontID=1|IsHidden=T|Text=4.3mm|Name=Depth
|RECORD=41|OwnerIndex=3162|IndexInSheet=32|OwnerPartId=-1|Location.X=1364|Location.Y=922|Color=8388608|FontID=1|IsHidden=T|Text=7343|Name=Case Code (Metric)
|RECORD=41|OwnerIndex=3162|IndexInSheet=33|OwnerPartId=-1|Location.X=1364|Location.Y=922|Color=8388608|FontID=1|IsHidden=T|Text=2917|Name=Case Code (Imperial)
|RECORD=41|OwnerIndex=3162|IndexInSheet=34|OwnerPartId=-1|Location.X=1364|Location.Y=922|Color=8388608|FontID=1|IsHidden=T|Text=SMD/SMT|Name=Termination
|RECORD=41|OwnerIndex=3162|IndexInSheet=35|OwnerPartId=-1|Location.X=1364|Location.Y=922|Color=8388608|FontID=1|IsHidden=T|Text=Polar|Name=Polarity
|RECORD=41|OwnerIndex=3162|IndexInSheet=36|OwnerPartId=-1|Location.X=1364|Location.Y=922|Color=8388608|FontID=1|IsHidden=T|Text=4.4mm|Name=Lead Pitch
|RECORD=41|OwnerIndex=3162|IndexInSheet=37|OwnerPartId=-1|Location.X=1364|Location.Y=922|Color=8388608|FontID=1|IsHidden=T|Text=General Purpose|Name=Features
|RECORD=41|OwnerIndex=3162|IndexInSheet=38|OwnerPartId=-1|Location.X=1364|Location.Y=922|Color=8388608|FontID=1|IsHidden=T|Text=0.169inch|Name=Height - Seated (Max)
|RECORD=41|OwnerIndex=3162|IndexInSheet=39|OwnerPartId=-1|Location.X=1364|Location.Y=922|Color=8388608|FontID=1|IsHidden=T|Text=1|Name=Package Quantity
|RECORD=34|OwnerIndex=3162|IndexInSheet=-1|OwnerPartId=-1|Location.X=1360|Location.Y=900|Orientation=1|Color=8388608|FontID=2|Text=C71|Name=Designator|ReadOnlyState=1
|RECORD=41|OwnerIndex=3162|IndexInSheet=-1|OwnerPartId=1|Location.X=1400|Location.Y=880|Orientation=1|Color=8388608|FontID=2|Text=470uF_10V_2917|Name=Comment
|RECORD=44|OwnerIndex=3162
|RECORD=45|OwnerIndex=3207|IndexInSheet=-1|UseComponentLibrary=T|ModelName=FP-TAJE-MFG|ModelType=PCBLIB|DatafileCount=1|ModelDatafileEntity0=FP-TAJE-MFG|ModelDatafileKind0=PCBLib|IsCurrent=T|DatalinksLocked=T|DatabaseDatalinksLocked=T
|RECORD=46|OwnerIndex=3208
|RECORD=48|OwnerIndex=3208
|RECORD=1|LibReference=a00bbbee19879c290e62620ae7e47b1|ComponentDescription=CAP TANT POLY 47UF 35V 2917|PartCount=2|DisplayModeCount=1|IndexInSheet=191|OwnerPartId=-1|Location.X=630|Location.Y=920|CurrentPartId=1|LibraryPath=*|SourceLibraryName=Altium Content Vault|TargetFileName=*|AreaColor=11599871|Color=128|PartIDLocked=T|DesignItemId=CMP-03016-000019-1|AllPinCount=2
|RECORD=2|OwnerIndex=3211|OwnerPartId=1|Electrical=4|PinConglomerate=51|PinLength=8|Location.X=630|Location.Y=908|Name=C|Designator=1|PinPropagationDelay=0.000000E+000
|RECORD=2|OwnerIndex=3211|OwnerPartId=1|Electrical=4|PinConglomerate=49|PinLength=8|Location.X=630|Location.Y=912|Name=A|Designator=2|PinPropagationDelay=0.000000E+000
|RECORD=5|OwnerIndex=3211|IsNotAccesible=T|IndexInSheet=2|OwnerPartId=1|LineWidth=1|Color=16711680|LocationCount=4|X1=620|Y1=904|X2=625|Y2=910|X3=635|Y3=910|X4=640|Y4=904
|RECORD=13|OwnerIndex=3211|IsNotAccesible=T|IndexInSheet=3|OwnerPartId=1|Location.X=620|Location.Y=912|Corner.X=640|Corner.Y=912|LineWidth=1|Color=16711680
|RECORD=13|OwnerIndex=3211|IsNotAccesible=T|IndexInSheet=4|OwnerPartId=1|Location.X=630|Location.Y=908|Corner.X=630|Corner.Y=906|LineWidth=1|Color=16711680
|RECORD=13|OwnerIndex=3211|IsNotAccesible=T|IndexInSheet=5|OwnerPartId=1|Location.X=630|Location.Y=912|Corner.X=630|Corner.Y=915|LineWidth=1|Color=16711680
|RECORD=4|OwnerIndex=3211|IsNotAccesible=T|IndexInSheet=6|OwnerPartId=1|Location.X=619|Location.Y=922|Justification=6|Color=8388608|FontID=1|Text=+
|RECORD=41|OwnerIndex=3211|IndexInSheet=7|OwnerPartId=-1|Location.X=619|Location.Y=922|Color=8388608|FontID=1|IsHidden=T|Text=Surface Mount|Name=Mount
|RECORD=41|OwnerIndex=3211|IndexInSheet=8|OwnerPartId=-1|Location.X=619|Location.Y=922|Color=8388608|FontID=1|IsHidden=T|Text=35V|Name=Voltage Rating (DC)
|RECORD=41|OwnerIndex=3211|IndexInSheet=9|OwnerPartId=-1|Location.X=619|Location.Y=922|Color=8388608|FontID=1|IsHidden=T|Text=0.169inch|Name=Height - Seated (Max)
|RECORD=41|OwnerIndex=3211|IndexInSheet=10|OwnerPartId=-1|Location.X=619|Location.Y=922|Color=8388608|FontID=1|IsHidden=T|Text=1|Name=Package Quantity
|RECORD=41|OwnerIndex=3211|IndexInSheet=11|OwnerPartId=-1|Location.X=619|Location.Y=922|Color=8388608|FontID=1|IsHidden=T|Text=4mm|Name=Height
|RECORD=41|OwnerIndex=3211|IndexInSheet=12|OwnerPartId=-1|Location.X=619|Location.Y=922|Color=8388608|FontID=1|IsHidden=T|Text=125°C|Name=Max Operating Temperature
|RECORD=41|OwnerIndex=3211|IndexInSheet=13|OwnerPartId=-1|Location.X=619|Location.Y=922|Color=8388608|FontID=1|IsHidden=T|Text=4.3mm|Name=Width
|RECORD=41|OwnerIndex=3211|IndexInSheet=14|OwnerPartId=-1|Location.X=619|Location.Y=922|Color=8388608|FontID=1|IsHidden=T|Text=Tape and Reel|Name=Packaging
|RECORD=41|OwnerIndex=3211|IndexInSheet=15|OwnerPartId=-1|Location.X=619|Location.Y=922|Color=8388608|FontID=1|IsHidden=T|Text=2917|Name=Case/Package
|RECORD=41|OwnerIndex=3211|IndexInSheet=16|OwnerPartId=-1|Location.X=619|Location.Y=922|Color=8388608|FontID=1|IsHidden=T|Text=KO-CAP T521|Name=Series
|RECORD=41|OwnerIndex=3211|IndexInSheet=17|OwnerPartId=-1|Location.X=619|Location.Y=922|Color=8388608|FontID=1|IsHidden=T|Text=20%|Name=Tolerance
|RECORD=41|OwnerIndex=3211|IndexInSheet=18|OwnerPartId=-1|Location.X=619|Location.Y=922|Color=8388608|FontID=1|IsHidden=T|Text=10%|Name=Dissipation Factor
|RECORD=41|OwnerIndex=3211|IndexInSheet=19|OwnerPartId=-1|Location.X=619|Location.Y=922|Color=8388608|FontID=1|IsHidden=T|Text=2000Hour|Name=Life (Hours)
|RECORD=41|OwnerIndex=3211|IndexInSheet=20|OwnerPartId=-1|Location.X=619|Location.Y=922|Color=8388608|FontID=1|IsHidden=T|Text=-55°C|Name=Min Operating Temperature
|RECORD=41|OwnerIndex=3211|IndexInSheet=21|OwnerPartId=-1|Location.X=619|Location.Y=922|Color=8388608|FontID=1|IsHidden=T|Text=4.3mm|Name=Depth
|RECORD=41|OwnerIndex=3211|IndexInSheet=22|OwnerPartId=-1|Location.X=619|Location.Y=922|Color=8388608|FontID=1|IsHidden=T|Text=7343|Name=Case Code (Metric)
|RECORD=41|OwnerIndex=3211|IndexInSheet=23|OwnerPartId=-1|Location.X=619|Location.Y=922|Color=8388608|FontID=1|IsHidden=T|Text=2|Name=Number of Pins
|RECORD=41|OwnerIndex=3211|IndexInSheet=24|OwnerPartId=-1|Location.X=619|Location.Y=922|Color=8388608|FontID=1|IsHidden=T|Text=Yes|Name=RoHS Compliant
|RECORD=41|OwnerIndex=3211|IndexInSheet=25|OwnerPartId=-1|Location.X=619|Location.Y=922|Color=8388608|FontID=1|IsHidden=T|Text=2917|Name=Case Code (Imperial)
|RECORD=41|OwnerIndex=3211|IndexInSheet=26|OwnerPartId=-1|Location.X=619|Location.Y=922|Color=8388608|FontID=1|IsHidden=T|Text=47uF|Name=Capacitance
|RECORD=41|OwnerIndex=3211|IndexInSheet=27|OwnerPartId=-1|Location.X=619|Location.Y=922|Color=8388608|FontID=1|IsHidden=T|Text=No SVHC|Name=REACH SVHC
|RECORD=41|OwnerIndex=3211|IndexInSheet=28|OwnerPartId=-1|Location.X=619|Location.Y=922|Color=8388608|FontID=1|IsHidden=T|Text=General Purpose|Name=Features
|RECORD=41|OwnerIndex=3211|IndexInSheet=29|OwnerPartId=-1|Location.X=619|Location.Y=922|Color=8388608|FontID=1|IsHidden=T|Text=SMD/SMT|Name=Termination
|RECORD=41|OwnerIndex=3211|IndexInSheet=30|OwnerPartId=-1|Location.X=619|Location.Y=922|Color=8388608|FontID=1|IsHidden=T|Text=Polar|Name=Polarity
|RECORD=41|OwnerIndex=3211|IndexInSheet=31|OwnerPartId=-1|Location.X=619|Location.Y=922|Color=8388608|FontID=1|IsHidden=T|Text=7.3mm|Name=Length
|RECORD=41|OwnerIndex=3211|IndexInSheet=32|OwnerPartId=-1|Location.X=619|Location.Y=922|Color=8388608|FontID=1|IsHidden=T|Text=35V|Name=Voltage Rating
|RECORD=41|OwnerIndex=3211|IndexInSheet=33|OwnerPartId=-1|Location.X=619|Location.Y=922|Color=8388608|FontID=1|IsHidden=T|Text=Flat|Name=Construction
|RECORD=41|OwnerIndex=3211|IndexInSheet=34|OwnerPartId=-1|Location.X=619|Location.Y=922|Color=8388608|FontID=1|IsHidden=T|Text=30mR|Name=ESR (Equivalent Series Resistance)
|RECORD=34|OwnerIndex=3211|IndexInSheet=-1|OwnerPartId=-1|Location.X=615|Location.Y=905|Orientation=1|Color=8388608|FontID=2|Text=C72|Name=Designator|ReadOnlyState=1
|RECORD=41|OwnerIndex=3211|IndexInSheet=-1|OwnerPartId=1|Location.X=650|Location.Y=885|Orientation=1|Color=8388608|FontID=2|Text=47uF_35V_2917|Name=Comment
|RECORD=44|OwnerIndex=3211
|RECORD=45|OwnerIndex=3251|IndexInSheet=-1|UseComponentLibrary=T|ModelName=FP-T521X476M035ATE030-MFG|ModelType=PCBLIB|DatafileCount=1|ModelDatafileEntity0=FP-T521X476M035ATE030-MFG|ModelDatafileKind0=PCBLib|IsCurrent=T|DatalinksLocked=T|DatabaseDatalinksLocked=T
|RECORD=46|OwnerIndex=3252
|RECORD=48|OwnerIndex=3252
|RECORD=27|IndexInSheet=192|OwnerPartId=-1|LineWidth=1|Color=8388608|LocationCount=2|X1=602|Y1=917|X2=602|Y2=937
|RECORD=27|IndexInSheet=193|OwnerPartId=-1|LineWidth=1|Color=8388608|LocationCount=2|X1=85|Y1=470|X2=85|Y2=450
|RECORD=27|IndexInSheet=194|OwnerPartId=-1|LineWidth=1|Color=8388608|LocationCount=2|X1=85|Y1=560|X2=85|Y2=540
|RECORD=27|IndexInSheet=195|OwnerPartId=-1|LineWidth=1|Color=8388608|LocationCount=2|X1=85|Y1=620|X2=85|Y2=630
|RECORD=27|IndexInSheet=196|OwnerPartId=-1|LineWidth=1|Color=8388608|LocationCount=3|X1=105|Y1=910|X2=170|Y2=910|X3=170|Y3=900
|RECORD=27|IndexInSheet=197|OwnerPartId=-1|LineWidth=1|Color=8388608|LocationCount=3|X1=105|Y1=930|X2=170|Y2=930|X3=170|Y3=910
|RECORD=27|IndexInSheet=198|OwnerPartId=-1|LineWidth=1|Color=8388608|LocationCount=3|X1=405|Y1=915|X2=425|Y2=915|X3=430|Y3=915
|RECORD=27|IndexInSheet=199|OwnerPartId=-1|LineWidth=1|Color=8388608|LocationCount=2|X1=552|Y1=877|X2=552|Y2=915
|RECORD=27|IndexInSheet=200|OwnerPartId=-1|LineWidth=1|Color=8388608|LocationCount=5|X1=470|Y1=915|X2=552|Y2=915|X3=552|Y3=917|X4=602|Y4=917|X5=602|Y5=877
|RECORD=27|IndexInSheet=201|OwnerPartId=-1|LineWidth=1|Color=8388608|LocationCount=2|X1=200|Y1=735|X2=200|Y2=755
|RECORD=27|IndexInSheet=202|OwnerPartId=-1|LineWidth=1|Color=8388608|LocationCount=2|X1=240|Y1=740|X2=240|Y2=755
|RECORD=27|IndexInSheet=203|OwnerPartId=-1|LineWidth=1|Color=8388608|LocationCount=2|X1=240|Y1=705|X2=240|Y2=710
|RECORD=27|IndexInSheet=204|OwnerPartId=-1|LineWidth=1|Color=8388608|LocationCount=2|X1=200|Y1=705|X2=200|Y2=715
|RECORD=27|IndexInSheet=205|OwnerPartId=-1|LineWidth=1|Color=8388608|LocationCount=3|X1=340|Y1=695|X2=320|Y2=695|X3=320|Y3=720
|RECORD=27|IndexInSheet=206|OwnerPartId=-1|LineWidth=1|Color=8388608|LocationCount=3|X1=340|Y1=685|X2=280|Y2=685|X3=280|Y3=720
|RECORD=27|IndexInSheet=207|OwnerPartId=-1|LineWidth=1|Color=8388608|LocationCount=3|X1=470|Y1=685|X2=480|Y2=685|X3=480|Y3=680
|RECORD=27|IndexInSheet=208|OwnerPartId=-1|LineWidth=1|Color=8388608|LocationCount=2|X1=470|Y1=755|X2=515|Y2=755
|RECORD=27|IndexInSheet=209|OwnerPartId=-1|LineWidth=1|Color=8388608|LocationCount=2|X1=470|Y1=735|X2=515|Y2=735
|RECORD=27|IndexInSheet=210|OwnerPartId=-1|LineWidth=1|Color=8388608|LocationCount=2|X1=470|Y1=715|X2=490|Y2=715
|RECORD=27|IndexInSheet=211|OwnerPartId=-1|LineWidth=1|Color=8388608|LocationCount=2|X1=490|Y1=705|X2=470|Y2=705
|RECORD=27|IndexInSheet=212|OwnerPartId=-1|LineWidth=1|Color=8388608|LocationCount=2|X1=530|Y1=705|X2=575|Y2=705
|RECORD=27|IndexInSheet=213|OwnerPartId=-1|LineWidth=1|Color=8388608|LocationCount=4|X1=200|Y1=775|X2=200|Y2=755|X3=240|Y3=755|X4=340|Y4=755
|RECORD=27|IndexInSheet=214|OwnerPartId=-1|LineWidth=1|Color=8388608|LocationCount=5|X1=530|Y1=715|X2=575|Y2=715|X3=575|Y3=705|X4=575|Y4=685|X5=480|Y5=685
|RECORD=27|IndexInSheet=215|OwnerPartId=-1|LineWidth=1|Color=8388608|LocationCount=2|X1=1475|Y1=925|X2=1475|Y2=955
|RECORD=27|IndexInSheet=216|OwnerPartId=-1|LineWidth=1|Color=8388608|LocationCount=2|X1=1515|Y1=925|X2=1515|Y2=955
|RECORD=27|IndexInSheet=217|OwnerPartId=-1|LineWidth=1|Color=8388608|LocationCount=2|X1=1560|Y1=925|X2=1560|Y2=955
|RECORD=27|IndexInSheet=218|OwnerPartId=-1|LineWidth=1|Color=8388608|LocationCount=2|X1=1605|Y1=925|X2=1605|Y2=955
|RECORD=27|IndexInSheet=219|OwnerPartId=-1|LineWidth=1|Color=8388608|LocationCount=2|X1=1475|Y1=905|X2=1475|Y2=875
|RECORD=27|IndexInSheet=220|OwnerPartId=-1|LineWidth=1|Color=8388608|LocationCount=2|X1=1515|Y1=905|X2=1515|Y2=875
|RECORD=27|IndexInSheet=221|OwnerPartId=-1|LineWidth=1|Color=8388608|LocationCount=2|X1=1560|Y1=905|X2=1560|Y2=875
|RECORD=27|IndexInSheet=222|OwnerPartId=-1|LineWidth=1|Color=8388608|LocationCount=2|X1=1605|Y1=905|X2=1605|Y2=875
|RECORD=27|IndexInSheet=223|OwnerPartId=-1|LineWidth=1|Color=8388608|LocationCount=2|X1=1245|Y1=760|X2=1245|Y2=780
|RECORD=27|IndexInSheet=224|OwnerPartId=-1|LineWidth=1|Color=8388608|LocationCount=2|X1=1285|Y1=765|X2=1285|Y2=780
|RECORD=27|IndexInSheet=225|OwnerPartId=-1|LineWidth=1|Color=8388608|LocationCount=2|X1=1285|Y1=730|X2=1285|Y2=735
|RECORD=27|IndexInSheet=226|OwnerPartId=-1|LineWidth=1|Color=8388608|LocationCount=2|X1=1245|Y1=730|X2=1245|Y2=740
|RECORD=27|IndexInSheet=227|OwnerPartId=-1|LineWidth=1|Color=8388608|LocationCount=3|X1=1385|Y1=720|X2=1365|Y2=720|X3=1365|Y3=745
|RECORD=27|IndexInSheet=228|OwnerPartId=-1|LineWidth=1|Color=8388608|LocationCount=3|X1=1385|Y1=710|X2=1325|Y2=710|X3=1325|Y3=745
|RECORD=27|IndexInSheet=229|OwnerPartId=-1|LineWidth=1|Color=8388608|LocationCount=3|X1=1515|Y1=710|X2=1525|Y2=710|X3=1525|Y3=705
|RECORD=27|IndexInSheet=230|OwnerPartId=-1|LineWidth=1|Color=8388608|LocationCount=2|X1=1515|Y1=780|X2=1560|Y2=780
|RECORD=27|IndexInSheet=231|OwnerPartId=-1|LineWidth=1|Color=8388608|LocationCount=2|X1=1515|Y1=760|X2=1560|Y2=760
|RECORD=27|IndexInSheet=232|OwnerPartId=-1|LineWidth=1|Color=8388608|LocationCount=2|X1=1515|Y1=740|X2=1535|Y2=740
|RECORD=27|IndexInSheet=233|OwnerPartId=-1|LineWidth=1|Color=8388608|LocationCount=2|X1=1535|Y1=730|X2=1515|Y2=730
|RECORD=27|IndexInSheet=234|OwnerPartId=-1|LineWidth=1|Color=8388608|LocationCount=4|X1=1575|Y1=730|X2=1620|Y2=730|X3=1620|Y3=710|X4=1525|Y4=710
|RECORD=27|IndexInSheet=235|OwnerPartId=-1|LineWidth=1|Color=8388608|LocationCount=3|X1=1575|Y1=740|X2=1620|Y2=740|X3=1620|Y3=795
|RECORD=27|IndexInSheet=236|OwnerPartId=-1|LineWidth=1|Color=8388608|LocationCount=3|X1=945|Y1=405|X2=960|Y2=405|X3=960|Y3=420
|RECORD=27|IndexInSheet=237|OwnerPartId=-1|LineWidth=1|Color=8388608|LocationCount=2|X1=1240|Y1=615|X2=1240|Y2=635
|RECORD=27|IndexInSheet=238|OwnerPartId=-1|LineWidth=1|Color=8388608|LocationCount=2|X1=1280|Y1=620|X2=1280|Y2=635
|RECORD=27|IndexInSheet=239|OwnerPartId=-1|LineWidth=1|Color=8388608|LocationCount=2|X1=1280|Y1=585|X2=1280|Y2=590
|RECORD=27|IndexInSheet=240|OwnerPartId=-1|LineWidth=1|Color=8388608|LocationCount=2|X1=1240|Y1=585|X2=1240|Y2=595
|RECORD=27|IndexInSheet=241|OwnerPartId=-1|LineWidth=1|Color=8388608|LocationCount=3|X1=1380|Y1=575|X2=1360|Y2=575|X3=1360|Y3=600
|RECORD=27|IndexInSheet=242|OwnerPartId=-1|LineWidth=1|Color=8388608|LocationCount=3|X1=1380|Y1=565|X2=1320|Y2=565|X3=1320|Y3=600
|RECORD=27|IndexInSheet=243|OwnerPartId=-1|LineWidth=1|Color=8388608|LocationCount=3|X1=1510|Y1=565|X2=1520|Y2=565|X3=1520|Y3=560
|RECORD=27|IndexInSheet=244|OwnerPartId=-1|LineWidth=1|Color=8388608|LocationCount=2|X1=1510|Y1=635|X2=1555|Y2=635
|RECORD=27|IndexInSheet=245|OwnerPartId=-1|LineWidth=1|Color=8388608|LocationCount=2|X1=1510|Y1=615|X2=1555|Y2=615
|RECORD=27|IndexInSheet=246|OwnerPartId=-1|LineWidth=1|Color=8388608|LocationCount=2|X1=1510|Y1=595|X2=1530|Y2=595
|RECORD=27|IndexInSheet=247|OwnerPartId=-1|LineWidth=1|Color=8388608|LocationCount=2|X1=1530|Y1=585|X2=1510|Y2=585
|RECORD=27|IndexInSheet=248|OwnerPartId=-1|LineWidth=1|Color=8388608|LocationCount=4|X1=1570|Y1=595|X2=1610|Y2=595|X3=1610|Y3=565|X4=1520|Y4=565
|RECORD=27|IndexInSheet=249|OwnerPartId=-1|LineWidth=1|Color=8388608|LocationCount=3|X1=1570|Y1=585|X2=1620|Y2=585|X3=1620|Y3=650
|RECORD=27|IndexInSheet=250|OwnerPartId=-1|LineWidth=1|Color=8388608|LocationCount=2|X1=200|Y1=475|X2=200|Y2=455
|RECORD=27|IndexInSheet=251|OwnerPartId=-1|LineWidth=1|Color=8388608|LocationCount=2|X1=200|Y1=565|X2=200|Y2=545
|RECORD=27|IndexInSheet=252|OwnerPartId=-1|LineWidth=1|Color=8388608|LocationCount=2|X1=200|Y1=625|X2=200|Y2=635
|RECORD=27|IndexInSheet=253|OwnerPartId=-1|LineWidth=1|Color=8388608|LocationCount=2|X1=600|Y1=837|X2=600|Y2=805
|RECORD=27|IndexInSheet=254|OwnerPartId=-1|LineWidth=1|Color=8388608|LocationCount=5|X1=552|Y1=847|X2=552|Y2=837|X3=600|Y3=837|X4=602|Y4=837|X5=602|Y5=847
|RECORD=27|IndexInSheet=255|OwnerPartId=-1|LineWidth=1|Color=8388608|LocationCount=2|X1=425|Y1=900|X2=425|Y2=915
|RECORD=27|IndexInSheet=256|OwnerPartId=-1|LineWidth=1|Color=8388608|LocationCount=2|X1=425|Y1=830|X2=425|Y2=840
|RECORD=27|IndexInSheet=257|OwnerPartId=-1|LineWidth=1|Color=8388608|LocationCount=3|X1=1360|Y1=1005|X2=1360|Y2=985|X3=1375|Y3=985
|RECORD=27|IndexInSheet=258|OwnerPartId=-1|LineWidth=1|Color=8388608|LocationCount=3|X1=1415|Y1=985|X2=1430|Y2=985|X3=1430|Y3=1005
|RECORD=27|IndexInSheet=259|OwnerPartId=-1|LineWidth=1|Color=8388608|LocationCount=2|X1=1430|Y1=925|X2=1430|Y2=955
|RECORD=27|IndexInSheet=260|OwnerPartId=-1|LineWidth=1|Color=8388608|LocationCount=4|X1=1245|Y1=800|X2=1245|Y2=780|X3=1285|Y3=780|X4=1385|Y4=780
|RECORD=27|IndexInSheet=261|OwnerPartId=-1|LineWidth=1|Color=8388608|LocationCount=3|X1=675|Y1=880|X2=725|Y2=880|X3=725|Y3=905
|RECORD=27|IndexInSheet=262|OwnerPartId=-1|LineWidth=1|Color=8388608|LocationCount=3|X1=725|Y1=880|X2=765|Y2=880|X3=765|Y3=905
|RECORD=27|IndexInSheet=263|OwnerPartId=-1|LineWidth=1|Color=8388608|LocationCount=3|X1=725|Y1=925|X2=725|Y2=960|X3=675|Y3=960
|RECORD=27|IndexInSheet=264|OwnerPartId=-1|LineWidth=1|Color=8388608|LocationCount=3|X1=765|Y1=925|X2=765|Y2=960|X3=725|Y3=960
|RECORD=27|IndexInSheet=265|OwnerPartId=-1|LineWidth=1|Color=8388608|LocationCount=2|X1=905|Y1=420|X2=905|Y2=405
|RECORD=27|IndexInSheet=266|OwnerPartId=-1|LineWidth=1|Color=8388608|LocationCount=3|X1=390|Y1=325|X2=390|Y2=300|X3=340|Y3=300
|RECORD=27|IndexInSheet=267|OwnerPartId=-1|LineWidth=1|Color=8388608|LocationCount=3|X1=430|Y1=325|X2=430|Y2=300|X3=390|Y3=300
|RECORD=27|IndexInSheet=268|OwnerPartId=-1|LineWidth=1|Color=8388608|LocationCount=3|X1=390|Y1=345|X2=390|Y2=375|X3=340|Y3=375
|RECORD=27|IndexInSheet=269|OwnerPartId=-1|LineWidth=1|Color=8388608|LocationCount=3|X1=390|Y1=375|X2=430|Y2=375|X3=430|Y3=345
|RECORD=27|IndexInSheet=270|OwnerPartId=-1|LineWidth=1|Color=8388608|LocationCount=4|X1=1240|Y1=660|X2=1240|Y2=635|X3=1280|Y3=635|X4=1380|Y4=635
|RECORD=27|IndexInSheet=271|OwnerPartId=-1|LineWidth=1|Color=8388608|LocationCount=4|X1=785|Y1=545|X2=805|Y2=545|X3=805|Y3=555|X4=805|Y4=565
|RECORD=27|IndexInSheet=272|OwnerPartId=-1|LineWidth=1|Color=8388608|LocationCount=2|X1=785|Y1=555|X2=805|Y2=555
|RECORD=27|IndexInSheet=273|OwnerPartId=-1|LineWidth=1|Color=8388608|LocationCount=4|X1=585|Y1=545|X2=565|Y2=545|X3=565|Y3=555|X4=565|Y4=565
|RECORD=27|IndexInSheet=274|OwnerPartId=-1|LineWidth=1|Color=8388608|LocationCount=2|X1=585|Y1=555|X2=565|Y2=555
|RECORD=27|IndexInSheet=275|OwnerPartId=-1|LineWidth=1|Color=8388608|LocationCount=3|X1=435|Y1=580|X2=435|Y2=525|X3=450|Y3=525
|RECORD=27|IndexInSheet=276|OwnerPartId=-1|LineWidth=1|Color=8388608|LocationCount=3|X1=435|Y1=525|X2=435|Y2=505|X3=450|Y3=505
|RECORD=27|IndexInSheet=277|OwnerPartId=-1|LineWidth=1|Color=8388608|LocationCount=3|X1=490|Y1=505|X2=530|Y2=505|X3=585|Y3=505
|RECORD=27|IndexInSheet=278|OwnerPartId=-1|LineWidth=1|Color=8388608|LocationCount=17|X1=785|Y1=485|X2=800|Y2=485|X3=800|Y3=475|X4=800|Y4=465|X5=800|Y5=455|X6=800|Y6=445|X7=800|Y7=435|X8=800|Y8=425|X9=800|Y9=415|X10=800|Y10=405|X11=800|Y11=395|X12=800|Y12=385|X13=800|Y13=375|X14=800|Y14=365|X15=800|Y15=355|X16=800|Y16=345|X17=800|Y17=335
|RECORD=27|IndexInSheet=279|OwnerPartId=-1|LineWidth=1|Color=8388608|LocationCount=2|X1=785|Y1=475|X2=800|Y2=475
|RECORD=27|IndexInSheet=280|OwnerPartId=-1|LineWidth=1|Color=8388608|LocationCount=2|X1=785|Y1=465|X2=800|Y2=465
|RECORD=27|IndexInSheet=281|OwnerPartId=-1|LineWidth=1|Color=8388608|LocationCount=2|X1=785|Y1=455|X2=800|Y2=455
|RECORD=27|IndexInSheet=282|OwnerPartId=-1|LineWidth=1|Color=8388608|LocationCount=2|X1=785|Y1=445|X2=800|Y2=445
|RECORD=27|IndexInSheet=283|OwnerPartId=-1|LineWidth=1|Color=8388608|LocationCount=2|X1=785|Y1=435|X2=800|Y2=435
|RECORD=27|IndexInSheet=284|OwnerPartId=-1|LineWidth=1|Color=8388608|LocationCount=2|X1=785|Y1=425|X2=800|Y2=425
|RECORD=27|IndexInSheet=285|OwnerPartId=-1|LineWidth=1|Color=8388608|LocationCount=2|X1=785|Y1=415|X2=800|Y2=415
|RECORD=27|IndexInSheet=286|OwnerPartId=-1|LineWidth=1|Color=8388608|LocationCount=2|X1=785|Y1=405|X2=800|Y2=405
|RECORD=27|IndexInSheet=287|OwnerPartId=-1|LineWidth=1|Color=8388608|LocationCount=2|X1=785|Y1=395|X2=800|Y2=395
|RECORD=27|IndexInSheet=288|OwnerPartId=-1|LineWidth=1|Color=8388608|LocationCount=2|X1=785|Y1=385|X2=800|Y2=385
|RECORD=27|IndexInSheet=289|OwnerPartId=-1|LineWidth=1|Color=8388608|LocationCount=2|X1=785|Y1=375|X2=800|Y2=375
|RECORD=27|IndexInSheet=290|OwnerPartId=-1|LineWidth=1|Color=8388608|LocationCount=2|X1=785|Y1=365|X2=800|Y2=365
|RECORD=27|IndexInSheet=291|OwnerPartId=-1|LineWidth=1|Color=8388608|LocationCount=2|X1=785|Y1=355|X2=800|Y2=355
|RECORD=27|IndexInSheet=292|OwnerPartId=-1|LineWidth=1|Color=8388608|LocationCount=2|X1=785|Y1=345|X2=800|Y2=345
|RECORD=27|IndexInSheet=293|OwnerPartId=-1|LineWidth=1|Color=8388608|LocationCount=2|X1=960|Y1=355|X2=960|Y2=385
|RECORD=27|IndexInSheet=294|OwnerPartId=-1|LineWidth=1|Color=8388608|LocationCount=2|X1=960|Y1=335|X2=960|Y2=305
|RECORD=27|IndexInSheet=295|OwnerPartId=-1|LineWidth=1|Color=8388608|LocationCount=9|X1=960|Y1=405|X2=960|Y2=385|X3=1010|Y3=385|X4=1055|Y4=385|X5=1095|Y5=385|X6=1140|Y6=385|X7=1185|Y7=385|X8=1225|Y8=385|X9=1225|Y9=355
|RECORD=27|IndexInSheet=296|OwnerPartId=-1|LineWidth=1|Color=8388608|LocationCount=2|X1=1010|Y1=335|X2=1010|Y2=305
|RECORD=27|IndexInSheet=297|OwnerPartId=-1|LineWidth=1|Color=8388608|LocationCount=2|X1=1010|Y1=355|X2=1010|Y2=385
|RECORD=27|IndexInSheet=298|OwnerPartId=-1|LineWidth=1|Color=8388608|LocationCount=2|X1=1055|Y1=335|X2=1055|Y2=305
|RECORD=27|IndexInSheet=299|OwnerPartId=-1|LineWidth=1|Color=8388608|LocationCount=2|X1=1055|Y1=355|X2=1055|Y2=385
|RECORD=27|IndexInSheet=300|OwnerPartId=-1|LineWidth=1|Color=8388608|LocationCount=2|X1=1095|Y1=335|X2=1095|Y2=305
|RECORD=27|IndexInSheet=301|OwnerPartId=-1|LineWidth=1|Color=8388608|LocationCount=2|X1=1095|Y1=355|X2=1095|Y2=385
|RECORD=27|IndexInSheet=302|OwnerPartId=-1|LineWidth=1|Color=8388608|LocationCount=2|X1=1140|Y1=335|X2=1140|Y2=305
|RECORD=27|IndexInSheet=303|OwnerPartId=-1|LineWidth=1|Color=8388608|LocationCount=2|X1=1140|Y1=355|X2=1140|Y2=385
|RECORD=27|IndexInSheet=304|OwnerPartId=-1|LineWidth=1|Color=8388608|LocationCount=2|X1=1185|Y1=335|X2=1185|Y2=305
|RECORD=27|IndexInSheet=305|OwnerPartId=-1|LineWidth=1|Color=8388608|LocationCount=2|X1=1185|Y1=355|X2=1185|Y2=385
|RECORD=27|IndexInSheet=306|OwnerPartId=-1|LineWidth=1|Color=8388608|LocationCount=9|X1=960|Y1=295|X2=960|Y2=305|X3=1010|Y3=305|X4=1055|Y4=305|X5=1095|Y5=305|X6=1140|Y6=305|X7=1185|Y7=305|X8=1225|Y8=305|X9=1225|Y9=335
|RECORD=27|IndexInSheet=307|OwnerPartId=-1|LineWidth=1|Color=8388608|LocationCount=3|X1=785|Y1=525|X2=805|Y2=525|X3=805|Y3=545
|RECORD=27|IndexInSheet=308|OwnerPartId=-1|LineWidth=1|Color=8388608|LocationCount=2|X1=830|Y1=505|X2=785|Y2=505
|RECORD=27|IndexInSheet=309|OwnerPartId=-1|LineWidth=1|Color=8388608|LocationCount=2|X1=830|Y1=465|X2=830|Y2=455
|RECORD=27|IndexInSheet=310|OwnerPartId=-1|LineWidth=1|Color=8388608|LocationCount=3|X1=830|Y1=385|X2=830|Y2=365|X3=800|Y3=365
|RECORD=27|IndexInSheet=311|OwnerPartId=-1|LineWidth=1|Color=8388608|LocationCount=3|X1=340|Y1=285|X2=340|Y2=300|X3=340|Y3=325
|RECORD=27|IndexInSheet=312|OwnerPartId=-1|LineWidth=1|Color=8388608|LocationCount=3|X1=340|Y1=395|X2=340|Y2=375|X3=340|Y3=345
|RECORD=27|IndexInSheet=313|OwnerPartId=-1|LineWidth=1|Color=8388608|LocationCount=4|X1=1095|Y1=730|X2=1115|Y2=730|X3=1115|Y3=740|X4=1115|Y4=750
|RECORD=27|IndexInSheet=314|OwnerPartId=-1|LineWidth=1|Color=8388608|LocationCount=2|X1=1095|Y1=740|X2=1115|Y2=740
|RECORD=27|IndexInSheet=315|OwnerPartId=-1|LineWidth=1|Color=8388608|LocationCount=4|X1=895|Y1=730|X2=875|Y2=730|X3=875|Y3=740|X4=875|Y4=750
|RECORD=27|IndexInSheet=316|OwnerPartId=-1|LineWidth=1|Color=8388608|LocationCount=2|X1=895|Y1=740|X2=875|Y2=740
|RECORD=27|IndexInSheet=317|OwnerPartId=-1|LineWidth=1|Color=8388608|LocationCount=3|X1=725|Y1=735|X2=725|Y2=710|X3=740|Y3=710
|RECORD=27|IndexInSheet=318|OwnerPartId=-1|LineWidth=1|Color=8388608|LocationCount=3|X1=780|Y1=710|X2=860|Y2=710|X3=895|Y3=710
|RECORD=27|IndexInSheet=319|OwnerPartId=-1|LineWidth=1|Color=8388608|LocationCount=3|X1=725|Y1=710|X2=725|Y2=690|X3=740|Y3=690
|RECORD=27|IndexInSheet=320|OwnerPartId=-1|LineWidth=1|Color=8388608|LocationCount=3|X1=780|Y1=690|X2=835|Y2=690|X3=895|Y3=690
|RECORD=27|IndexInSheet=321|OwnerPartId=-1|LineWidth=1|Color=8388608|LocationCount=17|X1=1095|Y1=670|X2=1110|Y2=670|X3=1110|Y3=660|X4=1110|Y4=650|X5=1110|Y5=640|X6=1110|Y6=630|X7=1110|Y7=620|X8=1110|Y8=610|X9=1110|Y9=600|X10=1110|Y10=590|X11=1110|Y11=580|X12=1110|Y12=570|X13=1110|Y13=560|X14=1110|Y14=550|X15=1110|Y15=540|X16=1110|Y16=530|X17=1110|Y17=520
|RECORD=27|IndexInSheet=322|OwnerPartId=-1|LineWidth=1|Color=8388608|LocationCount=2|X1=1095|Y1=660|X2=1110|Y2=660
|RECORD=27|IndexInSheet=323|OwnerPartId=-1|LineWidth=1|Color=8388608|LocationCount=2|X1=1095|Y1=650|X2=1110|Y2=650
|RECORD=27|IndexInSheet=324|OwnerPartId=-1|LineWidth=1|Color=8388608|LocationCount=2|X1=1095|Y1=640|X2=1110|Y2=640
|RECORD=27|IndexInSheet=325|OwnerPartId=-1|LineWidth=1|Color=8388608|LocationCount=2|X1=1095|Y1=630|X2=1110|Y2=630
|RECORD=27|IndexInSheet=326|OwnerPartId=-1|LineWidth=1|Color=8388608|LocationCount=2|X1=1095|Y1=620|X2=1110|Y2=620
|RECORD=27|IndexInSheet=327|OwnerPartId=-1|LineWidth=1|Color=8388608|LocationCount=2|X1=1095|Y1=610|X2=1110|Y2=610
|RECORD=27|IndexInSheet=328|OwnerPartId=-1|LineWidth=1|Color=8388608|LocationCount=2|X1=1095|Y1=600|X2=1110|Y2=600
|RECORD=27|IndexInSheet=329|OwnerPartId=-1|LineWidth=1|Color=8388608|LocationCount=2|X1=1095|Y1=590|X2=1110|Y2=590
|RECORD=27|IndexInSheet=330|OwnerPartId=-1|LineWidth=1|Color=8388608|LocationCount=2|X1=1095|Y1=580|X2=1110|Y2=580
|RECORD=27|IndexInSheet=331|OwnerPartId=-1|LineWidth=1|Color=8388608|LocationCount=2|X1=1095|Y1=570|X2=1110|Y2=570
|RECORD=27|IndexInSheet=332|OwnerPartId=-1|LineWidth=1|Color=8388608|LocationCount=2|X1=1095|Y1=560|X2=1110|Y2=560
|RECORD=27|IndexInSheet=333|OwnerPartId=-1|LineWidth=1|Color=8388608|LocationCount=2|X1=1095|Y1=550|X2=1110|Y2=550
|RECORD=27|IndexInSheet=334|OwnerPartId=-1|LineWidth=1|Color=8388608|LocationCount=2|X1=1095|Y1=540|X2=1110|Y2=540
|RECORD=27|IndexInSheet=335|OwnerPartId=-1|LineWidth=1|Color=8388608|LocationCount=2|X1=1095|Y1=530|X2=1110|Y2=530
|RECORD=27|IndexInSheet=336|OwnerPartId=-1|LineWidth=1|Color=8388608|LocationCount=3|X1=1095|Y1=710|X2=1115|Y2=710|X3=1115|Y3=730
|RECORD=27|IndexInSheet=337|OwnerPartId=-1|LineWidth=1|Color=8388608|LocationCount=2|X1=1140|Y1=690|X2=1095|Y2=690
|RECORD=27|IndexInSheet=338|OwnerPartId=-1|LineWidth=1|Color=8388608|LocationCount=2|X1=1140|Y1=650|X2=1140|Y2=640
|RECORD=27|IndexInSheet=339|OwnerPartId=-1|LineWidth=1|Color=8388608|LocationCount=3|X1=1140|Y1=570|X2=1140|Y2=550|X3=1110|Y3=550
|RECORD=27|IndexInSheet=340|OwnerPartId=-1|LineWidth=1|Color=8388608|LocationCount=3|X1=600|Y1=225|X2=580|Y2=225|X3=580|Y3=240
|RECORD=27|IndexInSheet=341|OwnerPartId=-1|LineWidth=1|Color=8388608|LocationCount=5|X1=600|Y1=185|X2=580|Y2=185|X3=580|Y3=175|X4=580|Y4=165|X5=580|Y5=90
|RECORD=27|IndexInSheet=342|OwnerPartId=-1|LineWidth=1|Color=8388608|LocationCount=2|X1=600|Y1=175|X2=580|Y2=175
|RECORD=27|IndexInSheet=343|OwnerPartId=-1|LineWidth=1|Color=8388608|LocationCount=2|X1=600|Y1=165|X2=580|Y2=165
|RECORD=27|IndexInSheet=344|OwnerPartId=-1|LineWidth=1|Color=8388608|LocationCount=3|X1=535|Y1=215|X2=590|Y2=215|X3=600|Y3=215
|RECORD=27|IndexInSheet=345|OwnerPartId=-1|LineWidth=1|Color=8388608|LocationCount=4|X1=600|Y1=195|X2=590|Y2=195|X3=590|Y3=205|X4=590|Y4=215
|RECORD=27|IndexInSheet=346|OwnerPartId=-1|LineWidth=1|Color=8388608|LocationCount=2|X1=600|Y1=205|X2=590|Y2=205
|RECORD=27|IndexInSheet=347|OwnerPartId=-1|LineWidth=1|Color=8388608|LocationCount=2|X1=800|Y1=195|X2=840|Y2=195
|RECORD=27|IndexInSheet=348|OwnerPartId=-1|LineWidth=1|Color=8388608|LocationCount=3|X1=800|Y1=185|X2=815|Y2=185|X3=850|Y3=185
|RECORD=27|IndexInSheet=349|OwnerPartId=-1|LineWidth=1|Color=8388608|LocationCount=4|X1=800|Y1=165|X2=815|Y2=165|X3=815|Y3=175|X4=815|Y4=185
|RECORD=27|IndexInSheet=350|OwnerPartId=-1|LineWidth=1|Color=8388608|LocationCount=2|X1=800|Y1=175|X2=815|Y2=175
|RECORD=27|IndexInSheet=351|OwnerPartId=-1|LineWidth=1|Color=8388608|LocationCount=3|X1=800|Y1=225|X2=825|Y2=225|X3=850|Y3=225
|RECORD=27|IndexInSheet=352|OwnerPartId=-1|LineWidth=1|Color=8388608|LocationCount=3|X1=545|Y1=115|X2=560|Y2=115|X3=600|Y3=115
|RECORD=27|IndexInSheet=353|OwnerPartId=-1|LineWidth=1|Color=8388608|LocationCount=3|X1=600|Y1=125|X2=560|Y2=125|X3=560|Y3=115
|RECORD=27|IndexInSheet=354|OwnerPartId=-1|LineWidth=1|Color=8388608|LocationCount=3|X1=600|Y1=135|X2=560|Y2=135|X3=560|Y3=125
|RECORD=27|IndexInSheet=355|OwnerPartId=-1|LineWidth=1|Color=8388608|LocationCount=3|X1=800|Y1=105|X2=820|Y2=105|X3=840|Y3=105
|RECORD=27|IndexInSheet=356|OwnerPartId=-1|LineWidth=1|Color=8388608|LocationCount=3|X1=800|Y1=115|X2=820|Y2=115|X3=820|Y3=105
|RECORD=27|IndexInSheet=357|OwnerPartId=-1|LineWidth=1|Color=8388608|LocationCount=2|X1=800|Y1=215|X2=885|Y2=215
|RECORD=27|IndexInSheet=358|OwnerPartId=-1|LineWidth=1|Color=8388608|LocationCount=3|X1=800|Y1=205|X2=825|Y2=205|X3=825|Y3=225
|RECORD=27|IndexInSheet=359|OwnerPartId=-1|LineWidth=1|Color=8388608|LocationCount=3|X1=470|Y1=155|X2=440|Y2=155|X3=440|Y3=180
|RECORD=27|IndexInSheet=360|OwnerPartId=-1|LineWidth=1|Color=8388608|LocationCount=3|X1=470|Y1=140|X2=440|Y2=140|X3=440|Y3=155
|RECORD=27|IndexInSheet=361|OwnerPartId=-1|LineWidth=1|Color=8388608|LocationCount=4|X1=600|Y1=145|X2=520|Y2=145|X3=520|Y3=140|X4=510|Y4=140
|RECORD=27|IndexInSheet=362|OwnerPartId=-1|LineWidth=1|Color=8388608|LocationCount=2|X1=510|Y1=155|X2=600|Y2=155
|RECORD=27|IndexInSheet=363|OwnerPartId=-1|LineWidth=1|Color=8388608|LocationCount=2|X1=800|Y1=145|X2=875|Y2=145
|RECORD=27|IndexInSheet=364|OwnerPartId=-1|LineWidth=1|Color=8388608|LocationCount=2|X1=985|Y1=170|X2=985|Y2=180
|RECORD=27|IndexInSheet=365|OwnerPartId=-1|LineWidth=1|Color=8388608|LocationCount=2|X1=985|Y1=135|X2=985|Y2=150
|RECORD=27|IndexInSheet=366|OwnerPartId=-1|LineWidth=1|Color=8388608|LocationCount=2|X1=700|Y1=275|X2=725|Y2=275
|RECORD=27|IndexInSheet=367|OwnerPartId=-1|LineWidth=1|Color=8388608|LocationCount=2|X1=765|Y1=275|X2=790|Y2=275
|RECORD=27|IndexInSheet=368|OwnerPartId=-1|LineWidth=1|Color=8388608|LocationCount=4|X1=800|Y1=125|X2=845|Y2=125|X3=845|Y3=120|X4=865|Y4=120
|RECORD=27|IndexInSheet=369|OwnerPartId=-1|LineWidth=1|Color=8388608|LocationCount=2|X1=800|Y1=135|X2=820|Y2=135
|RECORD=27|IndexInSheet=370|OwnerPartId=-1|LineWidth=1|Color=8388608|LocationCount=2|X1=620|Y1=275|X2=630|Y2=275
|RECORD=27|IndexInSheet=371|OwnerPartId=-1|LineWidth=1|Color=8388608|LocationCount=7|X1=1645|Y1=905|X2=1645|Y2=875|X3=1605|Y3=875|X4=1560|Y4=875|X5=1515|Y5=875|X6=1475|Y6=875|X7=1430|Y7=875
|RECORD=27|IndexInSheet=372|OwnerPartId=-1|LineWidth=1|Color=8388608|LocationCount=3|X1=1430|Y1=905|X2=1430|Y2=875|X3=1430|Y3=865
|RECORD=27|IndexInSheet=373|OwnerPartId=-1|LineWidth=1|Color=8388608|LocationCount=8|X1=1645|Y1=925|X2=1645|Y2=955|X3=1605|Y3=955|X4=1560|Y4=955|X5=1515|Y5=955|X6=1475|Y6=955|X7=1430|Y7=955|X8=1430|Y8=985
|RECORD=27|IndexInSheet=374|OwnerPartId=-1|LineWidth=1|Color=8388608|LocationCount=3|X1=675|Y1=865|X2=675|Y2=880|X3=675|Y3=905
|RECORD=27|IndexInSheet=375|OwnerPartId=-1|LineWidth=1|Color=8388608|LocationCount=3|X1=675|Y1=925|X2=675|Y2=960|X3=675|Y3=970
|RECORD=27|IndexInSheet=376|OwnerPartId=-1|LineWidth=1|Color=8388608|LocationCount=3|X1=980|Y1=950|X2=960|Y2=950|X3=960|Y3=965
|RECORD=27|IndexInSheet=377|OwnerPartId=-1|LineWidth=1|Color=8388608|LocationCount=5|X1=980|Y1=910|X2=960|Y2=910|X3=960|Y3=900|X4=960|Y4=890|X5=960|Y5=815
|RECORD=27|IndexInSheet=378|OwnerPartId=-1|LineWidth=1|Color=8388608|LocationCount=2|X1=980|Y1=900|X2=960|Y2=900
|RECORD=27|IndexInSheet=379|OwnerPartId=-1|LineWidth=1|Color=8388608|LocationCount=2|X1=980|Y1=890|X2=960|Y2=890
|RECORD=27|IndexInSheet=380|OwnerPartId=-1|LineWidth=1|Color=8388608|LocationCount=3|X1=915|Y1=940|X2=970|Y2=940|X3=980|Y3=940
|RECORD=27|IndexInSheet=381|OwnerPartId=-1|LineWidth=1|Color=8388608|LocationCount=4|X1=980|Y1=920|X2=970|Y2=920|X3=970|Y3=930|X4=970|Y4=940
|RECORD=27|IndexInSheet=382|OwnerPartId=-1|LineWidth=1|Color=8388608|LocationCount=2|X1=980|Y1=930|X2=970|Y2=930
|RECORD=27|IndexInSheet=383|OwnerPartId=-1|LineWidth=1|Color=8388608|LocationCount=2|X1=1180|Y1=920|X2=1220|Y2=920
|RECORD=27|IndexInSheet=384|OwnerPartId=-1|LineWidth=1|Color=8388608|LocationCount=3|X1=1180|Y1=910|X2=1195|Y2=910|X3=1230|Y3=910
|RECORD=27|IndexInSheet=385|OwnerPartId=-1|LineWidth=1|Color=8388608|LocationCount=4|X1=1180|Y1=890|X2=1195|Y2=890|X3=1195|Y3=900|X4=1195|Y4=910
|RECORD=27|IndexInSheet=386|OwnerPartId=-1|LineWidth=1|Color=8388608|LocationCount=2|X1=1180|Y1=900|X2=1195|Y2=900
|RECORD=27|IndexInSheet=387|OwnerPartId=-1|LineWidth=1|Color=8388608|LocationCount=3|X1=1180|Y1=950|X2=1205|Y2=950|X3=1230|Y3=950
|RECORD=27|IndexInSheet=388|OwnerPartId=-1|LineWidth=1|Color=8388608|LocationCount=3|X1=925|Y1=840|X2=940|Y2=840|X3=980|Y3=840
|RECORD=27|IndexInSheet=389|OwnerPartId=-1|LineWidth=1|Color=8388608|LocationCount=3|X1=980|Y1=850|X2=940|Y2=850|X3=940|Y3=840
|RECORD=27|IndexInSheet=390|OwnerPartId=-1|LineWidth=1|Color=8388608|LocationCount=3|X1=980|Y1=860|X2=940|Y2=860|X3=940|Y3=850
|RECORD=27|IndexInSheet=391|OwnerPartId=-1|LineWidth=1|Color=8388608|LocationCount=3|X1=1180|Y1=830|X2=1200|Y2=830|X3=1220|Y3=830
|RECORD=27|IndexInSheet=392|OwnerPartId=-1|LineWidth=1|Color=8388608|LocationCount=3|X1=1180|Y1=840|X2=1200|Y2=840|X3=1200|Y3=830
|RECORD=27|IndexInSheet=393|OwnerPartId=-1|LineWidth=1|Color=8388608|LocationCount=2|X1=1180|Y1=940|X2=1265|Y2=940
|RECORD=27|IndexInSheet=394|OwnerPartId=-1|LineWidth=1|Color=8388608|LocationCount=3|X1=1180|Y1=930|X2=1205|Y2=930|X3=1205|Y3=950
|RECORD=27|IndexInSheet=395|OwnerPartId=-1|LineWidth=1|Color=8388608|LocationCount=3|X1=850|Y1=880|X2=820|Y2=880|X3=820|Y3=905
|RECORD=27|IndexInSheet=396|OwnerPartId=-1|LineWidth=1|Color=8388608|LocationCount=3|X1=850|Y1=865|X2=820|Y2=865|X3=820|Y3=880
|RECORD=27|IndexInSheet=397|OwnerPartId=-1|LineWidth=1|Color=8388608|LocationCount=4|X1=980|Y1=870|X2=900|Y2=870|X3=900|Y3=865|X4=890|Y4=865
|RECORD=27|IndexInSheet=398|OwnerPartId=-1|LineWidth=1|Color=8388608|LocationCount=2|X1=890|Y1=880|X2=980|Y2=880
|RECORD=27|IndexInSheet=399|OwnerPartId=-1|LineWidth=1|Color=8388608|LocationCount=2|X1=1180|Y1=870|X2=1255|Y2=870
|RECORD=27|IndexInSheet=400|OwnerPartId=-1|LineWidth=1|Color=8388608|LocationCount=2|X1=1285|Y1=1025|X2=1285|Y2=1035
|RECORD=27|IndexInSheet=401|OwnerPartId=-1|LineWidth=1|Color=8388608|LocationCount=2|X1=1285|Y1=990|X2=1285|Y2=1005
|RECORD=27|IndexInSheet=402|OwnerPartId=-1|LineWidth=1|Color=8388608|LocationCount=2|X1=1160|Y1=1000|X2=1185|Y2=1000
|RECORD=27|IndexInSheet=403|OwnerPartId=-1|LineWidth=1|Color=8388608|LocationCount=4|X1=1180|Y1=850|X2=1225|Y2=850|X3=1225|Y3=845|X4=1245|Y4=845
|RECORD=27|IndexInSheet=404|OwnerPartId=-1|LineWidth=1|Color=8388608|LocationCount=2|X1=1180|Y1=860|X2=1200|Y2=860
|RECORD=27|IndexInSheet=405|OwnerPartId=-1|LineWidth=1|Color=8388608|LocationCount=2|X1=300|Y1=915|X2=320|Y2=915
|RECORD=27|IndexInSheet=406|OwnerPartId=-1|LineWidth=1|Color=8388608|LocationCount=5|X1=190|Y1=915|X2=185|Y2=915|X3=185|Y3=1010|X4=120|Y4=1010|X5=105|Y5=1010
|RECORD=27|IndexInSheet=407|OwnerPartId=-1|LineWidth=1|Color=8388608|LocationCount=3|X1=105|Y1=990|X2=120|Y2=990|X3=120|Y3=1010
|RECORD=27|IndexInSheet=408|OwnerPartId=-1|LineWidth=1|Color=8388608|LocationCount=3|X1=310|Y1=830|X2=82|Y2=830|X3=82|Y3=839
|RECORD=27|IndexInSheet=409|OwnerPartId=-1|LineWidth=1|Color=8388608|LocationCount=2|X1=380|Y1=915|X2=405|Y2=915
|RECORD=27|IndexInSheet=410|OwnerPartId=-1|LineWidth=1|Color=8388608|LocationCount=4|X1=300|Y1=905|X2=310|Y2=905|X3=310|Y3=830|X4=330|Y4=830
|RECORD=27|IndexInSheet=411|OwnerPartId=-1|LineWidth=1|Color=8388608|LocationCount=4|X1=405|Y1=980|X2=405|Y2=915|X3=405|Y3=830|X4=370|Y4=830
|RECORD=27|IndexInSheet=412|OwnerPartId=-1|LineWidth=1|Color=8388608|LocationCount=3|X1=1375|Y1=920|X2=1375|Y2=955|X3=1430|Y3=955
|RECORD=27|IndexInSheet=413|OwnerPartId=-1|LineWidth=1|Color=8388608|LocationCount=3|X1=1375|Y1=900|X2=1375|Y2=875|X3=1430|Y3=875
|RECORD=27|IndexInSheet=414|OwnerPartId=-1|LineWidth=1|Color=8388608|LocationCount=3|X1=630|Y1=920|X2=630|Y2=960|X3=675|Y3=960
|RECORD=27|IndexInSheet=415|OwnerPartId=-1|LineWidth=1|Color=8388608|LocationCount=3|X1=630|Y1=900|X2=630|Y2=880|X3=675|Y3=880
|RECORD=1|LibReference=a00bbbee19879c290e62620ae7e47b1|ComponentDescription=CAP TANT POLY 47UF 35V 2917|PartCount=2|DisplayModeCount=1|IndexInSheet=416|OwnerPartId=-1|Location.X=295|Location.Y=345|CurrentPartId=1|LibraryPath=*|SourceLibraryName=Altium Content Vault|TargetFileName=*|AreaColor=11599871|Color=128|PartIDLocked=T|DesignItemId=CMP-03016-000019-1|AllPinCount=2
|RECORD=2|OwnerIndex=3479|OwnerPartId=1|Electrical=4|PinConglomerate=51|PinLength=8|Location.X=295|Location.Y=333|Name=C|Designator=1|PinPropagationDelay=0.000000E+000
|RECORD=2|OwnerIndex=3479|OwnerPartId=1|Electrical=4|PinConglomerate=49|PinLength=8|Location.X=295|Location.Y=337|Name=A|Designator=2|PinPropagationDelay=0.000000E+000
|RECORD=5|OwnerIndex=3479|IsNotAccesible=T|IndexInSheet=2|OwnerPartId=1|LineWidth=1|Color=16711680|LocationCount=4|X1=285|Y1=329|X2=290|Y2=335|X3=300|Y3=335|X4=305|Y4=329
|RECORD=13|OwnerIndex=3479|IsNotAccesible=T|IndexInSheet=3|OwnerPartId=1|Location.X=285|Location.Y=337|Corner.X=305|Corner.Y=337|LineWidth=1|Color=16711680
|RECORD=13|OwnerIndex=3479|IsNotAccesible=T|IndexInSheet=4|OwnerPartId=1|Location.X=295|Location.Y=333|Corner.X=295|Corner.Y=331|LineWidth=1|Color=16711680
|RECORD=13|OwnerIndex=3479|IsNotAccesible=T|IndexInSheet=5|OwnerPartId=1|Location.X=295|Location.Y=337|Corner.X=295|Corner.Y=340|LineWidth=1|Color=16711680
|RECORD=4|OwnerIndex=3479|IsNotAccesible=T|IndexInSheet=6|OwnerPartId=1|Location.X=284|Location.Y=347|Justification=6|Color=8388608|FontID=1|Text=+
|RECORD=41|OwnerIndex=3479|IndexInSheet=7|OwnerPartId=-1|Location.X=284|Location.Y=347|Color=8388608|FontID=1|IsHidden=T|Text=Surface Mount|Name=Mount
|RECORD=41|OwnerIndex=3479|IndexInSheet=8|OwnerPartId=-1|Location.X=284|Location.Y=347|Color=8388608|FontID=1|IsHidden=T|Text=35V|Name=Voltage Rating (DC)
|RECORD=41|OwnerIndex=3479|IndexInSheet=9|OwnerPartId=-1|Location.X=284|Location.Y=347|Color=8388608|FontID=1|IsHidden=T|Text=0.169inch|Name=Height - Seated (Max)
|RECORD=41|OwnerIndex=3479|IndexInSheet=10|OwnerPartId=-1|Location.X=284|Location.Y=347|Color=8388608|FontID=1|IsHidden=T|Text=1|Name=Package Quantity
|RECORD=41|OwnerIndex=3479|IndexInSheet=11|OwnerPartId=-1|Location.X=284|Location.Y=347|Color=8388608|FontID=1|IsHidden=T|Text=4mm|Name=Height
|RECORD=41|OwnerIndex=3479|IndexInSheet=12|OwnerPartId=-1|Location.X=284|Location.Y=347|Color=8388608|FontID=1|IsHidden=T|Text=125°C|Name=Max Operating Temperature
|RECORD=41|OwnerIndex=3479|IndexInSheet=13|OwnerPartId=-1|Location.X=284|Location.Y=347|Color=8388608|FontID=1|IsHidden=T|Text=4.3mm|Name=Width
|RECORD=41|OwnerIndex=3479|IndexInSheet=14|OwnerPartId=-1|Location.X=284|Location.Y=347|Color=8388608|FontID=1|IsHidden=T|Text=Tape and Reel|Name=Packaging
|RECORD=41|OwnerIndex=3479|IndexInSheet=15|OwnerPartId=-1|Location.X=284|Location.Y=347|Color=8388608|FontID=1|IsHidden=T|Text=2917|Name=Case/Package
|RECORD=41|OwnerIndex=3479|IndexInSheet=16|OwnerPartId=-1|Location.X=284|Location.Y=347|Color=8388608|FontID=1|IsHidden=T|Text=KO-CAP T521|Name=Series
|RECORD=41|OwnerIndex=3479|IndexInSheet=17|OwnerPartId=-1|Location.X=284|Location.Y=347|Color=8388608|FontID=1|IsHidden=T|Text=20%|Name=Tolerance
|RECORD=41|OwnerIndex=3479|IndexInSheet=18|OwnerPartId=-1|Location.X=284|Location.Y=347|Color=8388608|FontID=1|IsHidden=T|Text=10%|Name=Dissipation Factor
|RECORD=41|OwnerIndex=3479|IndexInSheet=19|OwnerPartId=-1|Location.X=284|Location.Y=347|Color=8388608|FontID=1|IsHidden=T|Text=2000Hour|Name=Life (Hours)
|RECORD=41|OwnerIndex=3479|IndexInSheet=20|OwnerPartId=-1|Location.X=284|Location.Y=347|Color=8388608|FontID=1|IsHidden=T|Text=-55°C|Name=Min Operating Temperature
|RECORD=41|OwnerIndex=3479|IndexInSheet=21|OwnerPartId=-1|Location.X=284|Location.Y=347|Color=8388608|FontID=1|IsHidden=T|Text=4.3mm|Name=Depth
|RECORD=41|OwnerIndex=3479|IndexInSheet=22|OwnerPartId=-1|Location.X=284|Location.Y=347|Color=8388608|FontID=1|IsHidden=T|Text=7343|Name=Case Code (Metric)
|RECORD=41|OwnerIndex=3479|IndexInSheet=23|OwnerPartId=-1|Location.X=284|Location.Y=347|Color=8388608|FontID=1|IsHidden=T|Text=2|Name=Number of Pins
|RECORD=41|OwnerIndex=3479|IndexInSheet=24|OwnerPartId=-1|Location.X=284|Location.Y=347|Color=8388608|FontID=1|IsHidden=T|Text=Yes|Name=RoHS Compliant
|RECORD=41|OwnerIndex=3479|IndexInSheet=25|OwnerPartId=-1|Location.X=284|Location.Y=347|Color=8388608|FontID=1|IsHidden=T|Text=2917|Name=Case Code (Imperial)
|RECORD=41|OwnerIndex=3479|IndexInSheet=26|OwnerPartId=-1|Location.X=284|Location.Y=347|Color=8388608|FontID=1|IsHidden=T|Text=47uF|Name=Capacitance
|RECORD=41|OwnerIndex=3479|IndexInSheet=27|OwnerPartId=-1|Location.X=284|Location.Y=347|Color=8388608|FontID=1|IsHidden=T|Text=No SVHC|Name=REACH SVHC
|RECORD=41|OwnerIndex=3479|IndexInSheet=28|OwnerPartId=-1|Location.X=284|Location.Y=347|Color=8388608|FontID=1|IsHidden=T|Text=General Purpose|Name=Features
|RECORD=41|OwnerIndex=3479|IndexInSheet=29|OwnerPartId=-1|Location.X=284|Location.Y=347|Color=8388608|FontID=1|IsHidden=T|Text=SMD/SMT|Name=Termination
|RECORD=41|OwnerIndex=3479|IndexInSheet=30|OwnerPartId=-1|Location.X=284|Location.Y=347|Color=8388608|FontID=1|IsHidden=T|Text=Polar|Name=Polarity
|RECORD=41|OwnerIndex=3479|IndexInSheet=31|OwnerPartId=-1|Location.X=284|Location.Y=347|Color=8388608|FontID=1|IsHidden=T|Text=7.3mm|Name=Length
|RECORD=41|OwnerIndex=3479|IndexInSheet=32|OwnerPartId=-1|Location.X=284|Location.Y=347|Color=8388608|FontID=1|IsHidden=T|Text=35V|Name=Voltage Rating
|RECORD=41|OwnerIndex=3479|IndexInSheet=33|OwnerPartId=-1|Location.X=284|Location.Y=347|Color=8388608|FontID=1|IsHidden=T|Text=Flat|Name=Construction
|RECORD=41|OwnerIndex=3479|IndexInSheet=34|OwnerPartId=-1|Location.X=284|Location.Y=347|Color=8388608|FontID=1|IsHidden=T|Text=30mR|Name=ESR (Equivalent Series Resistance)
|RECORD=34|OwnerIndex=3479|IndexInSheet=-1|OwnerPartId=-1|Location.X=280|Location.Y=330|Orientation=1|Color=8388608|FontID=2|Text=C73|Name=Designator|ReadOnlyState=1
|RECORD=41|OwnerIndex=3479|IndexInSheet=-1|OwnerPartId=1|Location.X=315|Location.Y=310|Orientation=1|Color=8388608|FontID=2|Text=47uF_35V_2917|Name=Comment
|RECORD=44|OwnerIndex=3479
|RECORD=45|OwnerIndex=3519|IndexInSheet=-1|UseComponentLibrary=T|ModelName=FP-T521X476M035ATE030-MFG|ModelType=PCBLIB|DatafileCount=1|ModelDatafileEntity0=FP-T521X476M035ATE030-MFG|ModelDatafileKind0=PCBLib|IsCurrent=T|DatalinksLocked=T|DatabaseDatalinksLocked=T
|RECORD=46|OwnerIndex=3520
|RECORD=48|OwnerIndex=3520
|RECORD=27|IndexInSheet=417|OwnerPartId=-1|LineWidth=1|Color=8388608|LocationCount=3|X1=295|Y1=345|X2=295|Y2=375|X3=340|Y3=375
|RECORD=27|IndexInSheet=418|OwnerPartId=-1|LineWidth=1|Color=8388608|LocationCount=3|X1=295|Y1=325|X2=295|Y2=300|X3=340|Y3=300
|RECORD=1|LibReference=RES-2|ComponentDescription=Chip Resistor, 0 Ohm, 0.1 W, -55 to 155 degC, 0402 (1005 Metric), RoHS, Tape and Reel|PartCount=2|DisplayModeCount=1|IndexInSheet=419|OwnerPartId=-1|Location.X=1130|Location.Y=1000|CurrentPartId=1|LibraryPath=*|SourceLibraryName=Altium Content Vault|TargetFileName=*|AreaColor=11599871|Color=128|PartIDLocked=T|DesignItemId=CMP-2000-07451-1|AllPinCount=2
|RECORD=2|OwnerIndex=3525|OwnerPartId=1|FormalType=1|Electrical=4|PinConglomerate=32|PinLength=10|Location.X=1150|Location.Y=1000|Name=2|Designator=2|PinPropagationDelay=0.000000E+000
|RECORD=2|OwnerIndex=3525|OwnerPartId=1|FormalType=1|Electrical=4|PinConglomerate=34|PinLength=10|Location.X=1130|Location.Y=1000|Name=1|Designator=1|PinPropagationDelay=0.000000E+000
|RECORD=6|OwnerIndex=3525|IsNotAccesible=T|IndexInSheet=2|OwnerPartId=1|LineWidth=1|Color=16711680|LocationCount=10|X1=1150|Y1=1000|X2=1146|Y2=1000|X3=1145|Y3=998|X4=1143|Y4=1002|X5=1141|Y5=998|X6=1139|Y6=1002|X7=1137|Y7=998|X8=1135|Y8=1002|X9=1134|Y9=1000|X10=1130|Y10=1000
|RECORD=41|OwnerIndex=3525|IndexInSheet=3|OwnerPartId=-1|Location.X=1118|Location.Y=1015|Color=8388608|FontID=1|IsHidden=T|Text=50V|Name=Voltage Rating (DC)
|RECORD=41|OwnerIndex=3525|IndexInSheet=4|OwnerPartId=-1|Location.X=1118|Location.Y=1015|Color=8388608|FontID=1|IsHidden=T|Text=2|Name=Number of Terminations
|RECORD=41|OwnerIndex=3525|IndexInSheet=5|OwnerPartId=-1|Location.X=1118|Location.Y=1015|Color=8388608|FontID=1|IsHidden=T|Text=SurfaceMount|Name=Mount
|RECORD=41|OwnerIndex=3525|IndexInSheet=6|OwnerPartId=-1|Location.X=1118|Location.Y=1015|Color=8388608|FontID=1|IsHidden=T|Text=0.35mm|Name=Height
|RECORD=41|OwnerIndex=3525|IndexInSheet=7|OwnerPartId=-1|Location.X=1118|Location.Y=1015|Color=8388608|FontID=1|IsHidden=T|Text=TapeandReel|Name=Packaging
|RECORD=41|OwnerIndex=3525|IndexInSheet=8|OwnerPartId=-1|Location.X=1118|Location.Y=1015|Color=8388608|FontID=1|IsHidden=T|Text=Tin|Name=Contact Plating
|RECORD=41|OwnerIndex=3525|IndexInSheet=9|OwnerPartId=-1|Location.X=1118|Location.Y=1015|Color=8388608|FontID=3|IsHidden=T|Text=http://www.panasonic.com/|Name=Manufacturer URL
|RECORD=41|OwnerIndex=3525|IndexInSheet=10|OwnerPartId=-1|Location.X=1118|Location.Y=1015|Color=8388608|FontID=1|IsHidden=T|Text=ThickFilm|Name=Composition
|RECORD=41|OwnerIndex=3525|IndexInSheet=11|OwnerPartId=-1|Location.X=1118|Location.Y=1015|Color=8388608|FontID=1|IsHidden=T|Text=155degC|Name=Max Operating Temperature
|RECORD=41|OwnerIndex=3525|IndexInSheet=12|OwnerPartId=-1|Location.X=1118|Location.Y=1015|Color=8388608|FontID=1|IsHidden=T|Text=600ppm/??C|Name=Temperature Coefficient
|RECORD=41|OwnerIndex=3525|IndexInSheet=13|OwnerPartId=-1|Location.X=1118|Location.Y=1015|Color=8388608|FontID=1|IsHidden=T|Text=NoSVHC|Name=REACH SVHC
|RECORD=41|OwnerIndex=3525|IndexInSheet=14|OwnerPartId=-1|Location.X=1118|Location.Y=1015|Color=8388608|FontID=1|IsHidden=T|Text=0402|Name=Case/Package
|RECORD=41|OwnerIndex=3525|IndexInSheet=15|OwnerPartId=-1|Location.X=1118|Location.Y=1015|Color=8388608|FontID=1|IsHidden=T|Text=100mW|Name=Max Power Dissipation
|RECORD=41|OwnerIndex=3525|IndexInSheet=16|OwnerPartId=-1|Location.X=1118|Location.Y=1015|Color=8388608|FontID=1|IsHidden=T|Text=402|Name=Package Reference
|RECORD=41|OwnerIndex=3525|IndexInSheet=17|OwnerPartId=-1|Location.X=1118|Location.Y=1015|Color=8388608|FontID=1|IsHidden=T|Text=0.5mm|Name=Depth
|RECORD=41|OwnerIndex=3525|IndexInSheet=18|OwnerPartId=-1|Location.X=1118|Location.Y=1015|Color=8388608|FontID=1|IsHidden=T|Text=Panasonic|Name=Manufacturer
|RECORD=41|OwnerIndex=3525|IndexInSheet=19|OwnerPartId=-1|Location.X=1118|Location.Y=1015|Color=8388608|FontID=1|IsHidden=T|Text=2-Pin Surface Mount Device, Body 1 x 0.5 mm|Name=Package Description
|RECORD=41|OwnerIndex=3525|IndexInSheet=20|OwnerPartId=-1|Location.X=1118|Location.Y=1015|Color=8388608|FontID=3|IsHidden=T|Text=https://industrial.panasonic.com/cdbs/www-data/pdf/RDA0000/AOA0000C301.pdf|Name=Datasheet URL
|RECORD=41|OwnerIndex=3525|IndexInSheet=21|OwnerPartId=-1|Location.X=1118|Location.Y=1015|Color=8388608|FontID=1|IsHidden=T|Text=True|Name=RoHSCompliant
|RECORD=41|OwnerIndex=3525|IndexInSheet=22|OwnerPartId=-1|Location.X=1118|Location.Y=1015|Color=8388608|FontID=1|IsHidden=T|Text=0402|Name=Case Code (Imperial)
|RECORD=41|OwnerIndex=3525|IndexInSheet=23|OwnerPartId=-1|Location.X=1118|Location.Y=1015|Color=8388608|FontID=1|IsHidden=T|Text=0mOhm|Name=Resistance
|RECORD=41|OwnerIndex=3525|IndexInSheet=24|OwnerPartId=-1|Location.X=1118|Location.Y=1015|Color=8388608|FontID=1|IsHidden=T|Text=Not|Name=Military Standard
|RECORD=41|OwnerIndex=3525|IndexInSheet=25|OwnerPartId=-1|Location.X=1118|Location.Y=1015|Color=8388608|FontID=1|IsHidden=T|Text=5%|Name=Tolerance
|RECORD=41|OwnerIndex=3525|IndexInSheet=26|OwnerPartId=-1|Location.X=1118|Location.Y=1015|Color=8388608|FontID=1|IsHidden=T|Text=-55degC|Name=Min Operating Temperature
|RECORD=41|OwnerIndex=3525|IndexInSheet=27|OwnerPartId=-1|Location.X=1118|Location.Y=1015|Color=8388608|FontID=1|IsHidden=T|Text=100mW|Name=Power Rating
|RECORD=41|OwnerIndex=3525|IndexInSheet=28|OwnerPartId=-1|Location.X=1118|Location.Y=1015|Color=8388608|FontID=1|IsHidden=T|Text=03/2015|Name=Datasheet Version
|RECORD=41|OwnerIndex=3525|IndexInSheet=29|OwnerPartId=-1|Location.X=1118|Location.Y=1015|Color=8388608|FontID=1|IsHidden=T|Text=1mm|Name=Length
|RECORD=41|OwnerIndex=3525|IndexInSheet=30|OwnerPartId=-1|Location.X=1118|Location.Y=1015|Color=8388608|FontID=1|IsHidden=T|Text=1005|Name=Case Code (Metric)
|RECORD=41|OwnerIndex=3525|IndexInSheet=31|OwnerPartId=-1|Location.X=1118|Location.Y=1015|Color=8388608|FontID=1|IsHidden=T|Text=SMD/SMT|Name=Termination
|RECORD=41|OwnerIndex=3525|IndexInSheet=32|OwnerPartId=-1|Location.X=1118|Location.Y=1015|Color=8388608|FontID=1|IsHidden=T|Text=SurfaceMount|Name=Mounting Technology
|RECORD=41|OwnerIndex=3525|IndexInSheet=33|OwnerPartId=-1|Location.X=1118|Location.Y=1015|Color=8388608|FontID=1|IsHidden=T|Text=50V|Name=Voltage Rating
|RECORD=41|OwnerIndex=3525|IndexInSheet=34|OwnerPartId=-1|Location.X=1118|Location.Y=1015|Color=8388608|FontID=1|IsHidden=T|Text=0.02inch|Name=Width
|RECORD=41|OwnerIndex=3525|IndexInSheet=35|OwnerPartId=-1|Location.X=1118|Location.Y=1015|Color=8388608|FontID=1|IsHidden=T|Text=1|Name=Package Quantity
|RECORD=41|OwnerIndex=3525|IndexInSheet=36|OwnerPartId=-1|Location.X=1118|Location.Y=1015|Color=8388608|FontID=1|IsHidden=T|Text=LeadFree|Name=Lead Free
|RECORD=41|OwnerIndex=3525|IndexInSheet=37|OwnerPartId=-1|Location.X=1118|Location.Y=1015|Color=8388608|FontID=1|IsHidden=T|Text=No|Name=Radiation Hardening
|RECORD=34|OwnerIndex=3525|IndexInSheet=-1|OwnerPartId=-1|Location.X=1110|Location.Y=1000|Color=8388608|FontID=1|Text=R3|Name=Designator|ReadOnlyState=1
|RECORD=41|OwnerIndex=3525|IndexInSheet=-1|OwnerPartId=-1|Location.X=1150|Location.Y=1000|Color=8388608|FontID=1|Text=0_1%_0402|Name=Comment
|RECORD=44|OwnerIndex=3525
|RECORD=45|OwnerIndex=3568|IndexInSheet=-1|Description=Chip Resistor, 2-Leads, Body 1.05x0.55mm, IPC High Density|UseComponentLibrary=T|ModelName=RESC1005X40X25LL05T05|ModelType=PCBLIB|DatafileCount=1|ModelDatafileEntity0=RESC1005X40X25LL05T05|ModelDatafileKind0=PCBLib|IsCurrent=T|DatalinksLocked=T|DatabaseDatalinksLocked=T
|RECORD=46|OwnerIndex=3569
|RECORD=48|OwnerIndex=3569
|RECORD=41|OwnerIndex=3571|IndexInSheet=-1|OwnerPartId=-1|Color=8388608|FontID=1|IsHidden=T|Text=2D|Name=Available Preview Images
|RECORD=45|OwnerIndex=3568|IndexInSheet=-1|Description=Chip Resistor, 2-Leads, Body 1.05x0.55mm, IPC Low Density|UseComponentLibrary=T|ModelName=RESC1005X40X25ML05T05|ModelType=PCBLIB|DatafileCount=1|ModelDatafileEntity0=RESC1005X40X25ML05T05|ModelDatafileKind0=PCBLib|DatalinksLocked=T|DatabaseDatalinksLocked=T
|RECORD=46|OwnerIndex=3573
|RECORD=48|OwnerIndex=3573
|RECORD=41|OwnerIndex=3575|IndexInSheet=-1|OwnerPartId=-1|Color=8388608|FontID=1|IsHidden=T|Text=2D|Name=Available Preview Images
|RECORD=45|OwnerIndex=3568|IndexInSheet=-1|Description=Chip Resistor, 2-Leads, Body 1.05x0.55mm, IPC Medium Density|UseComponentLibrary=T|ModelName=RESC1005X40X25NL05T05|ModelType=PCBLIB|DatafileCount=1|ModelDatafileEntity0=RESC1005X40X25NL05T05|ModelDatafileKind0=PCBLib|DatalinksLocked=T|DatabaseDatalinksLocked=T
|RECORD=46|OwnerIndex=3577
|RECORD=48|OwnerIndex=3577
|RECORD=41|OwnerIndex=3579|IndexInSheet=-1|OwnerPartId=-1|Color=8388608|FontID=1|IsHidden=T|Text=2D|Name=Available Preview Images
|RECORD=27|IndexInSheet=420|OwnerPartId=-1|LineWidth=1|Color=8388608|LocationCount=2|X1=1080|Y1=1000|X2=1120|Y2=1000
|RECORD=1|LibReference=RES|PartCount=2|DisplayModeCount=2|IndexInSheet=421|OwnerPartId=-1|Location.X=1050|Location.Y=1010|CurrentPartId=1|SourceLibraryName=Altium Content Vault|TargetFileName=*|AreaColor=11599871|Color=128|PartIDLocked=F|DesignItemId=CMP-2002-07394-1|AllPinCount=2
|RECORD=2|OwnerIndex=3582|OwnerPartId=1|OwnerPartDisplayMode=1|FormalType=1|Electrical=4|PinConglomerate=32|PinLength=10|Location.X=1070|Location.Y=1000|Name=2|Designator=2|PinPropagationDelay=0.000000E+000
|RECORD=2|OwnerIndex=3582|OwnerPartId=1|OwnerPartDisplayMode=1|FormalType=1|Electrical=4|PinConglomerate=34|PinLength=10|Location.X=1050|Location.Y=1000|Name=1|Designator=1|PinPropagationDelay=0.000000E+000
|RECORD=14|OwnerIndex=3582|IsNotAccesible=T|IndexInSheet=2|OwnerPartId=1|OwnerPartDisplayMode=1|Location.X=1050|Location.Y=996|Corner.X=1070|Corner.Y=1004|LineWidth=1|Color=16711680|AreaColor=11599871
|RECORD=2|OwnerIndex=3582|OwnerPartId=1|FormalType=1|Electrical=4|PinConglomerate=32|PinLength=10|Location.X=1070|Location.Y=1000|Name=2|Designator=2|PinPropagationDelay=0.000000E+000
|RECORD=2|OwnerIndex=3582|OwnerPartId=1|FormalType=1|Electrical=4|PinConglomerate=34|PinLength=10|Location.X=1050|Location.Y=1000|Name=1|Designator=1|PinPropagationDelay=0.000000E+000
|RECORD=6|OwnerIndex=3582|IsNotAccesible=T|IndexInSheet=5|OwnerPartId=1|LineWidth=1|Color=16711680|LocationCount=10|X1=1070|Y1=1000|X2=1066|Y2=1000|X3=1065|Y3=998|X4=1063|Y4=1002|X5=1061|Y5=998|X6=1059|Y6=1002|X7=1057|Y7=998|X8=1055|Y8=1002|X9=1054|Y9=1000|X10=1050|Y10=1000
|RECORD=41|OwnerIndex=3582|IndexInSheet=6|OwnerPartId=-1|Location.X=1038|Location.Y=1013|Color=8388608|FontID=1|IsHidden=T|Text=Yageo / Phycomp|Name=Manufacturer
|RECORD=41|OwnerIndex=3582|IndexInSheet=7|OwnerPartId=-1|Location.X=1038|Location.Y=1013|Color=8388608|FontID=1|IsHidden=T|Text=RC0402FR-07147KL|Name=Part Number
|RECORD=34|OwnerIndex=3582|IndexInSheet=-1|OwnerPartId=-1|Location.X=1049|Location.Y=1003|Color=8388608|FontID=1|Text=R2|Name=Designator|ReadOnlyState=1
|RECORD=41|OwnerIndex=3582|IndexInSheet=-1|OwnerPartId=-1|Location.X=1049|Location.Y=987|Color=8388608|FontID=1|Text=147K_1%_0402|Name=Comment
|RECORD=44|OwnerIndex=3582
|RECORD=45|OwnerIndex=3597|IndexInSheet=-1|Description=Chip Resistor, 2-Leads, Body 1.00x0.50mm, IPC Low Density|UseComponentLibrary=T|ModelName=RESC1005X40X25ML05T10|ModelType=PCBLIB|DatafileCount=1|ModelDatafileEntity0=RESC1005X40X25ML05T10|ModelDatafileKind0=PCBLib|IsCurrent=T|DatalinksLocked=T|DatabaseDatalinksLocked=T
|RECORD=46|OwnerIndex=3598
|RECORD=48|OwnerIndex=3598
|RECORD=41|OwnerIndex=3600|IndexInSheet=-1|OwnerPartId=-1|Color=8388608|FontID=1|IsHidden=T|Text=2D|Name=Available Preview Images
|RECORD=45|OwnerIndex=3597|IndexInSheet=-1|Description=Chip Resistor, 2-Leads, Body 1.00x0.50mm, IPC High Density|UseComponentLibrary=T|ModelName=RESC1005X40X25LL05T10|ModelType=PCBLIB|DatafileCount=1|ModelDatafileEntity0=RESC1005X40X25LL05T10|ModelDatafileKind0=PCBLib|DatalinksLocked=T|DatabaseDatalinksLocked=T
|RECORD=46|OwnerIndex=3602
|RECORD=48|OwnerIndex=3602
|RECORD=41|OwnerIndex=3604|IndexInSheet=-1|OwnerPartId=-1|Color=8388608|FontID=1|IsHidden=T|Text=2D|Name=Available Preview Images
|RECORD=45|OwnerIndex=3597|IndexInSheet=-1|Description=Chip Resistor, 2-Leads, Body 1.00x0.50mm, IPC Medium Density|UseComponentLibrary=T|ModelName=RESC1005X40X25NL05T10|ModelType=PCBLIB|DatafileCount=1|ModelDatafileEntity0=RESC1005X40X25NL05T10|ModelDatafileKind0=PCBLib|DatalinksLocked=T|DatabaseDatalinksLocked=T
|RECORD=46|OwnerIndex=3606
|RECORD=48|OwnerIndex=3606
|RECORD=41|OwnerIndex=3608|IndexInSheet=-1|OwnerPartId=-1|Color=8388608|FontID=1|IsHidden=T|Text=2D|Name=Available Preview Images
|RECORD=27|IndexInSheet=422|OwnerPartId=-1|LineWidth=1|Color=8388608|LocationCount=2|X1=1000|Y1=1000|X2=1040|Y2=1000
|RECORD=1|LibReference=CAP|PartCount=2|DisplayModeCount=2|IndexInSheet=423|OwnerPartId=-1|Location.X=230|Location.Y=720|Orientation=1|CurrentPartId=1|SourceLibraryName=Altium Content Vault|TargetFileName=*|AreaColor=11599871|Color=128|PartIDLocked=F|DesignItemId=CMP-1034-02072-2|AllPinCount=2
|RECORD=2|OwnerIndex=3611|OwnerPartId=1|OwnerPartDisplayMode=1|FormalType=1|Electrical=4|PinConglomerate=35|PinLength=10|Location.X=240|Location.Y=720|Name=1|Designator=1|PinPropagationDelay=0.000000E+000
|RECORD=2|OwnerIndex=3611|OwnerPartId=1|OwnerPartDisplayMode=1|FormalType=1|Electrical=4|PinConglomerate=33|PinLength=10|Location.X=240|Location.Y=730|Name=2|Designator=2|PinPropagationDelay=0.000000E+000
|RECORD=13|OwnerIndex=3611|IsNotAccesible=T|IndexInSheet=2|OwnerPartId=1|OwnerPartDisplayMode=1|Location.X=248|Location.Y=720|Corner.X=232|Corner.Y=720|LineWidth=1|Color=16711680
|RECORD=13|OwnerIndex=3611|IsNotAccesible=T|IndexInSheet=3|OwnerPartId=1|OwnerPartDisplayMode=1|Location.X=240|Location.Y=724|Corner.X=240|Corner.Y=730|LineWidth=1|Color=16711680
|RECORD=12|OwnerIndex=3611|IsNotAccesible=T|IndexInSheet=4|OwnerPartId=1|OwnerPartDisplayMode=1|Location.X=240|Location.Y=740|Radius=16|LineWidth=1|StartAngle=241.000|EndAngle=270.000|Color=16711680
|RECORD=12|OwnerIndex=3611|IsNotAccesible=T|IndexInSheet=5|OwnerPartId=1|OwnerPartDisplayMode=1|Location.X=240|Location.Y=740|Radius=16|LineWidth=1|StartAngle=270.000|EndAngle=299.000|Color=16711680
|RECORD=2|OwnerIndex=3611|OwnerPartId=1|FormalType=1|Electrical=4|PinConglomerate=35|PinLength=10|Location.X=240|Location.Y=720|Name=1|Designator=1|PinPropagationDelay=0.000000E+000
|RECORD=2|OwnerIndex=3611|OwnerPartId=1|FormalType=1|Electrical=4|PinConglomerate=33|PinLength=10|Location.X=240|Location.Y=730|Name=2|Designator=2|PinPropagationDelay=0.000000E+000
|RECORD=13|OwnerIndex=3611|IsNotAccesible=T|IndexInSheet=8|OwnerPartId=1|Location.X=232|Location.Y=727|Corner.X=248|Corner.Y=727|LineWidth=1|Color=16711680
|RECORD=13|OwnerIndex=3611|IsNotAccesible=T|IndexInSheet=9|OwnerPartId=1|Location.X=248|Location.Y=723|Corner.X=232|Corner.Y=723|LineWidth=1|Color=16711680
|RECORD=6|OwnerIndex=3611|IsNotAccesible=T|IndexInSheet=10|OwnerPartId=1|LineWidth=1|Color=16711680|LocationCount=2|X1=240|Y1=720|X2=240|Y2=723
|RECORD=6|OwnerIndex=3611|IsNotAccesible=T|IndexInSheet=11|OwnerPartId=1|LineWidth=1|Color=16711680|LocationCount=2|X1=240|Y1=730|X2=240|Y2=727
|RECORD=41|OwnerIndex=3611|IndexInSheet=12|OwnerPartId=-1|Location.X=231|Location.Y=742|Color=8388608|FontID=1|IsHidden=T|Text=04023D104KAT2A|Name=Part Number
|RECORD=41|OwnerIndex=3611|IndexInSheet=13|OwnerPartId=-1|Location.X=231|Location.Y=742|Color=8388608|FontID=1|IsHidden=T|Text=AVX Interconnect / Elco|Name=Manufacturer
|RECORD=34|OwnerIndex=3611|IndexInSheet=-1|OwnerPartId=-1|Location.X=230|Location.Y=710|Orientation=1|Color=8388608|FontID=2|Text=C21|Name=Designator|ReadOnlyState=1
|RECORD=41|OwnerIndex=3611|IndexInSheet=-1|OwnerPartId=-1|Location.X=260|Location.Y=695|Orientation=1|Color=8388608|FontID=2|Text=0.1uF_25V_0402|Name=Comment
|RECORD=44|OwnerIndex=3611
|RECORD=45|OwnerIndex=3632|IndexInSheet=-1|Description=Chip Capacitor, 2-Leads, Body 1.00x0.50mm, IPC Medium Density|UseComponentLibrary=T|ModelName=CAPC1005X56X25NL10T15|ModelType=PCBLIB|DatafileCount=1|ModelDatafileEntity0=CAPC1005X56X25NL10T15|ModelDatafileKind0=PCBLib|IsCurrent=T|DatalinksLocked=T|DatabaseDatalinksLocked=T
|RECORD=46|OwnerIndex=3633
|RECORD=48|OwnerIndex=3633
|RECORD=41|OwnerIndex=3635|IndexInSheet=-1|OwnerPartId=-1|Color=8388608|FontID=1|IsHidden=T|Text=2D|Name=Available Preview Images
|RECORD=45|OwnerIndex=3632|IndexInSheet=-1|Description=Chip Capacitor, 2-Leads, Body 1.00x0.50mm, IPC High Density|UseComponentLibrary=T|ModelName=CAPC1005X56X25LL10T15|ModelType=PCBLIB|DatafileCount=1|ModelDatafileEntity0=CAPC1005X56X25LL10T15|ModelDatafileKind0=PCBLib|DatalinksLocked=T|DatabaseDatalinksLocked=T
|RECORD=46|OwnerIndex=3637
|RECORD=48|OwnerIndex=3637
|RECORD=41|OwnerIndex=3639|IndexInSheet=-1|OwnerPartId=-1|Color=8388608|FontID=1|IsHidden=T|Text=2D|Name=Available Preview Images
|RECORD=45|OwnerIndex=3632|IndexInSheet=-1|Description=Chip Capacitor, 2-Leads, Body 1.00x0.50mm, IPC Low Density|UseComponentLibrary=T|ModelName=CAPC1005X56X25ML10T15|ModelType=PCBLIB|DatafileCount=1|ModelDatafileEntity0=CAPC1005X56X25ML10T15|ModelDatafileKind0=PCBLib|DatalinksLocked=T|DatabaseDatalinksLocked=T
|RECORD=46|OwnerIndex=3641
|RECORD=48|OwnerIndex=3641
|RECORD=41|OwnerIndex=3643|IndexInSheet=-1|OwnerPartId=-1|Color=8388608|FontID=1|IsHidden=T|Text=2D|Name=Available Preview Images
|RECORD=1|LibReference=CAP|PartCount=2|DisplayModeCount=2|IndexInSheet=424|OwnerPartId=-1|Location.X=1275|Location.Y=745|Orientation=1|CurrentPartId=1|SourceLibraryName=Altium Content Vault|TargetFileName=*|AreaColor=11599871|Color=128|PartIDLocked=F|DesignItemId=CMP-1034-02072-2|AllPinCount=2
|RECORD=2|OwnerIndex=3645|OwnerPartId=1|OwnerPartDisplayMode=1|FormalType=1|Electrical=4|PinConglomerate=35|PinLength=10|Location.X=1285|Location.Y=745|Name=1|Designator=1|PinPropagationDelay=0.000000E+000
|RECORD=2|OwnerIndex=3645|OwnerPartId=1|OwnerPartDisplayMode=1|FormalType=1|Electrical=4|PinConglomerate=33|PinLength=10|Location.X=1285|Location.Y=755|Name=2|Designator=2|PinPropagationDelay=0.000000E+000
|RECORD=13|OwnerIndex=3645|IsNotAccesible=T|IndexInSheet=2|OwnerPartId=1|OwnerPartDisplayMode=1|Location.X=1293|Location.Y=745|Corner.X=1277|Corner.Y=745|LineWidth=1|Color=16711680
|RECORD=13|OwnerIndex=3645|IsNotAccesible=T|IndexInSheet=3|OwnerPartId=1|OwnerPartDisplayMode=1|Location.X=1285|Location.Y=749|Corner.X=1285|Corner.Y=755|LineWidth=1|Color=16711680
|RECORD=12|OwnerIndex=3645|IsNotAccesible=T|IndexInSheet=4|OwnerPartId=1|OwnerPartDisplayMode=1|Location.X=1285|Location.Y=765|Radius=16|LineWidth=1|StartAngle=241.000|EndAngle=270.000|Color=16711680
|RECORD=12|OwnerIndex=3645|IsNotAccesible=T|IndexInSheet=5|OwnerPartId=1|OwnerPartDisplayMode=1|Location.X=1285|Location.Y=765|Radius=16|LineWidth=1|StartAngle=270.000|EndAngle=299.000|Color=16711680
|RECORD=2|OwnerIndex=3645|OwnerPartId=1|FormalType=1|Electrical=4|PinConglomerate=35|PinLength=10|Location.X=1285|Location.Y=745|Name=1|Designator=1|PinPropagationDelay=0.000000E+000
|RECORD=2|OwnerIndex=3645|OwnerPartId=1|FormalType=1|Electrical=4|PinConglomerate=33|PinLength=10|Location.X=1285|Location.Y=755|Name=2|Designator=2|PinPropagationDelay=0.000000E+000
|RECORD=13|OwnerIndex=3645|IsNotAccesible=T|IndexInSheet=8|OwnerPartId=1|Location.X=1277|Location.Y=752|Corner.X=1293|Corner.Y=752|LineWidth=1|Color=16711680
|RECORD=13|OwnerIndex=3645|IsNotAccesible=T|IndexInSheet=9|OwnerPartId=1|Location.X=1293|Location.Y=748|Corner.X=1277|Corner.Y=748|LineWidth=1|Color=16711680
|RECORD=6|OwnerIndex=3645|IsNotAccesible=T|IndexInSheet=10|OwnerPartId=1|LineWidth=1|Color=16711680|LocationCount=2|X1=1285|Y1=745|X2=1285|Y2=748
|RECORD=6|OwnerIndex=3645|IsNotAccesible=T|IndexInSheet=11|OwnerPartId=1|LineWidth=1|Color=16711680|LocationCount=2|X1=1285|Y1=755|X2=1285|Y2=752
|RECORD=41|OwnerIndex=3645|IndexInSheet=12|OwnerPartId=-1|Location.X=1276|Location.Y=767|Color=8388608|FontID=1|IsHidden=T|Text=04023D104KAT2A|Name=Part Number
|RECORD=41|OwnerIndex=3645|IndexInSheet=13|OwnerPartId=-1|Location.X=1276|Location.Y=767|Color=8388608|FontID=1|IsHidden=T|Text=AVX Interconnect / Elco|Name=Manufacturer
|RECORD=34|OwnerIndex=3645|IndexInSheet=-1|OwnerPartId=-1|Location.X=1275|Location.Y=735|Orientation=1|Color=8388608|FontID=2|Text=C19|Name=Designator|ReadOnlyState=1
|RECORD=41|OwnerIndex=3645|IndexInSheet=-1|OwnerPartId=-1|Location.X=1305|Location.Y=720|Orientation=1|Color=8388608|FontID=2|Text=0.1uF_25V_0402|Name=Comment
|RECORD=44|OwnerIndex=3645
|RECORD=45|OwnerIndex=3666|IndexInSheet=-1|Description=Chip Capacitor, 2-Leads, Body 1.00x0.50mm, IPC Medium Density|UseComponentLibrary=T|ModelName=CAPC1005X56X25NL10T15|ModelType=PCBLIB|DatafileCount=1|ModelDatafileEntity0=CAPC1005X56X25NL10T15|ModelDatafileKind0=PCBLib|IsCurrent=T|DatalinksLocked=T|DatabaseDatalinksLocked=T
|RECORD=46|OwnerIndex=3667
|RECORD=48|OwnerIndex=3667
|RECORD=41|OwnerIndex=3669|IndexInSheet=-1|OwnerPartId=-1|Color=8388608|FontID=1|IsHidden=T|Text=2D|Name=Available Preview Images
|RECORD=45|OwnerIndex=3666|IndexInSheet=-1|Description=Chip Capacitor, 2-Leads, Body 1.00x0.50mm, IPC High Density|UseComponentLibrary=T|ModelName=CAPC1005X56X25LL10T15|ModelType=PCBLIB|DatafileCount=1|ModelDatafileEntity0=CAPC1005X56X25LL10T15|ModelDatafileKind0=PCBLib|DatalinksLocked=T|DatabaseDatalinksLocked=T
|RECORD=46|OwnerIndex=3671
|RECORD=48|OwnerIndex=3671
|RECORD=41|OwnerIndex=3673|IndexInSheet=-1|OwnerPartId=-1|Color=8388608|FontID=1|IsHidden=T|Text=2D|Name=Available Preview Images
|RECORD=45|OwnerIndex=3666|IndexInSheet=-1|Description=Chip Capacitor, 2-Leads, Body 1.00x0.50mm, IPC Low Density|UseComponentLibrary=T|ModelName=CAPC1005X56X25ML10T15|ModelType=PCBLIB|DatafileCount=1|ModelDatafileEntity0=CAPC1005X56X25ML10T15|ModelDatafileKind0=PCBLib|DatalinksLocked=T|DatabaseDatalinksLocked=T
|RECORD=46|OwnerIndex=3675
|RECORD=48|OwnerIndex=3675
|RECORD=41|OwnerIndex=3677|IndexInSheet=-1|OwnerPartId=-1|Color=8388608|FontID=1|IsHidden=T|Text=2D|Name=Available Preview Images
|RECORD=1|LibReference=CAP|PartCount=2|DisplayModeCount=2|IndexInSheet=425|OwnerPartId=-1|Location.X=1270|Location.Y=600|Orientation=1|CurrentPartId=1|SourceLibraryName=Altium Content Vault|TargetFileName=*|AreaColor=11599871|Color=128|PartIDLocked=F|DesignItemId=CMP-1034-02072-2|AllPinCount=2
|RECORD=2|OwnerIndex=3679|OwnerPartId=1|OwnerPartDisplayMode=1|FormalType=1|Electrical=4|PinConglomerate=35|PinLength=10|Location.X=1280|Location.Y=600|Name=1|Designator=1|PinPropagationDelay=0.000000E+000
|RECORD=2|OwnerIndex=3679|OwnerPartId=1|OwnerPartDisplayMode=1|FormalType=1|Electrical=4|PinConglomerate=33|PinLength=10|Location.X=1280|Location.Y=610|Name=2|Designator=2|PinPropagationDelay=0.000000E+000
|RECORD=13|OwnerIndex=3679|IsNotAccesible=T|IndexInSheet=2|OwnerPartId=1|OwnerPartDisplayMode=1|Location.X=1288|Location.Y=600|Corner.X=1272|Corner.Y=600|LineWidth=1|Color=16711680
|RECORD=13|OwnerIndex=3679|IsNotAccesible=T|IndexInSheet=3|OwnerPartId=1|OwnerPartDisplayMode=1|Location.X=1280|Location.Y=604|Corner.X=1280|Corner.Y=610|LineWidth=1|Color=16711680
|RECORD=12|OwnerIndex=3679|IsNotAccesible=T|IndexInSheet=4|OwnerPartId=1|OwnerPartDisplayMode=1|Location.X=1280|Location.Y=620|Radius=16|LineWidth=1|StartAngle=241.000|EndAngle=270.000|Color=16711680
|RECORD=12|OwnerIndex=3679|IsNotAccesible=T|IndexInSheet=5|OwnerPartId=1|OwnerPartDisplayMode=1|Location.X=1280|Location.Y=620|Radius=16|LineWidth=1|StartAngle=270.000|EndAngle=299.000|Color=16711680
|RECORD=2|OwnerIndex=3679|OwnerPartId=1|FormalType=1|Electrical=4|PinConglomerate=35|PinLength=10|Location.X=1280|Location.Y=600|Name=1|Designator=1|PinPropagationDelay=0.000000E+000
|RECORD=2|OwnerIndex=3679|OwnerPartId=1|FormalType=1|Electrical=4|PinConglomerate=33|PinLength=10|Location.X=1280|Location.Y=610|Name=2|Designator=2|PinPropagationDelay=0.000000E+000
|RECORD=13|OwnerIndex=3679|IsNotAccesible=T|IndexInSheet=8|OwnerPartId=1|Location.X=1272|Location.Y=607|Corner.X=1288|Corner.Y=607|LineWidth=1|Color=16711680
|RECORD=13|OwnerIndex=3679|IsNotAccesible=T|IndexInSheet=9|OwnerPartId=1|Location.X=1288|Location.Y=603|Corner.X=1272|Corner.Y=603|LineWidth=1|Color=16711680
|RECORD=6|OwnerIndex=3679|IsNotAccesible=T|IndexInSheet=10|OwnerPartId=1|LineWidth=1|Color=16711680|LocationCount=2|X1=1280|Y1=600|X2=1280|Y2=603
|RECORD=6|OwnerIndex=3679|IsNotAccesible=T|IndexInSheet=11|OwnerPartId=1|LineWidth=1|Color=16711680|LocationCount=2|X1=1280|Y1=610|X2=1280|Y2=607
|RECORD=41|OwnerIndex=3679|IndexInSheet=12|OwnerPartId=-1|Location.X=1271|Location.Y=622|Color=8388608|FontID=1|IsHidden=T|Text=04023D104KAT2A|Name=Part Number
|RECORD=41|OwnerIndex=3679|IndexInSheet=13|OwnerPartId=-1|Location.X=1271|Location.Y=622|Color=8388608|FontID=1|IsHidden=T|Text=AVX Interconnect / Elco|Name=Manufacturer
|RECORD=34|OwnerIndex=3679|IndexInSheet=-1|OwnerPartId=-1|Location.X=1270|Location.Y=590|Orientation=1|Color=8388608|FontID=2|Text=C66|Name=Designator|ReadOnlyState=1
|RECORD=41|OwnerIndex=3679|IndexInSheet=-1|OwnerPartId=-1|Location.X=1300|Location.Y=575|Orientation=1|Color=8388608|FontID=2|Text=0.1uF_25V_0402|Name=Comment
|RECORD=44|OwnerIndex=3679
|RECORD=45|OwnerIndex=3700|IndexInSheet=-1|Description=Chip Capacitor, 2-Leads, Body 1.00x0.50mm, IPC Medium Density|UseComponentLibrary=T|ModelName=CAPC1005X56X25NL10T15|ModelType=PCBLIB|DatafileCount=1|ModelDatafileEntity0=CAPC1005X56X25NL10T15|ModelDatafileKind0=PCBLib|IsCurrent=T|DatalinksLocked=T|DatabaseDatalinksLocked=T
|RECORD=46|OwnerIndex=3701
|RECORD=48|OwnerIndex=3701
|RECORD=41|OwnerIndex=3703|IndexInSheet=-1|OwnerPartId=-1|Color=8388608|FontID=1|IsHidden=T|Text=2D|Name=Available Preview Images
|RECORD=45|OwnerIndex=3700|IndexInSheet=-1|Description=Chip Capacitor, 2-Leads, Body 1.00x0.50mm, IPC High Density|UseComponentLibrary=T|ModelName=CAPC1005X56X25LL10T15|ModelType=PCBLIB|DatafileCount=1|ModelDatafileEntity0=CAPC1005X56X25LL10T15|ModelDatafileKind0=PCBLib|DatalinksLocked=T|DatabaseDatalinksLocked=T
|RECORD=46|OwnerIndex=3705
|RECORD=48|OwnerIndex=3705
|RECORD=41|OwnerIndex=3707|IndexInSheet=-1|OwnerPartId=-1|Color=8388608|FontID=1|IsHidden=T|Text=2D|Name=Available Preview Images
|RECORD=45|OwnerIndex=3700|IndexInSheet=-1|Description=Chip Capacitor, 2-Leads, Body 1.00x0.50mm, IPC Low Density|UseComponentLibrary=T|ModelName=CAPC1005X56X25ML10T15|ModelType=PCBLIB|DatafileCount=1|ModelDatafileEntity0=CAPC1005X56X25ML10T15|ModelDatafileKind0=PCBLib|DatalinksLocked=T|DatabaseDatalinksLocked=T
|RECORD=46|OwnerIndex=3709
|RECORD=48|OwnerIndex=3709
|RECORD=41|OwnerIndex=3711|IndexInSheet=-1|OwnerPartId=-1|Color=8388608|FontID=1|IsHidden=T|Text=2D|Name=Available Preview Images
|RECORD=1|LibReference=RES|PartCount=2|DisplayModeCount=2|IndexInSheet=426|OwnerPartId=-1|Location.X=545|Location.Y=460|Orientation=1|CurrentPartId=1|SourceLibraryName=Altium Content Vault|TargetFileName=*|AreaColor=11599871|Color=128|PartIDLocked=F|DesignItemId=CMP-2002-04694-1|AllPinCount=2
|RECORD=2|OwnerIndex=3713|OwnerPartId=1|OwnerPartDisplayMode=1|FormalType=1|Electrical=4|PinConglomerate=33|PinLength=10|Location.X=555|Location.Y=480|Name=2|Designator=2|PinPropagationDelay=0.000000E+000
|RECORD=2|OwnerIndex=3713|OwnerPartId=1|OwnerPartDisplayMode=1|FormalType=1|Electrical=4|PinConglomerate=35|PinLength=10|Location.X=555|Location.Y=460|Name=1|Designator=1|PinPropagationDelay=0.000000E+000
|RECORD=14|OwnerIndex=3713|IsNotAccesible=T|IndexInSheet=2|OwnerPartId=1|OwnerPartDisplayMode=1|Location.X=551|Location.Y=460|Corner.X=559|Corner.Y=480|LineWidth=1|Color=16711680|AreaColor=11599871
|RECORD=2|OwnerIndex=3713|OwnerPartId=1|FormalType=1|Electrical=4|PinConglomerate=33|PinLength=10|Location.X=555|Location.Y=480|Name=2|Designator=2|PinPropagationDelay=0.000000E+000
|RECORD=2|OwnerIndex=3713|OwnerPartId=1|FormalType=1|Electrical=4|PinConglomerate=35|PinLength=10|Location.X=555|Location.Y=460|Name=1|Designator=1|PinPropagationDelay=0.000000E+000
|RECORD=6|OwnerIndex=3713|IsNotAccesible=T|IndexInSheet=5|OwnerPartId=1|LineWidth=1|Color=16711680|LocationCount=10|X1=555|Y1=480|X2=555|Y2=476|X3=557|Y3=475|X4=553|Y4=473|X5=557|Y5=471|X6=553|Y6=469|X7=557|Y7=467|X8=553|Y8=465|X9=555|Y9=464|X10=555|Y10=460
|RECORD=41|OwnerIndex=3713|IndexInSheet=6|OwnerPartId=-1|Location.X=552|Location.Y=492|Color=8388608|FontID=1|IsHidden=T|Text=Bourns|Name=Manufacturer
|RECORD=41|OwnerIndex=3713|IndexInSheet=7|OwnerPartId=-1|Location.X=552|Location.Y=492|Color=8388608|FontID=1|IsHidden=T|Text=CR0402-FX-1002GLF|Name=Part Number
|RECORD=34|OwnerIndex=3713|IndexInSheet=-1|OwnerPartId=-1|Location.X=555|Location.Y=450|Orientation=1|Color=8388608|FontID=2|Text=R185|Name=Designator|ReadOnlyState=1
|RECORD=41|OwnerIndex=3713|IndexInSheet=-1|OwnerPartId=-1|Location.X=570|Location.Y=440|Orientation=1|Color=8388608|FontID=2|Text=10K_1%_0402|Name=Comment
|RECORD=44|OwnerIndex=3713
|RECORD=45|OwnerIndex=3728|IndexInSheet=-1|Description=Chip Resistor, 2-Leads, Body 1.00x0.50mm, IPC Medium Density|UseComponentLibrary=T|ModelName=RESC1005X40X25NL10T10|ModelType=PCBLIB|IsCurrent=T|DatalinksLocked=T|DatabaseDatalinksLocked=T
|RECORD=46|OwnerIndex=3729
|RECORD=48|OwnerIndex=3729
|RECORD=41|OwnerIndex=3731|IndexInSheet=-1|OwnerPartId=-1|Color=8388608|FontID=1|IsHidden=T|Text=2D|Name=Available Preview Images
|RECORD=45|OwnerIndex=3728|IndexInSheet=-1|Description=Chip Resistor, 2-Leads, Body 1.00x0.50mm, IPC High Density|UseComponentLibrary=T|ModelName=RESC1005X40X25LL10T10|ModelType=PCBLIB|DatalinksLocked=T|DatabaseDatalinksLocked=T
|RECORD=46|OwnerIndex=3733
|RECORD=48|OwnerIndex=3733
|RECORD=41|OwnerIndex=3735|IndexInSheet=-1|OwnerPartId=-1|Color=8388608|FontID=1|IsHidden=T|Text=2D|Name=Available Preview Images
|RECORD=45|OwnerIndex=3728|IndexInSheet=-1|Description=Chip Resistor, 2-Leads, Body 1.00x0.50mm, IPC Low Density|UseComponentLibrary=T|ModelName=RESC1005X40X25ML10T10|ModelType=PCBLIB|DatalinksLocked=T|DatabaseDatalinksLocked=T
|RECORD=46|OwnerIndex=3737
|RECORD=48|OwnerIndex=3737
|RECORD=41|OwnerIndex=3739|IndexInSheet=-1|OwnerPartId=-1|Color=8388608|FontID=1|IsHidden=T|Text=2D|Name=Available Preview Images
|RECORD=1|LibReference=RES|PartCount=2|DisplayModeCount=2|IndexInSheet=427|OwnerPartId=-1|Location.X=460|Location.Y=535|CurrentPartId=1|SourceLibraryName=Altium Content Vault|TargetFileName=*|AreaColor=11599871|Color=128|PartIDLocked=F|DesignItemId=CMP-2002-06039-1|AllPinCount=2
|RECORD=2|OwnerIndex=3741|OwnerPartId=1|OwnerPartDisplayMode=1|FormalType=1|Electrical=4|PinConglomerate=32|PinLength=10|Location.X=480|Location.Y=525|Name=2|Designator=2|PinPropagationDelay=0.000000E+000
|RECORD=2|OwnerIndex=3741|OwnerPartId=1|OwnerPartDisplayMode=1|FormalType=1|Electrical=4|PinConglomerate=34|PinLength=10|Location.X=460|Location.Y=525|Name=1|Designator=1|PinPropagationDelay=0.000000E+000
|RECORD=14|OwnerIndex=3741|IsNotAccesible=T|IndexInSheet=2|OwnerPartId=1|OwnerPartDisplayMode=1|Location.X=460|Location.Y=521|Corner.X=480|Corner.Y=529|LineWidth=1|Color=16711680|AreaColor=11599871
|RECORD=2|OwnerIndex=3741|OwnerPartId=1|FormalType=1|Electrical=4|PinConglomerate=32|PinLength=10|Location.X=480|Location.Y=525|Name=2|Designator=2|PinPropagationDelay=0.000000E+000
|RECORD=2|OwnerIndex=3741|OwnerPartId=1|FormalType=1|Electrical=4|PinConglomerate=34|PinLength=10|Location.X=460|Location.Y=525|Name=1|Designator=1|PinPropagationDelay=0.000000E+000
|RECORD=6|OwnerIndex=3741|IsNotAccesible=T|IndexInSheet=5|OwnerPartId=1|LineWidth=1|Color=16711680|LocationCount=10|X1=480|Y1=525|X2=476|Y2=525|X3=475|Y3=523|X4=473|Y4=527|X5=471|Y5=523|X6=469|Y6=527|X7=467|Y7=523|X8=465|Y8=527|X9=464|Y9=525|X10=460|Y10=525
|RECORD=41|OwnerIndex=3741|IndexInSheet=6|OwnerPartId=-1|Location.X=448|Location.Y=538|Color=8388608|FontID=1|IsHidden=T|Text=MC00625W0402120K|Name=Part Number
|RECORD=41|OwnerIndex=3741|IndexInSheet=7|OwnerPartId=-1|Location.X=448|Location.Y=538|Color=8388608|FontID=1|IsHidden=T|Text=Multicomp|Name=Manufacturer
|RECORD=34|OwnerIndex=3741|IndexInSheet=-1|OwnerPartId=-1|Location.X=459|Location.Y=528|Color=8388608|FontID=1|Text=R129|Name=Designator|ReadOnlyState=1
|RECORD=41|OwnerIndex=3741|IndexInSheet=-1|OwnerPartId=-1|Location.X=485|Location.Y=525|Color=8388608|FontID=1|Text=20K_1%_0402|Name=Comment
|RECORD=44|OwnerIndex=3741
|RECORD=45|OwnerIndex=3756|IndexInSheet=-1|Description=Chip Resistor, 2-Leads, Body 1.00x0.50mm, IPC Medium Density|UseComponentLibrary=T|ModelName=RESC1005X40X25NL10T10|ModelType=PCBLIB|IsCurrent=T|DatalinksLocked=T|DatabaseDatalinksLocked=T
|RECORD=46|OwnerIndex=3757
|RECORD=48|OwnerIndex=3757
|RECORD=41|OwnerIndex=3759|IndexInSheet=-1|OwnerPartId=-1|Color=8388608|FontID=1|IsHidden=T|Text=2D|Name=Available Preview Images
|RECORD=45|OwnerIndex=3756|IndexInSheet=-1|Description=Chip Resistor, 2-Leads, Body 1.00x0.50mm, IPC High Density|UseComponentLibrary=T|ModelName=RESC1005X40X25LL10T10|ModelType=PCBLIB|DatalinksLocked=T|DatabaseDatalinksLocked=T
|RECORD=46|OwnerIndex=3761
|RECORD=48|OwnerIndex=3761
|RECORD=41|OwnerIndex=3763|IndexInSheet=-1|OwnerPartId=-1|Color=8388608|FontID=1|IsHidden=T|Text=2D|Name=Available Preview Images
|RECORD=45|OwnerIndex=3756|IndexInSheet=-1|Description=Chip Resistor, 2-Leads, Body 1.00x0.50mm, IPC Low Density|UseComponentLibrary=T|ModelName=RESC1005X40X25ML10T10|ModelType=PCBLIB|DatalinksLocked=T|DatabaseDatalinksLocked=T
|RECORD=46|OwnerIndex=3765
|RECORD=48|OwnerIndex=3765
|RECORD=41|OwnerIndex=3767|IndexInSheet=-1|OwnerPartId=-1|Color=8388608|FontID=1|IsHidden=T|Text=2D|Name=Available Preview Images
|RECORD=17|IndexInSheet=428|OwnerPartId=-1|Style=4|ShowNetName=T|Location.X=555|Location.Y=430|Orientation=3|Color=128|FontID=1|Text=GND
|RECORD=27|IndexInSheet=429|OwnerPartId=-1|LineWidth=1|Color=8388608|LocationCount=3|X1=555|Y1=430|X2=555|Y2=440|X3=555|Y3=450
|RECORD=1|LibReference=RES|PartCount=2|DisplayModeCount=2|IndexInSheet=430|OwnerPartId=-1|Location.X=460|Location.Y=515|CurrentPartId=1|SourceLibraryName=Altium Content Vault|TargetFileName=*|AreaColor=11599871|Color=128|PartIDLocked=F|DesignItemId=CMP-2002-06039-1|AllPinCount=2
|RECORD=2|OwnerIndex=3771|OwnerPartId=1|OwnerPartDisplayMode=1|FormalType=1|Electrical=4|PinConglomerate=32|PinLength=10|Location.X=480|Location.Y=505|Name=2|Designator=2|PinPropagationDelay=0.000000E+000
|RECORD=2|OwnerIndex=3771|OwnerPartId=1|OwnerPartDisplayMode=1|FormalType=1|Electrical=4|PinConglomerate=34|PinLength=10|Location.X=460|Location.Y=505|Name=1|Designator=1|PinPropagationDelay=0.000000E+000
|RECORD=14|OwnerIndex=3771|IsNotAccesible=T|IndexInSheet=2|OwnerPartId=1|OwnerPartDisplayMode=1|Location.X=460|Location.Y=501|Corner.X=480|Corner.Y=509|LineWidth=1|Color=16711680|AreaColor=11599871
|RECORD=2|OwnerIndex=3771|OwnerPartId=1|FormalType=1|Electrical=4|PinConglomerate=32|PinLength=10|Location.X=480|Location.Y=505|Name=2|Designator=2|PinPropagationDelay=0.000000E+000
|RECORD=2|OwnerIndex=3771|OwnerPartId=1|FormalType=1|Electrical=4|PinConglomerate=34|PinLength=10|Location.X=460|Location.Y=505|Name=1|Designator=1|PinPropagationDelay=0.000000E+000
|RECORD=6|OwnerIndex=3771|IsNotAccesible=T|IndexInSheet=5|OwnerPartId=1|LineWidth=1|Color=16711680|LocationCount=10|X1=480|Y1=505|X2=476|Y2=505|X3=475|Y3=503|X4=473|Y4=507|X5=471|Y5=503|X6=469|Y6=507|X7=467|Y7=503|X8=465|Y8=507|X9=464|Y9=505|X10=460|Y10=505
|RECORD=41|OwnerIndex=3771|IndexInSheet=6|OwnerPartId=-1|Location.X=448|Location.Y=518|Color=8388608|FontID=1|IsHidden=T|Text=MC00625W0402120K|Name=Part Number
|RECORD=41|OwnerIndex=3771|IndexInSheet=7|OwnerPartId=-1|Location.X=448|Location.Y=518|Color=8388608|FontID=1|IsHidden=T|Text=Multicomp|Name=Manufacturer
|RECORD=34|OwnerIndex=3771|IndexInSheet=-1|OwnerPartId=-1|Location.X=459|Location.Y=508|Color=8388608|FontID=1|Text=R183|Name=Designator|ReadOnlyState=1
|RECORD=41|OwnerIndex=3771|IndexInSheet=-1|OwnerPartId=-1|Location.X=485|Location.Y=505|Color=8388608|FontID=1|Text=20K_1%_0402|Name=Comment
|RECORD=44|OwnerIndex=3771
|RECORD=45|OwnerIndex=3786|IndexInSheet=-1|Description=Chip Resistor, 2-Leads, Body 1.00x0.50mm, IPC Medium Density|UseComponentLibrary=T|ModelName=RESC1005X40X25NL10T10|ModelType=PCBLIB|IsCurrent=T|DatalinksLocked=T|DatabaseDatalinksLocked=T
|RECORD=46|OwnerIndex=3787
|RECORD=48|OwnerIndex=3787
|RECORD=41|OwnerIndex=3789|IndexInSheet=-1|OwnerPartId=-1|Color=8388608|FontID=1|IsHidden=T|Text=2D|Name=Available Preview Images
|RECORD=45|OwnerIndex=3786|IndexInSheet=-1|Description=Chip Resistor, 2-Leads, Body 1.00x0.50mm, IPC High Density|UseComponentLibrary=T|ModelName=RESC1005X40X25LL10T10|ModelType=PCBLIB|DatalinksLocked=T|DatabaseDatalinksLocked=T
|RECORD=46|OwnerIndex=3791
|RECORD=48|OwnerIndex=3791
|RECORD=41|OwnerIndex=3793|IndexInSheet=-1|OwnerPartId=-1|Color=8388608|FontID=1|IsHidden=T|Text=2D|Name=Available Preview Images
|RECORD=45|OwnerIndex=3786|IndexInSheet=-1|Description=Chip Resistor, 2-Leads, Body 1.00x0.50mm, IPC Low Density|UseComponentLibrary=T|ModelName=RESC1005X40X25ML10T10|ModelType=PCBLIB|DatalinksLocked=T|DatabaseDatalinksLocked=T
|RECORD=46|OwnerIndex=3795
|RECORD=48|OwnerIndex=3795
|RECORD=41|OwnerIndex=3797|IndexInSheet=-1|OwnerPartId=-1|Color=8388608|FontID=1|IsHidden=T|Text=2D|Name=Available Preview Images
|RECORD=27|IndexInSheet=431|OwnerPartId=-1|LineWidth=1|Color=8388608|LocationCount=2|X1=555|Y1=490|X2=555|Y2=525
|RECORD=27|IndexInSheet=432|OwnerPartId=-1|LineWidth=1|Color=8388608|LocationCount=3|X1=490|Y1=525|X2=555|Y2=525|X3=585|Y3=525
|RECORD=1|LibReference=RES|PartCount=2|DisplayModeCount=2|IndexInSheet=433|OwnerPartId=-1|Location.X=520|Location.Y=465|Orientation=1|CurrentPartId=1|SourceLibraryName=Altium Content Vault|TargetFileName=*|AreaColor=11599871|Color=128|PartIDLocked=F|DesignItemId=CMP-2002-04694-1|AllPinCount=2
|RECORD=2|OwnerIndex=3801|OwnerPartId=1|OwnerPartDisplayMode=1|FormalType=1|Electrical=4|PinConglomerate=33|PinLength=10|Location.X=530|Location.Y=485|Name=2|Designator=2|PinPropagationDelay=0.000000E+000
|RECORD=2|OwnerIndex=3801|OwnerPartId=1|OwnerPartDisplayMode=1|FormalType=1|Electrical=4|PinConglomerate=35|PinLength=10|Location.X=530|Location.Y=465|Name=1|Designator=1|PinPropagationDelay=0.000000E+000
|RECORD=14|OwnerIndex=3801|IsNotAccesible=T|IndexInSheet=2|OwnerPartId=1|OwnerPartDisplayMode=1|Location.X=526|Location.Y=465|Corner.X=534|Corner.Y=485|LineWidth=1|Color=16711680|AreaColor=11599871
|RECORD=2|OwnerIndex=3801|OwnerPartId=1|FormalType=1|Electrical=4|PinConglomerate=33|PinLength=10|Location.X=530|Location.Y=485|Name=2|Designator=2|PinPropagationDelay=0.000000E+000
|RECORD=2|OwnerIndex=3801|OwnerPartId=1|FormalType=1|Electrical=4|PinConglomerate=35|PinLength=10|Location.X=530|Location.Y=465|Name=1|Designator=1|PinPropagationDelay=0.000000E+000
|RECORD=6|OwnerIndex=3801|IsNotAccesible=T|IndexInSheet=5|OwnerPartId=1|LineWidth=1|Color=16711680|LocationCount=10|X1=530|Y1=485|X2=530|Y2=481|X3=532|Y3=480|X4=528|Y4=478|X5=532|Y5=476|X6=528|Y6=474|X7=532|Y7=472|X8=528|Y8=470|X9=530|Y9=469|X10=530|Y10=465
|RECORD=41|OwnerIndex=3801|IndexInSheet=6|OwnerPartId=-1|Location.X=527|Location.Y=497|Color=8388608|FontID=1|IsHidden=T|Text=Bourns|Name=Manufacturer
|RECORD=41|OwnerIndex=3801|IndexInSheet=7|OwnerPartId=-1|Location.X=527|Location.Y=497|Color=8388608|FontID=1|IsHidden=T|Text=CR0402-FX-1002GLF|Name=Part Number
|RECORD=34|OwnerIndex=3801|IndexInSheet=-1|OwnerPartId=-1|Location.X=530|Location.Y=455|Orientation=1|Color=8388608|FontID=2|Text=R184|Name=Designator|ReadOnlyState=1
|RECORD=41|OwnerIndex=3801|IndexInSheet=-1|OwnerPartId=-1|Location.X=545|Location.Y=445|Orientation=1|Color=8388608|FontID=2|Text=10K_1%_0402|Name=Comment
|RECORD=44|OwnerIndex=3801
|RECORD=45|OwnerIndex=3816|IndexInSheet=-1|Description=Chip Resistor, 2-Leads, Body 1.00x0.50mm, IPC Medium Density|UseComponentLibrary=T|ModelName=RESC1005X40X25NL10T10|ModelType=PCBLIB|IsCurrent=T|DatalinksLocked=T|DatabaseDatalinksLocked=T
|RECORD=46|OwnerIndex=3817
|RECORD=48|OwnerIndex=3817
|RECORD=41|OwnerIndex=3819|IndexInSheet=-1|OwnerPartId=-1|Color=8388608|FontID=1|IsHidden=T|Text=2D|Name=Available Preview Images
|RECORD=45|OwnerIndex=3816|IndexInSheet=-1|Description=Chip Resistor, 2-Leads, Body 1.00x0.50mm, IPC High Density|UseComponentLibrary=T|ModelName=RESC1005X40X25LL10T10|ModelType=PCBLIB|DatalinksLocked=T|DatabaseDatalinksLocked=T
|RECORD=46|OwnerIndex=3821
|RECORD=48|OwnerIndex=3821
|RECORD=41|OwnerIndex=3823|IndexInSheet=-1|OwnerPartId=-1|Color=8388608|FontID=1|IsHidden=T|Text=2D|Name=Available Preview Images
|RECORD=45|OwnerIndex=3816|IndexInSheet=-1|Description=Chip Resistor, 2-Leads, Body 1.00x0.50mm, IPC Low Density|UseComponentLibrary=T|ModelName=RESC1005X40X25ML10T10|ModelType=PCBLIB|DatalinksLocked=T|DatabaseDatalinksLocked=T
|RECORD=46|OwnerIndex=3825
|RECORD=48|OwnerIndex=3825
|RECORD=41|OwnerIndex=3827|IndexInSheet=-1|OwnerPartId=-1|Color=8388608|FontID=1|IsHidden=T|Text=2D|Name=Available Preview Images
|RECORD=27|IndexInSheet=434|OwnerPartId=-1|LineWidth=1|Color=8388608|LocationCount=2|X1=530|Y1=495|X2=530|Y2=505
|RECORD=27|IndexInSheet=435|OwnerPartId=-1|LineWidth=1|Color=8388608|LocationCount=3|X1=530|Y1=455|X2=530|Y2=440|X3=555|Y3=440
|RECORD=1|LibReference=RES|PartCount=2|DisplayModeCount=2|IndexInSheet=436|OwnerPartId=-1|Location.X=750|Location.Y=720|CurrentPartId=1|SourceLibraryName=Altium Content Vault|TargetFileName=*|AreaColor=11599871|Color=128|PartIDLocked=F|DesignItemId=CMP-2002-06039-1|AllPinCount=2
|RECORD=2|OwnerIndex=3831|OwnerPartId=1|OwnerPartDisplayMode=1|FormalType=1|Electrical=4|PinConglomerate=32|PinLength=10|Location.X=770|Location.Y=710|Name=2|Designator=2|PinPropagationDelay=0.000000E+000
|RECORD=2|OwnerIndex=3831|OwnerPartId=1|OwnerPartDisplayMode=1|FormalType=1|Electrical=4|PinConglomerate=34|PinLength=10|Location.X=750|Location.Y=710|Name=1|Designator=1|PinPropagationDelay=0.000000E+000
|RECORD=14|OwnerIndex=3831|IsNotAccesible=T|IndexInSheet=2|OwnerPartId=1|OwnerPartDisplayMode=1|Location.X=750|Location.Y=706|Corner.X=770|Corner.Y=714|LineWidth=1|Color=16711680|AreaColor=11599871
|RECORD=2|OwnerIndex=3831|OwnerPartId=1|FormalType=1|Electrical=4|PinConglomerate=32|PinLength=10|Location.X=770|Location.Y=710|Name=2|Designator=2|PinPropagationDelay=0.000000E+000
|RECORD=2|OwnerIndex=3831|OwnerPartId=1|FormalType=1|Electrical=4|PinConglomerate=34|PinLength=10|Location.X=750|Location.Y=710|Name=1|Designator=1|PinPropagationDelay=0.000000E+000
|RECORD=6|OwnerIndex=3831|IsNotAccesible=T|IndexInSheet=5|OwnerPartId=1|LineWidth=1|Color=16711680|LocationCount=10|X1=770|Y1=710|X2=766|Y2=710|X3=765|Y3=708|X4=763|Y4=712|X5=761|Y5=708|X6=759|Y6=712|X7=757|Y7=708|X8=755|Y8=712|X9=754|Y9=710|X10=750|Y10=710
|RECORD=41|OwnerIndex=3831|IndexInSheet=6|OwnerPartId=-1|Location.X=738|Location.Y=723|Color=8388608|FontID=1|IsHidden=T|Text=MC00625W0402120K|Name=Part Number
|RECORD=41|OwnerIndex=3831|IndexInSheet=7|OwnerPartId=-1|Location.X=738|Location.Y=723|Color=8388608|FontID=1|IsHidden=T|Text=Multicomp|Name=Manufacturer
|RECORD=34|OwnerIndex=3831|IndexInSheet=-1|OwnerPartId=-1|Location.X=749|Location.Y=713|Color=8388608|FontID=1|Text=R6|Name=Designator|ReadOnlyState=1
|RECORD=41|OwnerIndex=3831|IndexInSheet=-1|OwnerPartId=-1|Location.X=775|Location.Y=710|Color=8388608|FontID=1|Text=20K_1%_0402|Name=Comment
|RECORD=44|OwnerIndex=3831
|RECORD=45|OwnerIndex=3846|IndexInSheet=-1|Description=Chip Resistor, 2-Leads, Body 1.00x0.50mm, IPC Medium Density|UseComponentLibrary=T|ModelName=RESC1005X40X25NL10T10|ModelType=PCBLIB|IsCurrent=T|DatalinksLocked=T|DatabaseDatalinksLocked=T
|RECORD=46|OwnerIndex=3847
|RECORD=48|OwnerIndex=3847
|RECORD=41|OwnerIndex=3849|IndexInSheet=-1|OwnerPartId=-1|Color=8388608|FontID=1|IsHidden=T|Text=2D|Name=Available Preview Images
|RECORD=45|OwnerIndex=3846|IndexInSheet=-1|Description=Chip Resistor, 2-Leads, Body 1.00x0.50mm, IPC High Density|UseComponentLibrary=T|ModelName=RESC1005X40X25LL10T10|ModelType=PCBLIB|DatalinksLocked=T|DatabaseDatalinksLocked=T
|RECORD=46|OwnerIndex=3851
|RECORD=48|OwnerIndex=3851
|RECORD=41|OwnerIndex=3853|IndexInSheet=-1|OwnerPartId=-1|Color=8388608|FontID=1|IsHidden=T|Text=2D|Name=Available Preview Images
|RECORD=45|OwnerIndex=3846|IndexInSheet=-1|Description=Chip Resistor, 2-Leads, Body 1.00x0.50mm, IPC Low Density|UseComponentLibrary=T|ModelName=RESC1005X40X25ML10T10|ModelType=PCBLIB|DatalinksLocked=T|DatabaseDatalinksLocked=T
|RECORD=46|OwnerIndex=3855
|RECORD=48|OwnerIndex=3855
|RECORD=41|OwnerIndex=3857|IndexInSheet=-1|OwnerPartId=-1|Color=8388608|FontID=1|IsHidden=T|Text=2D|Name=Available Preview Images
|RECORD=1|LibReference=RES|PartCount=2|DisplayModeCount=2|IndexInSheet=437|OwnerPartId=-1|Location.X=750|Location.Y=700|CurrentPartId=1|SourceLibraryName=Altium Content Vault|TargetFileName=*|AreaColor=11599871|Color=128|PartIDLocked=F|DesignItemId=CMP-2002-06039-1|AllPinCount=2
|RECORD=2|OwnerIndex=3859|OwnerPartId=1|OwnerPartDisplayMode=1|FormalType=1|Electrical=4|PinConglomerate=32|PinLength=10|Location.X=770|Location.Y=690|Name=2|Designator=2|PinPropagationDelay=0.000000E+000
|RECORD=2|OwnerIndex=3859|OwnerPartId=1|OwnerPartDisplayMode=1|FormalType=1|Electrical=4|PinConglomerate=34|PinLength=10|Location.X=750|Location.Y=690|Name=1|Designator=1|PinPropagationDelay=0.000000E+000
|RECORD=14|OwnerIndex=3859|IsNotAccesible=T|IndexInSheet=2|OwnerPartId=1|OwnerPartDisplayMode=1|Location.X=750|Location.Y=686|Corner.X=770|Corner.Y=694|LineWidth=1|Color=16711680|AreaColor=11599871
|RECORD=2|OwnerIndex=3859|OwnerPartId=1|FormalType=1|Electrical=4|PinConglomerate=32|PinLength=10|Location.X=770|Location.Y=690|Name=2|Designator=2|PinPropagationDelay=0.000000E+000
|RECORD=2|OwnerIndex=3859|OwnerPartId=1|FormalType=1|Electrical=4|PinConglomerate=34|PinLength=10|Location.X=750|Location.Y=690|Name=1|Designator=1|PinPropagationDelay=0.000000E+000
|RECORD=6|OwnerIndex=3859|IsNotAccesible=T|IndexInSheet=5|OwnerPartId=1|LineWidth=1|Color=16711680|LocationCount=10|X1=770|Y1=690|X2=766|Y2=690|X3=765|Y3=688|X4=763|Y4=692|X5=761|Y5=688|X6=759|Y6=692|X7=757|Y7=688|X8=755|Y8=692|X9=754|Y9=690|X10=750|Y10=690
|RECORD=41|OwnerIndex=3859|IndexInSheet=6|OwnerPartId=-1|Location.X=738|Location.Y=703|Color=8388608|FontID=1|IsHidden=T|Text=MC00625W0402120K|Name=Part Number
|RECORD=41|OwnerIndex=3859|IndexInSheet=7|OwnerPartId=-1|Location.X=738|Location.Y=703|Color=8388608|FontID=1|IsHidden=T|Text=Multicomp|Name=Manufacturer
|RECORD=34|OwnerIndex=3859|IndexInSheet=-1|OwnerPartId=-1|Location.X=749|Location.Y=693|Color=8388608|FontID=1|Text=R9|Name=Designator|ReadOnlyState=1
|RECORD=41|OwnerIndex=3859|IndexInSheet=-1|OwnerPartId=-1|Location.X=775|Location.Y=690|Color=8388608|FontID=1|Text=20K_1%_0402|Name=Comment
|RECORD=44|OwnerIndex=3859
|RECORD=45|OwnerIndex=3874|IndexInSheet=-1|Description=Chip Resistor, 2-Leads, Body 1.00x0.50mm, IPC Medium Density|UseComponentLibrary=T|ModelName=RESC1005X40X25NL10T10|ModelType=PCBLIB|IsCurrent=T|DatalinksLocked=T|DatabaseDatalinksLocked=T
|RECORD=46|OwnerIndex=3875
|RECORD=48|OwnerIndex=3875
|RECORD=41|OwnerIndex=3877|IndexInSheet=-1|OwnerPartId=-1|Color=8388608|FontID=1|IsHidden=T|Text=2D|Name=Available Preview Images
|RECORD=45|OwnerIndex=3874|IndexInSheet=-1|Description=Chip Resistor, 2-Leads, Body 1.00x0.50mm, IPC High Density|UseComponentLibrary=T|ModelName=RESC1005X40X25LL10T10|ModelType=PCBLIB|DatalinksLocked=T|DatabaseDatalinksLocked=T
|RECORD=46|OwnerIndex=3879
|RECORD=48|OwnerIndex=3879
|RECORD=41|OwnerIndex=3881|IndexInSheet=-1|OwnerPartId=-1|Color=8388608|FontID=1|IsHidden=T|Text=2D|Name=Available Preview Images
|RECORD=45|OwnerIndex=3874|IndexInSheet=-1|Description=Chip Resistor, 2-Leads, Body 1.00x0.50mm, IPC Low Density|UseComponentLibrary=T|ModelName=RESC1005X40X25ML10T10|ModelType=PCBLIB|DatalinksLocked=T|DatabaseDatalinksLocked=T
|RECORD=46|OwnerIndex=3883
|RECORD=48|OwnerIndex=3883
|RECORD=41|OwnerIndex=3885|IndexInSheet=-1|OwnerPartId=-1|Color=8388608|FontID=1|IsHidden=T|Text=2D|Name=Available Preview Images
|RECORD=1|LibReference=RES|PartCount=2|DisplayModeCount=2|IndexInSheet=438|OwnerPartId=-1|Location.X=850|Location.Y=645|Orientation=1|CurrentPartId=1|SourceLibraryName=Altium Content Vault|TargetFileName=*|AreaColor=11599871|Color=128|PartIDLocked=F|DesignItemId=CMP-2002-04694-1|AllPinCount=2
|RECORD=2|OwnerIndex=3887|OwnerPartId=1|OwnerPartDisplayMode=1|FormalType=1|Electrical=4|PinConglomerate=33|PinLength=10|Location.X=860|Location.Y=665|Name=2|Designator=2|PinPropagationDelay=0.000000E+000
|RECORD=2|OwnerIndex=3887|OwnerPartId=1|OwnerPartDisplayMode=1|FormalType=1|Electrical=4|PinConglomerate=35|PinLength=10|Location.X=860|Location.Y=645|Name=1|Designator=1|PinPropagationDelay=0.000000E+000
|RECORD=14|OwnerIndex=3887|IsNotAccesible=T|IndexInSheet=2|OwnerPartId=1|OwnerPartDisplayMode=1|Location.X=856|Location.Y=645|Corner.X=864|Corner.Y=665|LineWidth=1|Color=16711680|AreaColor=11599871
|RECORD=2|OwnerIndex=3887|OwnerPartId=1|FormalType=1|Electrical=4|PinConglomerate=33|PinLength=10|Location.X=860|Location.Y=665|Name=2|Designator=2|PinPropagationDelay=0.000000E+000
|RECORD=2|OwnerIndex=3887|OwnerPartId=1|FormalType=1|Electrical=4|PinConglomerate=35|PinLength=10|Location.X=860|Location.Y=645|Name=1|Designator=1|PinPropagationDelay=0.000000E+000
|RECORD=6|OwnerIndex=3887|IsNotAccesible=T|IndexInSheet=5|OwnerPartId=1|LineWidth=1|Color=16711680|LocationCount=10|X1=860|Y1=665|X2=860|Y2=661|X3=862|Y3=660|X4=858|Y4=658|X5=862|Y5=656|X6=858|Y6=654|X7=862|Y7=652|X8=858|Y8=650|X9=860|Y9=649|X10=860|Y10=645
|RECORD=41|OwnerIndex=3887|IndexInSheet=6|OwnerPartId=-1|Location.X=857|Location.Y=677|Color=8388608|FontID=1|IsHidden=T|Text=Bourns|Name=Manufacturer
|RECORD=41|OwnerIndex=3887|IndexInSheet=7|OwnerPartId=-1|Location.X=857|Location.Y=677|Color=8388608|FontID=1|IsHidden=T|Text=CR0402-FX-1002GLF|Name=Part Number
|RECORD=34|OwnerIndex=3887|IndexInSheet=-1|OwnerPartId=-1|Location.X=860|Location.Y=635|Orientation=1|Color=8388608|FontID=2|Text=R60|Name=Designator|ReadOnlyState=1
|RECORD=41|OwnerIndex=3887|IndexInSheet=-1|OwnerPartId=-1|Location.X=875|Location.Y=625|Orientation=1|Color=8388608|FontID=2|Text=10K_1%_0402|Name=Comment
|RECORD=44|OwnerIndex=3887
|RECORD=45|OwnerIndex=3902|IndexInSheet=-1|Description=Chip Resistor, 2-Leads, Body 1.00x0.50mm, IPC Medium Density|UseComponentLibrary=T|ModelName=RESC1005X40X25NL10T10|ModelType=PCBLIB|IsCurrent=T|DatalinksLocked=T|DatabaseDatalinksLocked=T
|RECORD=46|OwnerIndex=3903
|RECORD=48|OwnerIndex=3903
|RECORD=41|OwnerIndex=3905|IndexInSheet=-1|OwnerPartId=-1|Color=8388608|FontID=1|IsHidden=T|Text=2D|Name=Available Preview Images
|RECORD=45|OwnerIndex=3902|IndexInSheet=-1|Description=Chip Resistor, 2-Leads, Body 1.00x0.50mm, IPC High Density|UseComponentLibrary=T|ModelName=RESC1005X40X25LL10T10|ModelType=PCBLIB|DatalinksLocked=T|DatabaseDatalinksLocked=T
|RECORD=46|OwnerIndex=3907
|RECORD=48|OwnerIndex=3907
|RECORD=41|OwnerIndex=3909|IndexInSheet=-1|OwnerPartId=-1|Color=8388608|FontID=1|IsHidden=T|Text=2D|Name=Available Preview Images
|RECORD=45|OwnerIndex=3902|IndexInSheet=-1|Description=Chip Resistor, 2-Leads, Body 1.00x0.50mm, IPC Low Density|UseComponentLibrary=T|ModelName=RESC1005X40X25ML10T10|ModelType=PCBLIB|DatalinksLocked=T|DatabaseDatalinksLocked=T
|RECORD=46|OwnerIndex=3911
|RECORD=48|OwnerIndex=3911
|RECORD=41|OwnerIndex=3913|IndexInSheet=-1|OwnerPartId=-1|Color=8388608|FontID=1|IsHidden=T|Text=2D|Name=Available Preview Images
|RECORD=17|IndexInSheet=439|OwnerPartId=-1|Style=4|ShowNetName=T|Location.X=860|Location.Y=615|Orientation=3|Color=128|FontID=1|Text=GND
|RECORD=27|IndexInSheet=440|OwnerPartId=-1|LineWidth=1|Color=8388608|LocationCount=3|X1=860|Y1=615|X2=860|Y2=625|X3=860|Y3=635
|RECORD=27|IndexInSheet=441|OwnerPartId=-1|LineWidth=1|Color=8388608|LocationCount=2|X1=860|Y1=675|X2=860|Y2=710
|RECORD=1|LibReference=RES|PartCount=2|DisplayModeCount=2|IndexInSheet=442|OwnerPartId=-1|Location.X=825|Location.Y=650|Orientation=1|CurrentPartId=1|SourceLibraryName=Altium Content Vault|TargetFileName=*|AreaColor=11599871|Color=128|PartIDLocked=F|DesignItemId=CMP-2002-04694-1|AllPinCount=2
|RECORD=2|OwnerIndex=3918|OwnerPartId=1|OwnerPartDisplayMode=1|FormalType=1|Electrical=4|PinConglomerate=33|PinLength=10|Location.X=835|Location.Y=670|Name=2|Designator=2|PinPropagationDelay=0.000000E+000
|RECORD=2|OwnerIndex=3918|OwnerPartId=1|OwnerPartDisplayMode=1|FormalType=1|Electrical=4|PinConglomerate=35|PinLength=10|Location.X=835|Location.Y=650|Name=1|Designator=1|PinPropagationDelay=0.000000E+000
|RECORD=14|OwnerIndex=3918|IsNotAccesible=T|IndexInSheet=2|OwnerPartId=1|OwnerPartDisplayMode=1|Location.X=831|Location.Y=650|Corner.X=839|Corner.Y=670|LineWidth=1|Color=16711680|AreaColor=11599871
|RECORD=2|OwnerIndex=3918|OwnerPartId=1|FormalType=1|Electrical=4|PinConglomerate=33|PinLength=10|Location.X=835|Location.Y=670|Name=2|Designator=2|PinPropagationDelay=0.000000E+000
|RECORD=2|OwnerIndex=3918|OwnerPartId=1|FormalType=1|Electrical=4|PinConglomerate=35|PinLength=10|Location.X=835|Location.Y=650|Name=1|Designator=1|PinPropagationDelay=0.000000E+000
|RECORD=6|OwnerIndex=3918|IsNotAccesible=T|IndexInSheet=5|OwnerPartId=1|LineWidth=1|Color=16711680|LocationCount=10|X1=835|Y1=670|X2=835|Y2=666|X3=837|Y3=665|X4=833|Y4=663|X5=837|Y5=661|X6=833|Y6=659|X7=837|Y7=657|X8=833|Y8=655|X9=835|Y9=654|X10=835|Y10=650
|RECORD=41|OwnerIndex=3918|IndexInSheet=6|OwnerPartId=-1|Location.X=832|Location.Y=682|Color=8388608|FontID=1|IsHidden=T|Text=Bourns|Name=Manufacturer
|RECORD=41|OwnerIndex=3918|IndexInSheet=7|OwnerPartId=-1|Location.X=832|Location.Y=682|Color=8388608|FontID=1|IsHidden=T|Text=CR0402-FX-1002GLF|Name=Part Number
|RECORD=34|OwnerIndex=3918|IndexInSheet=-1|OwnerPartId=-1|Location.X=835|Location.Y=640|Orientation=1|Color=8388608|FontID=2|Text=R59|Name=Designator|ReadOnlyState=1
|RECORD=41|OwnerIndex=3918|IndexInSheet=-1|OwnerPartId=-1|Location.X=850|Location.Y=630|Orientation=1|Color=8388608|FontID=2|Text=10K_1%_0402|Name=Comment
|RECORD=44|OwnerIndex=3918
|RECORD=45|OwnerIndex=3933|IndexInSheet=-1|Description=Chip Resistor, 2-Leads, Body 1.00x0.50mm, IPC Medium Density|UseComponentLibrary=T|ModelName=RESC1005X40X25NL10T10|ModelType=PCBLIB|IsCurrent=T|DatalinksLocked=T|DatabaseDatalinksLocked=T
|RECORD=46|OwnerIndex=3934
|RECORD=48|OwnerIndex=3934
|RECORD=41|OwnerIndex=3936|IndexInSheet=-1|OwnerPartId=-1|Color=8388608|FontID=1|IsHidden=T|Text=2D|Name=Available Preview Images
|RECORD=45|OwnerIndex=3933|IndexInSheet=-1|Description=Chip Resistor, 2-Leads, Body 1.00x0.50mm, IPC High Density|UseComponentLibrary=T|ModelName=RESC1005X40X25LL10T10|ModelType=PCBLIB|DatalinksLocked=T|DatabaseDatalinksLocked=T
|RECORD=46|OwnerIndex=3938
|RECORD=48|OwnerIndex=3938
|RECORD=41|OwnerIndex=3940|IndexInSheet=-1|OwnerPartId=-1|Color=8388608|FontID=1|IsHidden=T|Text=2D|Name=Available Preview Images
|RECORD=45|OwnerIndex=3933|IndexInSheet=-1|Description=Chip Resistor, 2-Leads, Body 1.00x0.50mm, IPC Low Density|UseComponentLibrary=T|ModelName=RESC1005X40X25ML10T10|ModelType=PCBLIB|DatalinksLocked=T|DatabaseDatalinksLocked=T
|RECORD=46|OwnerIndex=3942
|RECORD=48|OwnerIndex=3942
|RECORD=41|OwnerIndex=3944|IndexInSheet=-1|OwnerPartId=-1|Color=8388608|FontID=1|IsHidden=T|Text=2D|Name=Available Preview Images
|RECORD=27|IndexInSheet=443|OwnerPartId=-1|LineWidth=1|Color=8388608|LocationCount=3|X1=835|Y1=640|X2=835|Y2=625|X3=860|Y3=625
|RECORD=27|IndexInSheet=444|OwnerPartId=-1|LineWidth=1|Color=8388608|LocationCount=2|X1=835|Y1=680|X2=835|Y2=690
|RECORD=29|IndexInSheet=-1|OwnerPartId=-1|Location.X=120|Location.Y=1010|Color=128
|RECORD=29|IndexInSheet=-1|OwnerPartId=-1|Location.X=170|Location.Y=910|Color=128
|RECORD=29|IndexInSheet=-1|OwnerPartId=-1|Location.X=200|Location.Y=755|Color=128
|RECORD=29|IndexInSheet=-1|OwnerPartId=-1|Location.X=240|Location.Y=755|Color=128
|RECORD=29|IndexInSheet=-1|OwnerPartId=-1|Location.X=310|Location.Y=830|Color=128
|RECORD=29|IndexInSheet=-1|OwnerPartId=-1|Location.X=340|Location.Y=300|Color=128
|RECORD=29|IndexInSheet=-1|OwnerPartId=-1|Location.X=340|Location.Y=375|Color=128
|RECORD=29|IndexInSheet=-1|OwnerPartId=-1|Location.X=390|Location.Y=300|Color=128
|RECORD=29|IndexInSheet=-1|OwnerPartId=-1|Location.X=390|Location.Y=375|Color=128
|RECORD=29|IndexInSheet=-1|OwnerPartId=-1|Location.X=405|Location.Y=915|Color=128
|RECORD=29|IndexInSheet=-1|OwnerPartId=-1|Location.X=425|Location.Y=915|Color=128
|RECORD=29|IndexInSheet=-1|OwnerPartId=-1|Location.X=435|Location.Y=525|Color=128
|RECORD=29|IndexInSheet=-1|OwnerPartId=-1|Location.X=440|Location.Y=155|Color=128
|RECORD=29|IndexInSheet=-1|OwnerPartId=-1|Location.X=480|Location.Y=685|Color=128
|RECORD=29|IndexInSheet=-1|OwnerPartId=-1|Location.X=530|Location.Y=505|Color=128
|RECORD=29|IndexInSheet=-1|OwnerPartId=-1|Location.X=552|Location.Y=915|Color=128
|RECORD=29|IndexInSheet=-1|OwnerPartId=-1|Location.X=555|Location.Y=440|Color=128
|RECORD=29|IndexInSheet=-1|OwnerPartId=-1|Location.X=555|Location.Y=525|Color=128
|RECORD=29|IndexInSheet=-1|OwnerPartId=-1|Location.X=560|Location.Y=115|Color=128
|RECORD=29|IndexInSheet=-1|OwnerPartId=-1|Location.X=560|Location.Y=125|Color=128
|RECORD=29|IndexInSheet=-1|OwnerPartId=-1|Location.X=565|Location.Y=555|Color=128
|RECORD=29|IndexInSheet=-1|OwnerPartId=-1|Location.X=575|Location.Y=705|Color=128
|RECORD=29|IndexInSheet=-1|OwnerPartId=-1|Location.X=580|Location.Y=165|Color=128
|RECORD=29|IndexInSheet=-1|OwnerPartId=-1|Location.X=580|Location.Y=175|Color=128
|RECORD=29|IndexInSheet=-1|OwnerPartId=-1|Location.X=590|Location.Y=205|Color=128
|RECORD=29|IndexInSheet=-1|OwnerPartId=-1|Location.X=590|Location.Y=215|Color=128
|RECORD=29|IndexInSheet=-1|OwnerPartId=-1|Location.X=600|Location.Y=837|Color=128
|RECORD=29|IndexInSheet=-1|OwnerPartId=-1|Location.X=602|Location.Y=917|Color=128
|RECORD=29|IndexInSheet=-1|OwnerPartId=-1|Location.X=675|Location.Y=880|Color=128
|RECORD=29|IndexInSheet=-1|OwnerPartId=-1|Location.X=675|Location.Y=960|Color=128
|RECORD=29|IndexInSheet=-1|OwnerPartId=-1|Location.X=725|Location.Y=710|Color=128
|RECORD=29|IndexInSheet=-1|OwnerPartId=-1|Location.X=725|Location.Y=880|Color=128
|RECORD=29|IndexInSheet=-1|OwnerPartId=-1|Location.X=725|Location.Y=960|Color=128
|RECORD=29|IndexInSheet=-1|OwnerPartId=-1|Location.X=800|Location.Y=345|Color=128
|RECORD=29|IndexInSheet=-1|OwnerPartId=-1|Location.X=800|Location.Y=355|Color=128
|RECORD=29|IndexInSheet=-1|OwnerPartId=-1|Location.X=800|Location.Y=365|Color=128
|RECORD=29|IndexInSheet=-1|OwnerPartId=-1|Location.X=800|Location.Y=375|Color=128
|RECORD=29|IndexInSheet=-1|OwnerPartId=-1|Location.X=800|Location.Y=385|Color=128
|RECORD=29|IndexInSheet=-1|OwnerPartId=-1|Location.X=800|Location.Y=395|Color=128
|RECORD=29|IndexInSheet=-1|OwnerPartId=-1|Location.X=800|Location.Y=405|Color=128
|RECORD=29|IndexInSheet=-1|OwnerPartId=-1|Location.X=800|Location.Y=415|Color=128
|RECORD=29|IndexInSheet=-1|OwnerPartId=-1|Location.X=800|Location.Y=425|Color=128
|RECORD=29|IndexInSheet=-1|OwnerPartId=-1|Location.X=800|Location.Y=435|Color=128
|RECORD=29|IndexInSheet=-1|OwnerPartId=-1|Location.X=800|Location.Y=445|Color=128
|RECORD=29|IndexInSheet=-1|OwnerPartId=-1|Location.X=800|Location.Y=455|Color=128
|RECORD=29|IndexInSheet=-1|OwnerPartId=-1|Location.X=800|Location.Y=465|Color=128
|RECORD=29|IndexInSheet=-1|OwnerPartId=-1|Location.X=800|Location.Y=475|Color=128
|RECORD=29|IndexInSheet=-1|OwnerPartId=-1|Location.X=805|Location.Y=545|Color=128
|RECORD=29|IndexInSheet=-1|OwnerPartId=-1|Location.X=805|Location.Y=555|Color=128
|RECORD=29|IndexInSheet=-1|OwnerPartId=-1|Location.X=815|Location.Y=175|Color=128
|RECORD=29|IndexInSheet=-1|OwnerPartId=-1|Location.X=815|Location.Y=185|Color=128
|RECORD=29|IndexInSheet=-1|OwnerPartId=-1|Location.X=820|Location.Y=105|Color=128
|RECORD=29|IndexInSheet=-1|OwnerPartId=-1|Location.X=820|Location.Y=880|Color=128
|RECORD=29|IndexInSheet=-1|OwnerPartId=-1|Location.X=825|Location.Y=225|Color=128
|RECORD=29|IndexInSheet=-1|OwnerPartId=-1|Location.X=835|Location.Y=690|Color=128
|RECORD=29|IndexInSheet=-1|OwnerPartId=-1|Location.X=860|Location.Y=625|Color=128
|RECORD=29|IndexInSheet=-1|OwnerPartId=-1|Location.X=860|Location.Y=710|Color=128
|RECORD=29|IndexInSheet=-1|OwnerPartId=-1|Location.X=875|Location.Y=740|Color=128
|RECORD=29|IndexInSheet=-1|OwnerPartId=-1|Location.X=940|Location.Y=840|Color=128
|RECORD=29|IndexInSheet=-1|OwnerPartId=-1|Location.X=940|Location.Y=850|Color=128
|RECORD=29|IndexInSheet=-1|OwnerPartId=-1|Location.X=960|Location.Y=305|Color=128
|RECORD=29|IndexInSheet=-1|OwnerPartId=-1|Location.X=960|Location.Y=385|Color=128
|RECORD=29|IndexInSheet=-1|OwnerPartId=-1|Location.X=960|Location.Y=405|Color=128
|RECORD=29|IndexInSheet=-1|OwnerPartId=-1|Location.X=960|Location.Y=890|Color=128
|RECORD=29|IndexInSheet=-1|OwnerPartId=-1|Location.X=960|Location.Y=900|Color=128
|RECORD=29|IndexInSheet=-1|OwnerPartId=-1|Location.X=970|Location.Y=930|Color=128
|RECORD=29|IndexInSheet=-1|OwnerPartId=-1|Location.X=970|Location.Y=940|Color=128
|RECORD=29|IndexInSheet=-1|OwnerPartId=-1|Location.X=1010|Location.Y=305|Color=128
|RECORD=29|IndexInSheet=-1|OwnerPartId=-1|Location.X=1010|Location.Y=385|Color=128
|RECORD=29|IndexInSheet=-1|OwnerPartId=-1|Location.X=1055|Location.Y=305|Color=128
|RECORD=29|IndexInSheet=-1|OwnerPartId=-1|Location.X=1055|Location.Y=385|Color=128
|RECORD=29|IndexInSheet=-1|OwnerPartId=-1|Location.X=1095|Location.Y=305|Color=128
|RECORD=29|IndexInSheet=-1|OwnerPartId=-1|Location.X=1095|Location.Y=385|Color=128
|RECORD=29|IndexInSheet=-1|OwnerPartId=-1|Location.X=1110|Location.Y=530|Color=128
|RECORD=29|IndexInSheet=-1|OwnerPartId=-1|Location.X=1110|Location.Y=540|Color=128
|RECORD=29|IndexInSheet=-1|OwnerPartId=-1|Location.X=1110|Location.Y=550|Color=128
|RECORD=29|IndexInSheet=-1|OwnerPartId=-1|Location.X=1110|Location.Y=560|Color=128
|RECORD=29|IndexInSheet=-1|OwnerPartId=-1|Location.X=1110|Location.Y=570|Color=128
|RECORD=29|IndexInSheet=-1|OwnerPartId=-1|Location.X=1110|Location.Y=580|Color=128
|RECORD=29|IndexInSheet=-1|OwnerPartId=-1|Location.X=1110|Location.Y=590|Color=128
|RECORD=29|IndexInSheet=-1|OwnerPartId=-1|Location.X=1110|Location.Y=600|Color=128
|RECORD=29|IndexInSheet=-1|OwnerPartId=-1|Location.X=1110|Location.Y=610|Color=128
|RECORD=29|IndexInSheet=-1|OwnerPartId=-1|Location.X=1110|Location.Y=620|Color=128
|RECORD=29|IndexInSheet=-1|OwnerPartId=-1|Location.X=1110|Location.Y=630|Color=128
|RECORD=29|IndexInSheet=-1|OwnerPartId=-1|Location.X=1110|Location.Y=640|Color=128
|RECORD=29|IndexInSheet=-1|OwnerPartId=-1|Location.X=1110|Location.Y=650|Color=128
|RECORD=29|IndexInSheet=-1|OwnerPartId=-1|Location.X=1110|Location.Y=660|Color=128
|RECORD=29|IndexInSheet=-1|OwnerPartId=-1|Location.X=1115|Location.Y=730|Color=128
|RECORD=29|IndexInSheet=-1|OwnerPartId=-1|Location.X=1115|Location.Y=740|Color=128
|RECORD=29|IndexInSheet=-1|OwnerPartId=-1|Location.X=1140|Location.Y=305|Color=128
|RECORD=29|IndexInSheet=-1|OwnerPartId=-1|Location.X=1140|Location.Y=385|Color=128
|RECORD=29|IndexInSheet=-1|OwnerPartId=-1|Location.X=1185|Location.Y=305|Color=128
|RECORD=29|IndexInSheet=-1|OwnerPartId=-1|Location.X=1185|Location.Y=385|Color=128
|RECORD=29|IndexInSheet=-1|OwnerPartId=-1|Location.X=1195|Location.Y=900|Color=128
|RECORD=29|IndexInSheet=-1|OwnerPartId=-1|Location.X=1195|Location.Y=910|Color=128
|RECORD=29|IndexInSheet=-1|OwnerPartId=-1|Location.X=1200|Location.Y=830|Color=128
|RECORD=29|IndexInSheet=-1|OwnerPartId=-1|Location.X=1205|Location.Y=950|Color=128
|RECORD=29|IndexInSheet=-1|OwnerPartId=-1|Location.X=1240|Location.Y=635|Color=128
|RECORD=29|IndexInSheet=-1|OwnerPartId=-1|Location.X=1245|Location.Y=780|Color=128
|RECORD=29|IndexInSheet=-1|OwnerPartId=-1|Location.X=1280|Location.Y=635|Color=128
|RECORD=29|IndexInSheet=-1|OwnerPartId=-1|Location.X=1285|Location.Y=780|Color=128
|RECORD=29|IndexInSheet=-1|OwnerPartId=-1|Location.X=1430|Location.Y=875|Color=128
|RECORD=29|IndexInSheet=-1|OwnerPartId=-1|Location.X=1430|Location.Y=955|Color=128
|RECORD=29|IndexInSheet=-1|OwnerPartId=-1|Location.X=1430|Location.Y=985|Color=128
|RECORD=29|IndexInSheet=-1|OwnerPartId=-1|Location.X=1475|Location.Y=875|Color=128
|RECORD=29|IndexInSheet=-1|OwnerPartId=-1|Location.X=1475|Location.Y=955|Color=128
|RECORD=29|IndexInSheet=-1|OwnerPartId=-1|Location.X=1515|Location.Y=875|Color=128
|RECORD=29|IndexInSheet=-1|OwnerPartId=-1|Location.X=1515|Location.Y=955|Color=128
|RECORD=29|IndexInSheet=-1|OwnerPartId=-1|Location.X=1520|Location.Y=565|Color=128
|RECORD=29|IndexInSheet=-1|OwnerPartId=-1|Location.X=1525|Location.Y=710|Color=128
|RECORD=29|IndexInSheet=-1|OwnerPartId=-1|Location.X=1560|Location.Y=875|Color=128
|RECORD=29|IndexInSheet=-1|OwnerPartId=-1|Location.X=1560|Location.Y=955|Color=128
|RECORD=29|IndexInSheet=-1|OwnerPartId=-1|Location.X=1605|Location.Y=875|Color=128
|RECORD=29|IndexInSheet=-1|OwnerPartId=-1|Location.X=1605|Location.Y=955|Color=128